G04 ================== begin FILE IDENTIFICATION RECORD ==================*
G04 Layout Name:  9048_F0T_Management_Board_D_brd_V04_1213_1625.brd*
G04 Film Name:    fab*
G04 File Format:  Gerber RS274X*
G04 File Origin:  Cadence Allegro 17.2-S081*
G04 Origin Date:  Tue Dec 13 16:31:11 2022*
G04 *
G04 Layer:  MANUFACTURING/NCLEGEND-1-12*
G04 Layer:  DRAWING FORMAT/TITLE_BLOCK_A*
G04 Layer:  MANUFACTURING/NCLEGEND-1-8*
G04 Layer:  BOARD GEOMETRY/DESIGN_OUTLINE*
G04 Layer:  BOARD GEOMETRY/CUTOUT*
G04 Layer:  MANUFACTURING/NCDRILL_LEGEND*
G04 Layer:  MANUFACTURING/NCDRILL_FIGURE*
G04 Layer:  MANUFACTURING/PHOTOPLOT_OUTLINE*
G04 Layer:  MANUFACTURING/DIMENSION*
G04 Layer:  MANUFACTURING/DETAILS*
G04 Layer:  DRAWING FORMAT/TITLE_BLOCK*
G04 Layer:  DRAWING FORMAT/TITLE_DATA_FAB*
G04 Layer:  BOARD GEOMETRY/OUTLINE*
G04 *
G04 Offset:    (0.00 0.00)*
G04 Mirror:    No*
G04 Mode:      Positive*
G04 Rotation:  0*
G04 FullContactRelief:  No*
G04 UndefLineWidth:     6.00*
G04 ================== end FILE IDENTIFICATION RECORD ====================*
%FSLAX25Y25*MOIN*%
%IR0*IPPOS*OFA0.00000B0.00000*MIA0B0*SFA1.00000B1.00000*%
%AMMACRO14*
1,1,.006,.035,.035*
20,1,.006,.035,.035,.035,-.035,0.0*
1,1,.006,.035,-.035*
20,1,.006,.035,-.035,-.035,-.035,0.0*
1,1,.006,-.035,-.035*
20,1,.006,-.035,-.035,-.035,.035,0.0*
1,1,.006,-.035,.035*
20,1,.006,-.035,.035,.035,.035,0.0*
1,1,.006,.035,.035*
1,1,.006,-.03185,-.02042*
20,1,.006,-.03185,-.02042,-.03185,.00408,0.0*
1,1,.006,-.03185,.00408*
1,1,.006,-.03185,.00041*
20,1,.006,-.03185,.00041,-.02981,.00245,0.0*
1,1,.006,-.02981,.00245*
20,1,.006,-.02981,.00245,-.02777,.00367,0.0*
1,1,.006,-.02777,.00367*
20,1,.006,-.02777,.00367,-.0245,.00408,0.0*
1,1,.006,-.0245,.00408*
20,1,.006,-.0245,.00408,-.02164,.00367,0.0*
1,1,.006,-.02164,.00367*
20,1,.006,-.02164,.00367,-.01878,.00163,0.0*
1,1,.006,-.01878,.00163*
20,1,.006,-.01878,.00163,-.01756,-.00123,0.0*
1,1,.006,-.01756,-.00123*
20,1,.006,-.01756,-.00123,-.01715,-.00408,0.0*
1,1,.006,-.01715,-.00408*
20,1,.006,-.01715,-.00408,-.01756,-.00694,0.0*
1,1,.006,-.01756,-.00694*
20,1,.006,-.01756,-.00694,-.01878,-.0098,0.0*
1,1,.006,-.01878,-.0098*
20,1,.006,-.01878,-.0098,-.02123,-.01143,0.0*
1,1,.006,-.02123,-.01143*
20,1,.006,-.02123,-.01143,-.0245,-.01225,0.0*
1,1,.006,-.0245,-.01225*
20,1,.006,-.0245,-.01225,-.02736,-.01184,0.0*
1,1,.006,-.02736,-.01184*
20,1,.006,-.02736,-.01184,-.03022,-.01062,0.0*
1,1,.006,-.03022,-.01062*
20,1,.006,-.03022,-.01062,-.03185,-.00898,0.0*
1,1,.006,-.03185,-.00898*
1,1,.006,-.00611,-.00123*
20,1,.006,-.00611,-.00123,.00695,-.00123,0.0*
1,1,.006,.00695,-.00123*
20,1,.006,.00695,-.00123,.00573,.00163,0.0*
1,1,.006,.00573,.00163*
20,1,.006,.00573,.00163,.00369,.00327,0.0*
1,1,.006,.00369,.00327*
20,1,.006,.00369,.00327,.00083,.00408,0.0*
1,1,.006,.00083,.00408*
20,1,.006,.00083,.00408,-.00203,.00367,0.0*
1,1,.006,-.00203,.00367*
20,1,.006,-.00203,.00367,-.00448,.00245,0.0*
1,1,.006,-.00448,.00245*
20,1,.006,-.00448,.00245,-.00611,-.00041,0.0*
1,1,.006,-.00611,-.00041*
20,1,.006,-.00611,-.00041,-.00693,-.00286,0.0*
1,1,.006,-.00693,-.00286*
20,1,.006,-.00693,-.00286,-.00693,-.00531,0.0*
1,1,.006,-.00693,-.00531*
20,1,.006,-.00693,-.00531,-.00611,-.00776,0.0*
1,1,.006,-.00611,-.00776*
20,1,.006,-.00611,-.00776,-.00407,-.01021,0.0*
1,1,.006,-.00407,-.01021*
20,1,.006,-.00407,-.01021,-.00162,-.01184,0.0*
1,1,.006,-.00162,-.01184*
20,1,.006,-.00162,-.01184,.00124,-.01225,0.0*
1,1,.006,.00124,-.01225*
20,1,.006,.00124,-.01225,.00409,-.01143,0.0*
1,1,.006,.00409,-.01143*
20,1,.006,.00409,-.01143,.00695,-.00898,0.0*
1,1,.006,.00695,-.00898*
1,1,.006,.01594,-.0196*
20,1,.006,.01594,-.0196,.0184,-.02042,0.0*
1,1,.006,.0184,-.02042*
20,1,.006,.0184,-.02042,.02166,-.0196,0.0*
1,1,.006,.02166,-.0196*
20,1,.006,.02166,-.0196,.0237,-.01797,0.0*
1,1,.006,.0237,-.01797*
20,1,.006,.0237,-.01797,.02534,-.01592,0.0*
1,1,.006,.02534,-.01592*
20,1,.006,.02534,-.01592,.02779,-.00939,0.0*
1,1,.006,.02779,-.00939*
20,1,.006,.02779,-.00939,.0331,.00408,0.0*
1,1,.006,.0331,.00408*
1,1,.006,.02003,.00408*
20,1,.006,.02003,.00408,.02779,-.00939,0.0*
1,1,.006,.02779,-.00939*
%
%ADD14MACRO14*%
%AMMACRO22*
1,1,.006,.035,0.0*
20,1,.006,.035,0.0,.034468,-.006078,0.0*
1,1,.006,.034468,-.006078*
20,1,.006,.034468,-.006078,.032889,-.011971,0.0*
1,1,.006,.032889,-.011971*
20,1,.006,.032889,-.011971,.030311,-.0175,0.0*
1,1,.006,.030311,-.0175*
20,1,.006,.030311,-.0175,.026812,-.022498,0.0*
1,1,.006,.026812,-.022498*
20,1,.006,.026812,-.022498,.022498,-.026812,0.0*
1,1,.006,.022498,-.026812*
20,1,.006,.022498,-.026812,.0175,-.030311,0.0*
1,1,.006,.0175,-.030311*
20,1,.006,.0175,-.030311,.011971,-.032889,0.0*
1,1,.006,.011971,-.032889*
20,1,.006,.011971,-.032889,.006078,-.034468,0.0*
1,1,.006,.006078,-.034468*
20,1,.006,.006078,-.034468,0.0,-.035,0.0*
1,1,.006,0.0,-.035*
20,1,.006,0.0,-.035,-.006078,-.034468,0.0*
1,1,.006,-.006078,-.034468*
20,1,.006,-.006078,-.034468,-.011971,-.032889,0.0*
1,1,.006,-.011971,-.032889*
20,1,.006,-.011971,-.032889,-.0175,-.030311,0.0*
1,1,.006,-.0175,-.030311*
20,1,.006,-.0175,-.030311,-.022498,-.026812,0.0*
1,1,.006,-.022498,-.026812*
20,1,.006,-.022498,-.026812,-.026812,-.022498,0.0*
1,1,.006,-.026812,-.022498*
20,1,.006,-.026812,-.022498,-.030311,-.0175,0.0*
1,1,.006,-.030311,-.0175*
20,1,.006,-.030311,-.0175,-.032889,-.011971,0.0*
1,1,.006,-.032889,-.011971*
20,1,.006,-.032889,-.011971,-.034468,-.006078,0.0*
1,1,.006,-.034468,-.006078*
20,1,.006,-.034468,-.006078,-.035,0.0,0.0*
1,1,.006,-.035,0.0*
20,1,.006,-.035,0.0,-.034468,.006078,0.0*
1,1,.006,-.034468,.006078*
20,1,.006,-.034468,.006078,-.032889,.011971,0.0*
1,1,.006,-.032889,.011971*
20,1,.006,-.032889,.011971,-.030311,.0175,0.0*
1,1,.006,-.030311,.0175*
20,1,.006,-.030311,.0175,-.026812,.022498,0.0*
1,1,.006,-.026812,.022498*
20,1,.006,-.026812,.022498,-.022498,.026812,0.0*
1,1,.006,-.022498,.026812*
20,1,.006,-.022498,.026812,-.0175,.030311,0.0*
1,1,.006,-.0175,.030311*
20,1,.006,-.0175,.030311,-.011971,.032889,0.0*
1,1,.006,-.011971,.032889*
20,1,.006,-.011971,.032889,-.006078,.034468,0.0*
1,1,.006,-.006078,.034468*
20,1,.006,-.006078,.034468,0.0,.035,0.0*
1,1,.006,0.0,.035*
20,1,.006,0.0,.035,.006078,.034468,0.0*
1,1,.006,.006078,.034468*
20,1,.006,.006078,.034468,.011971,.032889,0.0*
1,1,.006,.011971,.032889*
20,1,.006,.011971,.032889,.0175,.030311,0.0*
1,1,.006,.0175,.030311*
20,1,.006,.0175,.030311,.022498,.026812,0.0*
1,1,.006,.022498,.026812*
20,1,.006,.022498,.026812,.026812,.022498,0.0*
1,1,.006,.026812,.022498*
20,1,.006,.026812,.022498,.030311,.0175,0.0*
1,1,.006,.030311,.0175*
20,1,.006,.030311,.0175,.032889,.011971,0.0*
1,1,.006,.032889,.011971*
20,1,.006,.032889,.011971,.034468,.006078,0.0*
1,1,.006,.034468,.006078*
20,1,.006,.034468,.006078,.035,0.0,0.0*
1,1,.006,.035,0.0*
1,1,.006,-.01804,.00069*
20,1,.006,-.01804,.00069,-.01666,.00173,0.0*
1,1,.006,-.01666,.00173*
20,1,.006,-.01666,.00173,-.01562,.00347,0.0*
1,1,.006,-.01562,.00347*
20,1,.006,-.01562,.00347,-.01492,.0059,0.0*
1,1,.006,-.01492,.0059*
20,1,.006,-.01492,.0059,-.01562,.00798,0.0*
1,1,.006,-.01562,.00798*
20,1,.006,-.01562,.00798,-.017,.00937,0.0*
1,1,.006,-.017,.00937*
20,1,.006,-.017,.00937,-.01943,.01041,0.0*
1,1,.006,-.01943,.01041*
20,1,.006,-.01943,.01041,-.0288,.01041,0.0*
1,1,.006,-.0288,.01041*
20,1,.006,-.0288,.01041,-.0288,-.01041,0.0*
1,1,.006,-.0288,-.01041*
20,1,.006,-.0288,-.01041,-.01735,-.01041,0.0*
1,1,.006,-.01735,-.01041*
20,1,.006,-.01735,-.01041,-.01492,-.00902,0.0*
1,1,.006,-.01492,-.00902*
20,1,.006,-.01492,-.00902,-.01353,-.00694,0.0*
1,1,.006,-.01353,-.00694*
20,1,.006,-.01353,-.00694,-.01284,-.00451,0.0*
1,1,.006,-.01284,-.00451*
20,1,.006,-.01284,-.00451,-.01353,-.00208,0.0*
1,1,.006,-.01353,-.00208*
20,1,.006,-.01353,-.00208,-.01562,0.0,0.0*
1,1,.006,-.01562,0.0*
20,1,.006,-.01562,0.0,-.01804,.00069,0.0*
1,1,.006,-.01804,.00069*
20,1,.006,-.01804,.00069,-.0288,.00069,0.0*
1,1,.006,-.0288,.00069*
1,1,.006,-.0104,-.01735*
20,1,.006,-.0104,-.01735,.01042,-.01735,0.0*
1,1,.006,.01042,-.01735*
1,1,.006,.01216,.01041*
20,1,.006,.01216,.01041,.02084,-.01041,0.0*
1,1,.006,.02084,-.01041*
20,1,.006,.02084,-.01041,.02952,.01041,0.0*
1,1,.006,.02952,.01041*
%
%ADD22MACRO22*%
%AMMACRO17*
1,1,.006,.035,0.0*
20,1,.006,.035,0.0,.034468,-.006078,0.0*
1,1,.006,.034468,-.006078*
20,1,.006,.034468,-.006078,.032889,-.011971,0.0*
1,1,.006,.032889,-.011971*
20,1,.006,.032889,-.011971,.030311,-.0175,0.0*
1,1,.006,.030311,-.0175*
20,1,.006,.030311,-.0175,.026812,-.022498,0.0*
1,1,.006,.026812,-.022498*
20,1,.006,.026812,-.022498,.022498,-.026812,0.0*
1,1,.006,.022498,-.026812*
20,1,.006,.022498,-.026812,.0175,-.030311,0.0*
1,1,.006,.0175,-.030311*
20,1,.006,.0175,-.030311,.011971,-.032889,0.0*
1,1,.006,.011971,-.032889*
20,1,.006,.011971,-.032889,.006078,-.034468,0.0*
1,1,.006,.006078,-.034468*
20,1,.006,.006078,-.034468,0.0,-.035,0.0*
1,1,.006,0.0,-.035*
20,1,.006,0.0,-.035,-.006078,-.034468,0.0*
1,1,.006,-.006078,-.034468*
20,1,.006,-.006078,-.034468,-.011971,-.032889,0.0*
1,1,.006,-.011971,-.032889*
20,1,.006,-.011971,-.032889,-.0175,-.030311,0.0*
1,1,.006,-.0175,-.030311*
20,1,.006,-.0175,-.030311,-.022498,-.026812,0.0*
1,1,.006,-.022498,-.026812*
20,1,.006,-.022498,-.026812,-.026812,-.022498,0.0*
1,1,.006,-.026812,-.022498*
20,1,.006,-.026812,-.022498,-.030311,-.0175,0.0*
1,1,.006,-.030311,-.0175*
20,1,.006,-.030311,-.0175,-.032889,-.011971,0.0*
1,1,.006,-.032889,-.011971*
20,1,.006,-.032889,-.011971,-.034468,-.006078,0.0*
1,1,.006,-.034468,-.006078*
20,1,.006,-.034468,-.006078,-.035,0.0,0.0*
1,1,.006,-.035,0.0*
20,1,.006,-.035,0.0,-.034468,.006078,0.0*
1,1,.006,-.034468,.006078*
20,1,.006,-.034468,.006078,-.032889,.011971,0.0*
1,1,.006,-.032889,.011971*
20,1,.006,-.032889,.011971,-.030311,.0175,0.0*
1,1,.006,-.030311,.0175*
20,1,.006,-.030311,.0175,-.026812,.022498,0.0*
1,1,.006,-.026812,.022498*
20,1,.006,-.026812,.022498,-.022498,.026812,0.0*
1,1,.006,-.022498,.026812*
20,1,.006,-.022498,.026812,-.0175,.030311,0.0*
1,1,.006,-.0175,.030311*
20,1,.006,-.0175,.030311,-.011971,.032889,0.0*
1,1,.006,-.011971,.032889*
20,1,.006,-.011971,.032889,-.006078,.034468,0.0*
1,1,.006,-.006078,.034468*
20,1,.006,-.006078,.034468,0.0,.035,0.0*
1,1,.006,0.0,.035*
20,1,.006,0.0,.035,.006078,.034468,0.0*
1,1,.006,.006078,.034468*
20,1,.006,.006078,.034468,.011971,.032889,0.0*
1,1,.006,.011971,.032889*
20,1,.006,.011971,.032889,.0175,.030311,0.0*
1,1,.006,.0175,.030311*
20,1,.006,.0175,.030311,.022498,.026812,0.0*
1,1,.006,.022498,.026812*
20,1,.006,.022498,.026812,.026812,.022498,0.0*
1,1,.006,.026812,.022498*
20,1,.006,.026812,.022498,.030311,.0175,0.0*
1,1,.006,.030311,.0175*
20,1,.006,.030311,.0175,.032889,.011971,0.0*
1,1,.006,.032889,.011971*
20,1,.006,.032889,.011971,.034468,.006078,0.0*
1,1,.006,.034468,.006078*
20,1,.006,.034468,.006078,.035,0.0,0.0*
1,1,.006,.035,0.0*
1,1,.006,-.02082,.01041*
20,1,.006,-.02082,.01041,-.02082,-.01041,0.0*
1,1,.006,-.02082,-.01041*
1,1,.006,-.0288,.01041*
20,1,.006,-.0288,.01041,-.01284,.01041,0.0*
1,1,.006,-.01284,.01041*
1,1,.006,-.00693,-.01041*
20,1,.006,-.00693,-.01041,-.00693,.01041,0.0*
1,1,.006,-.00693,.01041*
20,1,.006,-.00693,.01041,.0014,.01041,0.0*
1,1,.006,.0014,.01041*
20,1,.006,.0014,.01041,.00417,.00937,0.0*
1,1,.006,.00417,.00937*
20,1,.006,.00417,.00937,.00626,.00694,0.0*
1,1,.006,.00626,.00694*
20,1,.006,.00626,.00694,.00695,.00416,0.0*
1,1,.006,.00695,.00416*
20,1,.006,.00695,.00416,.00626,.00139,0.0*
1,1,.006,.00626,.00139*
20,1,.006,.00626,.00139,.00452,-.00069,0.0*
1,1,.006,.00452,-.00069*
20,1,.006,.00452,-.00069,.0014,-.00174,0.0*
1,1,.006,.0014,-.00174*
20,1,.006,.0014,-.00174,-.00693,-.00174,0.0*
1,1,.006,-.00693,-.00174*
1,1,.006,.01216,.01041*
20,1,.006,.01216,.01041,.02084,-.01041,0.0*
1,1,.006,.02084,-.01041*
20,1,.006,.02084,-.01041,.02952,.01041,0.0*
1,1,.006,.02952,.01041*
%
%ADD17MACRO17*%
%AMMACRO20*
1,1,.006,.035,.035*
20,1,.006,.035,.035,.035,-.035,0.0*
1,1,.006,.035,-.035*
20,1,.006,.035,-.035,-.035,-.035,0.0*
1,1,.006,-.035,-.035*
20,1,.006,-.035,-.035,-.035,.035,0.0*
1,1,.006,-.035,.035*
20,1,.006,-.035,.035,.035,.035,0.0*
1,1,.006,.035,.035*
1,1,.006,-.0245,.01225*
20,1,.006,-.0245,.01225,-.02777,.01143,0.0*
1,1,.006,-.02777,.01143*
20,1,.006,-.02777,.01143,-.03022,.00939,0.0*
1,1,.006,-.03022,.00939*
20,1,.006,-.03022,.00939,-.03185,.00694,0.0*
1,1,.006,-.03185,.00694*
20,1,.006,-.03185,.00694,-.03308,.00367,0.0*
1,1,.006,-.03308,.00367*
20,1,.006,-.03308,.00367,-.03348,0.0,0.0*
1,1,.006,-.03348,0.0*
20,1,.006,-.03348,0.0,-.03308,-.00368,0.0*
1,1,.006,-.03308,-.00368*
20,1,.006,-.03308,-.00368,-.03185,-.00694,0.0*
1,1,.006,-.03185,-.00694*
20,1,.006,-.03185,-.00694,-.03022,-.00939,0.0*
1,1,.006,-.03022,-.00939*
20,1,.006,-.03022,-.00939,-.02777,-.01143,0.0*
1,1,.006,-.02777,-.01143*
20,1,.006,-.02777,-.01143,-.0245,-.01225,0.0*
1,1,.006,-.0245,-.01225*
20,1,.006,-.0245,-.01225,-.02123,-.01143,0.0*
1,1,.006,-.02123,-.01143*
20,1,.006,-.02123,-.01143,-.01878,-.00939,0.0*
1,1,.006,-.01878,-.00939*
20,1,.006,-.01878,-.00939,-.01715,-.00694,0.0*
1,1,.006,-.01715,-.00694*
20,1,.006,-.01715,-.00694,-.01592,-.00368,0.0*
1,1,.006,-.01592,-.00368*
20,1,.006,-.01592,-.00368,-.01552,0.0,0.0*
1,1,.006,-.01552,0.0*
20,1,.006,-.01552,0.0,-.01592,.00367,0.0*
1,1,.006,-.01592,.00367*
20,1,.006,-.01592,.00367,-.01715,.00694,0.0*
1,1,.006,-.01715,.00694*
20,1,.006,-.01715,.00694,-.01878,.00939,0.0*
1,1,.006,-.01878,.00939*
20,1,.006,-.01878,.00939,-.02123,.01143,0.0*
1,1,.006,-.02123,.01143*
20,1,.006,-.02123,.01143,-.0245,.01225,0.0*
1,1,.006,-.0245,.01225*
1,1,.006,-.00897,-.00735*
20,1,.006,-.00897,-.00735,-.00652,-.01021,0.0*
1,1,.006,-.00652,-.01021*
20,1,.006,-.00652,-.01021,-.00326,-.01184,0.0*
1,1,.006,-.00326,-.01184*
20,1,.006,-.00326,-.01184,.00042,-.01225,0.0*
1,1,.006,.00042,-.01225*
20,1,.006,.00042,-.01225,.00369,-.01184,0.0*
1,1,.006,.00369,-.01184*
20,1,.006,.00369,-.01184,.00695,-.0098,0.0*
1,1,.006,.00695,-.0098*
20,1,.006,.00695,-.0098,.00899,-.00735,0.0*
1,1,.006,.00899,-.00735*
20,1,.006,.00899,-.00735,.0094,-.0049,0.0*
1,1,.006,.0094,-.0049*
20,1,.006,.0094,-.0049,.00859,-.00204,0.0*
1,1,.006,.00859,-.00204*
20,1,.006,.00859,-.00204,.00573,0.0,0.0*
1,1,.006,.00573,0.0*
20,1,.006,.00573,0.0,.00287,.00082,0.0*
1,1,.006,.00287,.00082*
20,1,.006,.00287,.00082,-.00081,.00082,0.0*
1,1,.006,-.00081,.00082*
1,1,.006,.00287,.00082*
20,1,.006,.00287,.00082,.00532,.00204,0.0*
1,1,.006,.00532,.00204*
20,1,.006,.00532,.00204,.00736,.00408,0.0*
1,1,.006,.00736,.00408*
20,1,.006,.00736,.00408,.00818,.00653,0.0*
1,1,.006,.00818,.00653*
20,1,.006,.00818,.00653,.00736,.00898,0.0*
1,1,.006,.00736,.00898*
20,1,.006,.00736,.00898,.00532,.01102,0.0*
1,1,.006,.00532,.01102*
20,1,.006,.00532,.01102,.00164,.01225,0.0*
1,1,.006,.00164,.01225*
20,1,.006,.00164,.01225,-.00203,.01184,0.0*
1,1,.006,-.00203,.01184*
20,1,.006,-.00203,.01184,-.00571,.01021,0.0*
1,1,.006,-.00571,.01021*
1,1,.006,.01676,.00817*
20,1,.006,.01676,.00817,.01921,.01062,0.0*
1,1,.006,.01921,.01062*
20,1,.006,.01921,.01062,.02207,.01184,0.0*
1,1,.006,.02207,.01184*
20,1,.006,.02207,.01184,.02534,.01225,0.0*
1,1,.006,.02534,.01225*
20,1,.006,.02534,.01225,.02942,.01143,0.0*
1,1,.006,.02942,.01143*
20,1,.006,.02942,.01143,.03228,.00939,0.0*
1,1,.006,.03228,.00939*
20,1,.006,.03228,.00939,.0331,.00694,0.0*
1,1,.006,.0331,.00694*
20,1,.006,.0331,.00694,.03269,.00449,0.0*
1,1,.006,.03269,.00449*
20,1,.006,.03269,.00449,.03105,.00245,0.0*
1,1,.006,.03105,.00245*
20,1,.006,.03105,.00245,.02289,-.00163,0.0*
1,1,.006,.02289,-.00163*
20,1,.006,.02289,-.00163,.01921,-.00449,0.0*
1,1,.006,.01921,-.00449*
20,1,.006,.01921,-.00449,.01676,-.00858,0.0*
1,1,.006,.01676,-.00858*
20,1,.006,.01676,-.00858,.01594,-.01225,0.0*
1,1,.006,.01594,-.01225*
20,1,.006,.01594,-.01225,.0331,-.01225,0.0*
1,1,.006,.0331,-.01225*
%
%ADD20MACRO20*%
%AMMACRO12*
1,1,.006,.05049,0.0*
20,1,.006,.05049,0.0,-.05049,0.0,0.0*
1,1,.006,-.05049,0.0*
1,1,.006,0.0,.05049*
20,1,.006,0.0,.05049,0.0,-.05049,0.0*
1,1,.006,0.0,-.05049*
%
%ADD12MACRO12*%
%AMMACRO26*
1,1,.006,.035,.035*
20,1,.006,.035,.035,.035,-.035,0.0*
1,1,.006,.035,-.035*
20,1,.006,.035,-.035,-.035,-.035,0.0*
1,1,.006,-.035,-.035*
20,1,.006,-.035,-.035,-.035,.035,0.0*
1,1,.006,-.035,.035*
20,1,.006,-.035,.035,.035,.035,0.0*
1,1,.006,.035,.035*
1,1,.006,-.0245,.01225*
20,1,.006,-.0245,.01225,-.02777,.01143,0.0*
1,1,.006,-.02777,.01143*
20,1,.006,-.02777,.01143,-.03022,.00939,0.0*
1,1,.006,-.03022,.00939*
20,1,.006,-.03022,.00939,-.03185,.00694,0.0*
1,1,.006,-.03185,.00694*
20,1,.006,-.03185,.00694,-.03308,.00367,0.0*
1,1,.006,-.03308,.00367*
20,1,.006,-.03308,.00367,-.03348,0.0,0.0*
1,1,.006,-.03348,0.0*
20,1,.006,-.03348,0.0,-.03308,-.00368,0.0*
1,1,.006,-.03308,-.00368*
20,1,.006,-.03308,-.00368,-.03185,-.00694,0.0*
1,1,.006,-.03185,-.00694*
20,1,.006,-.03185,-.00694,-.03022,-.00939,0.0*
1,1,.006,-.03022,-.00939*
20,1,.006,-.03022,-.00939,-.02777,-.01143,0.0*
1,1,.006,-.02777,-.01143*
20,1,.006,-.02777,-.01143,-.0245,-.01225,0.0*
1,1,.006,-.0245,-.01225*
20,1,.006,-.0245,-.01225,-.02123,-.01143,0.0*
1,1,.006,-.02123,-.01143*
20,1,.006,-.02123,-.01143,-.01878,-.00939,0.0*
1,1,.006,-.01878,-.00939*
20,1,.006,-.01878,-.00939,-.01715,-.00694,0.0*
1,1,.006,-.01715,-.00694*
20,1,.006,-.01715,-.00694,-.01592,-.00368,0.0*
1,1,.006,-.01592,-.00368*
20,1,.006,-.01592,-.00368,-.01552,0.0,0.0*
1,1,.006,-.01552,0.0*
20,1,.006,-.01552,0.0,-.01592,.00367,0.0*
1,1,.006,-.01592,.00367*
20,1,.006,-.01592,.00367,-.01715,.00694,0.0*
1,1,.006,-.01715,.00694*
20,1,.006,-.01715,.00694,-.01878,.00939,0.0*
1,1,.006,-.01878,.00939*
20,1,.006,-.01878,.00939,-.02123,.01143,0.0*
1,1,.006,-.02123,.01143*
20,1,.006,-.02123,.01143,-.0245,.01225,0.0*
1,1,.006,-.0245,.01225*
1,1,.006,-.00775,.00817*
20,1,.006,-.00775,.00817,-.0053,.01062,0.0*
1,1,.006,-.0053,.01062*
20,1,.006,-.0053,.01062,-.00244,.01184,0.0*
1,1,.006,-.00244,.01184*
20,1,.006,-.00244,.01184,.00083,.01225,0.0*
1,1,.006,.00083,.01225*
20,1,.006,.00083,.01225,.00491,.01143,0.0*
1,1,.006,.00491,.01143*
20,1,.006,.00491,.01143,.00777,.00939,0.0*
1,1,.006,.00777,.00939*
20,1,.006,.00777,.00939,.00859,.00694,0.0*
1,1,.006,.00859,.00694*
20,1,.006,.00859,.00694,.00818,.00449,0.0*
1,1,.006,.00818,.00449*
20,1,.006,.00818,.00449,.00654,.00245,0.0*
1,1,.006,.00654,.00245*
20,1,.006,.00654,.00245,-.00162,-.00163,0.0*
1,1,.006,-.00162,-.00163*
20,1,.006,-.00162,-.00163,-.0053,-.00449,0.0*
1,1,.006,-.0053,-.00449*
20,1,.006,-.0053,-.00449,-.00775,-.00858,0.0*
1,1,.006,-.00775,-.00858*
20,1,.006,-.00775,-.00858,-.00857,-.01225,0.0*
1,1,.006,-.00857,-.01225*
20,1,.006,-.00857,-.01225,.00859,-.01225,0.0*
1,1,.006,.00859,-.01225*
1,1,.006,.02452,-.01225*
20,1,.006,.02452,-.01225,.02738,-.01184,0.0*
1,1,.006,.02738,-.01184*
20,1,.006,.02738,-.01184,.03064,-.01062,0.0*
1,1,.006,.03064,-.01062*
20,1,.006,.03064,-.01062,.03269,-.00858,0.0*
1,1,.006,.03269,-.00858*
20,1,.006,.03269,-.00858,.0335,-.00572,0.0*
1,1,.006,.0335,-.00572*
20,1,.006,.0335,-.00572,.03269,-.00286,0.0*
1,1,.006,.03269,-.00286*
20,1,.006,.03269,-.00286,.03024,-.00041,0.0*
1,1,.006,.03024,-.00041*
20,1,.006,.03024,-.00041,.02656,.00082,0.0*
1,1,.006,.02656,.00082*
20,1,.006,.02656,.00082,.02248,.00082,0.0*
1,1,.006,.02248,.00082*
20,1,.006,.02248,.00082,.02003,.00163,0.0*
1,1,.006,.02003,.00163*
20,1,.006,.02003,.00163,.01799,.00367,0.0*
1,1,.006,.01799,.00367*
20,1,.006,.01799,.00367,.01717,.00653,0.0*
1,1,.006,.01717,.00653*
20,1,.006,.01717,.00653,.0184,.00939,0.0*
1,1,.006,.0184,.00939*
20,1,.006,.0184,.00939,.02125,.01143,0.0*
1,1,.006,.02125,.01143*
20,1,.006,.02125,.01143,.02452,.01225,0.0*
1,1,.006,.02452,.01225*
20,1,.006,.02452,.01225,.02779,.01143,0.0*
1,1,.006,.02779,.01143*
20,1,.006,.02779,.01143,.03064,.00939,0.0*
1,1,.006,.03064,.00939*
20,1,.006,.03064,.00939,.03187,.00653,0.0*
1,1,.006,.03187,.00653*
20,1,.006,.03187,.00653,.03105,.00367,0.0*
1,1,.006,.03105,.00367*
20,1,.006,.03105,.00367,.02901,.00163,0.0*
1,1,.006,.02901,.00163*
20,1,.006,.02901,.00163,.02656,.00082,0.0*
1,1,.006,.02656,.00082*
20,1,.006,.02656,.00082,.02248,.00082,0.0*
1,1,.006,.02248,.00082*
20,1,.006,.02248,.00082,.0188,-.00041,0.0*
1,1,.006,.0188,-.00041*
20,1,.006,.0188,-.00041,.01635,-.00286,0.0*
1,1,.006,.01635,-.00286*
20,1,.006,.01635,-.00286,.01554,-.00572,0.0*
1,1,.006,.01554,-.00572*
20,1,.006,.01554,-.00572,.01635,-.00858,0.0*
1,1,.006,.01635,-.00858*
20,1,.006,.01635,-.00858,.0184,-.01062,0.0*
1,1,.006,.0184,-.01062*
20,1,.006,.0184,-.01062,.02166,-.01184,0.0*
1,1,.006,.02166,-.01184*
20,1,.006,.02166,-.01184,.02452,-.01225,0.0*
1,1,.006,.02452,-.01225*
%
%ADD26MACRO26*%
%AMMACRO31*
1,1,.006,.035,0.0*
20,1,.006,.035,0.0,.034468,-.006078,0.0*
1,1,.006,.034468,-.006078*
20,1,.006,.034468,-.006078,.032889,-.011971,0.0*
1,1,.006,.032889,-.011971*
20,1,.006,.032889,-.011971,.030311,-.0175,0.0*
1,1,.006,.030311,-.0175*
20,1,.006,.030311,-.0175,.026812,-.022498,0.0*
1,1,.006,.026812,-.022498*
20,1,.006,.026812,-.022498,.022498,-.026812,0.0*
1,1,.006,.022498,-.026812*
20,1,.006,.022498,-.026812,.0175,-.030311,0.0*
1,1,.006,.0175,-.030311*
20,1,.006,.0175,-.030311,.011971,-.032889,0.0*
1,1,.006,.011971,-.032889*
20,1,.006,.011971,-.032889,.006078,-.034468,0.0*
1,1,.006,.006078,-.034468*
20,1,.006,.006078,-.034468,0.0,-.035,0.0*
1,1,.006,0.0,-.035*
20,1,.006,0.0,-.035,-.006078,-.034468,0.0*
1,1,.006,-.006078,-.034468*
20,1,.006,-.006078,-.034468,-.011971,-.032889,0.0*
1,1,.006,-.011971,-.032889*
20,1,.006,-.011971,-.032889,-.0175,-.030311,0.0*
1,1,.006,-.0175,-.030311*
20,1,.006,-.0175,-.030311,-.022498,-.026812,0.0*
1,1,.006,-.022498,-.026812*
20,1,.006,-.022498,-.026812,-.026812,-.022498,0.0*
1,1,.006,-.026812,-.022498*
20,1,.006,-.026812,-.022498,-.030311,-.0175,0.0*
1,1,.006,-.030311,-.0175*
20,1,.006,-.030311,-.0175,-.032889,-.011971,0.0*
1,1,.006,-.032889,-.011971*
20,1,.006,-.032889,-.011971,-.034468,-.006078,0.0*
1,1,.006,-.034468,-.006078*
20,1,.006,-.034468,-.006078,-.035,0.0,0.0*
1,1,.006,-.035,0.0*
20,1,.006,-.035,0.0,-.034468,.006078,0.0*
1,1,.006,-.034468,.006078*
20,1,.006,-.034468,.006078,-.032889,.011971,0.0*
1,1,.006,-.032889,.011971*
20,1,.006,-.032889,.011971,-.030311,.0175,0.0*
1,1,.006,-.030311,.0175*
20,1,.006,-.030311,.0175,-.026812,.022498,0.0*
1,1,.006,-.026812,.022498*
20,1,.006,-.026812,.022498,-.022498,.026812,0.0*
1,1,.006,-.022498,.026812*
20,1,.006,-.022498,.026812,-.0175,.030311,0.0*
1,1,.006,-.0175,.030311*
20,1,.006,-.0175,.030311,-.011971,.032889,0.0*
1,1,.006,-.011971,.032889*
20,1,.006,-.011971,.032889,-.006078,.034468,0.0*
1,1,.006,-.006078,.034468*
20,1,.006,-.006078,.034468,0.0,.035,0.0*
1,1,.006,0.0,.035*
20,1,.006,0.0,.035,.006078,.034468,0.0*
1,1,.006,.006078,.034468*
20,1,.006,.006078,.034468,.011971,.032889,0.0*
1,1,.006,.011971,.032889*
20,1,.006,.011971,.032889,.0175,.030311,0.0*
1,1,.006,.0175,.030311*
20,1,.006,.0175,.030311,.022498,.026812,0.0*
1,1,.006,.022498,.026812*
20,1,.006,.022498,.026812,.026812,.022498,0.0*
1,1,.006,.026812,.022498*
20,1,.006,.026812,.022498,.030311,.0175,0.0*
1,1,.006,.030311,.0175*
20,1,.006,.030311,.0175,.032889,.011971,0.0*
1,1,.006,.032889,.011971*
20,1,.006,.032889,.011971,.034468,.006078,0.0*
1,1,.006,.034468,.006078*
20,1,.006,.034468,.006078,.035,0.0,0.0*
1,1,.006,.035,0.0*
1,1,.006,-.01488,.01488*
20,1,.006,-.01488,.01488,-.01488,-.01487,0.0*
1,1,.006,-.01488,-.01487*
1,1,.006,-.02628,.01488*
20,1,.006,-.02628,.01488,-.00347,.01488,0.0*
1,1,.006,-.00347,.01488*
1,1,.006,.00497,-.01487*
20,1,.006,.00497,-.01487,.00497,.01488,0.0*
1,1,.006,.00497,.01488*
20,1,.006,.00497,.01488,.01687,.01488,0.0*
1,1,.006,.01687,.01488*
20,1,.006,.01687,.01488,.02084,.01339,0.0*
1,1,.006,.02084,.01339*
20,1,.006,.02084,.01339,.02381,.00992,0.0*
1,1,.006,.02381,.00992*
20,1,.006,.02381,.00992,.0248,.00596,0.0*
1,1,.006,.0248,.00596*
20,1,.006,.0248,.00596,.02381,.00199,0.0*
1,1,.006,.02381,.00199*
20,1,.006,.02381,.00199,.02133,-.00099,0.0*
1,1,.006,.02133,-.00099*
20,1,.006,.02133,-.00099,.01687,-.00247,0.0*
1,1,.006,.01687,-.00247*
20,1,.006,.01687,-.00247,.00497,-.00247,0.0*
1,1,.006,.00497,-.00247*
%
%ADD31MACRO31*%
%AMMACRO25*
1,1,.006,.0455,0.0*
20,1,.006,.0455,0.0,0.0,-.0455,0.0*
1,1,.006,0.0,-.0455*
20,1,.006,0.0,-.0455,-.0455,0.0,0.0*
1,1,.006,-.0455,0.0*
20,1,.006,-.0455,0.0,0.0,.0455,0.0*
1,1,.006,0.0,.0455*
20,1,.006,0.0,.0455,.0455,0.0,0.0*
1,1,.006,.0455,0.0*
1,1,.006,-.03185,.01593*
20,1,.006,-.03185,.01593,-.03609,.01487,0.0*
1,1,.006,-.03609,.01487*
20,1,.006,-.03609,.01487,-.03928,.01221,0.0*
1,1,.006,-.03928,.01221*
20,1,.006,-.03928,.01221,-.0414,.00903,0.0*
1,1,.006,-.0414,.00903*
20,1,.006,-.0414,.00903,-.04299,.00478,0.0*
1,1,.006,-.04299,.00478*
20,1,.006,-.04299,.00478,-.04352,0.0,0.0*
1,1,.006,-.04352,0.0*
20,1,.006,-.04352,0.0,-.04299,-.00477,0.0*
1,1,.006,-.04299,-.00477*
20,1,.006,-.04299,-.00477,-.0414,-.00902,0.0*
1,1,.006,-.0414,-.00902*
20,1,.006,-.0414,-.00902,-.03928,-.0122,0.0*
1,1,.006,-.03928,-.0122*
20,1,.006,-.03928,-.0122,-.03609,-.01486,0.0*
1,1,.006,-.03609,-.01486*
20,1,.006,-.03609,-.01486,-.03185,-.01592,0.0*
1,1,.006,-.03185,-.01592*
20,1,.006,-.03185,-.01592,-.0276,-.01486,0.0*
1,1,.006,-.0276,-.01486*
20,1,.006,-.0276,-.01486,-.02441,-.0122,0.0*
1,1,.006,-.02441,-.0122*
20,1,.006,-.02441,-.0122,-.02229,-.00902,0.0*
1,1,.006,-.02229,-.00902*
20,1,.006,-.02229,-.00902,-.0207,-.00477,0.0*
1,1,.006,-.0207,-.00477*
20,1,.006,-.0207,-.00477,-.02017,0.0,0.0*
1,1,.006,-.02017,0.0*
20,1,.006,-.02017,0.0,-.0207,.00478,0.0*
1,1,.006,-.0207,.00478*
20,1,.006,-.0207,.00478,-.02229,.00903,0.0*
1,1,.006,-.02229,.00903*
20,1,.006,-.02229,.00903,-.02441,.01221,0.0*
1,1,.006,-.02441,.01221*
20,1,.006,-.02441,.01221,-.0276,.01487,0.0*
1,1,.006,-.0276,.01487*
20,1,.006,-.0276,.01487,-.03185,.01593,0.0*
1,1,.006,-.03185,.01593*
1,1,.006,-.00901,-.0122*
20,1,.006,-.00901,-.0122,-.00529,-.01486,0.0*
1,1,.006,-.00529,-.01486*
20,1,.006,-.00529,-.01486,-.00105,-.01592,0.0*
1,1,.006,-.00105,-.01592*
20,1,.006,-.00105,-.01592,.0032,-.01486,0.0*
1,1,.006,.0032,-.01486*
20,1,.006,.0032,-.01486,.00692,-.01167,0.0*
1,1,.006,.00692,-.01167*
20,1,.006,.00692,-.01167,.00957,-.0069,0.0*
1,1,.006,.00957,-.0069*
20,1,.006,.00957,-.0069,.01063,-.00212,0.0*
1,1,.006,.01063,-.00212*
20,1,.006,.01063,-.00212,.01063,.00372,0.0*
1,1,.006,.01063,.00372*
20,1,.006,.01063,.00372,.00957,.0085,0.0*
1,1,.006,.00957,.0085*
20,1,.006,.00957,.0085,.00692,.01274,0.0*
1,1,.006,.00692,.01274*
20,1,.006,.00692,.01274,.00373,.01487,0.0*
1,1,.006,.00373,.01487*
20,1,.006,.00373,.01487,.00001,.01593,0.0*
1,1,.006,.00001,.01593*
20,1,.006,.00001,.01593,-.00423,.01487,0.0*
1,1,.006,-.00423,.01487*
20,1,.006,-.00423,.01487,-.00742,.01274,0.0*
1,1,.006,-.00742,.01274*
20,1,.006,-.00742,.01274,-.00954,.00956,0.0*
1,1,.006,-.00954,.00956*
20,1,.006,-.00954,.00956,-.0106,.00531,0.0*
1,1,.006,-.0106,.00531*
20,1,.006,-.0106,.00531,-.00954,.0016,0.0*
1,1,.006,-.00954,.0016*
20,1,.006,-.00954,.0016,-.00689,-.00212,0.0*
1,1,.006,-.00689,-.00212*
20,1,.006,-.00689,-.00212,-.0037,-.00424,0.0*
1,1,.006,-.0037,-.00424*
20,1,.006,-.0037,-.00424,.00001,-.00477,0.0*
1,1,.006,.00001,-.00477*
20,1,.006,.00001,-.00477,.00426,-.00371,0.0*
1,1,.006,.00426,-.00371*
20,1,.006,.00426,-.00371,.00745,-.00106,0.0*
1,1,.006,.00745,-.00106*
20,1,.006,.00745,-.00106,.01063,.00372,0.0*
1,1,.006,.01063,.00372*
1,1,.006,.03187,-.01592*
20,1,.006,.03187,-.01592,.03187,.01593,0.0*
1,1,.006,.03187,.01593*
20,1,.006,.03187,.01593,.0255,.00956,0.0*
1,1,.006,.0255,.00956*
1,1,.006,.0255,-.01592*
20,1,.006,.0255,-.01592,.03824,-.01592,0.0*
1,1,.006,.03824,-.01592*
%
%ADD25MACRO25*%
%AMMACRO11*
1,1,.006,.04764,0.0*
20,1,.006,.04764,0.0,-.04764,0.0,0.0*
1,1,.006,-.04764,0.0*
1,1,.006,0.0,.04764*
20,1,.006,0.0,.04764,0.0,-.04764,0.0*
1,1,.006,0.0,-.04764*
%
%ADD11MACRO11*%
%AMMACRO13*
1,1,.006,.035,0.0*
20,1,.006,.035,0.0,.034468,-.006078,0.0*
1,1,.006,.034468,-.006078*
20,1,.006,.034468,-.006078,.032889,-.011971,0.0*
1,1,.006,.032889,-.011971*
20,1,.006,.032889,-.011971,.030311,-.0175,0.0*
1,1,.006,.030311,-.0175*
20,1,.006,.030311,-.0175,.026812,-.022498,0.0*
1,1,.006,.026812,-.022498*
20,1,.006,.026812,-.022498,.022498,-.026812,0.0*
1,1,.006,.022498,-.026812*
20,1,.006,.022498,-.026812,.0175,-.030311,0.0*
1,1,.006,.0175,-.030311*
20,1,.006,.0175,-.030311,.011971,-.032889,0.0*
1,1,.006,.011971,-.032889*
20,1,.006,.011971,-.032889,.006078,-.034468,0.0*
1,1,.006,.006078,-.034468*
20,1,.006,.006078,-.034468,0.0,-.035,0.0*
1,1,.006,0.0,-.035*
20,1,.006,0.0,-.035,-.006078,-.034468,0.0*
1,1,.006,-.006078,-.034468*
20,1,.006,-.006078,-.034468,-.011971,-.032889,0.0*
1,1,.006,-.011971,-.032889*
20,1,.006,-.011971,-.032889,-.0175,-.030311,0.0*
1,1,.006,-.0175,-.030311*
20,1,.006,-.0175,-.030311,-.022498,-.026812,0.0*
1,1,.006,-.022498,-.026812*
20,1,.006,-.022498,-.026812,-.026812,-.022498,0.0*
1,1,.006,-.026812,-.022498*
20,1,.006,-.026812,-.022498,-.030311,-.0175,0.0*
1,1,.006,-.030311,-.0175*
20,1,.006,-.030311,-.0175,-.032889,-.011971,0.0*
1,1,.006,-.032889,-.011971*
20,1,.006,-.032889,-.011971,-.034468,-.006078,0.0*
1,1,.006,-.034468,-.006078*
20,1,.006,-.034468,-.006078,-.035,0.0,0.0*
1,1,.006,-.035,0.0*
20,1,.006,-.035,0.0,-.034468,.006078,0.0*
1,1,.006,-.034468,.006078*
20,1,.006,-.034468,.006078,-.032889,.011971,0.0*
1,1,.006,-.032889,.011971*
20,1,.006,-.032889,.011971,-.030311,.0175,0.0*
1,1,.006,-.030311,.0175*
20,1,.006,-.030311,.0175,-.026812,.022498,0.0*
1,1,.006,-.026812,.022498*
20,1,.006,-.026812,.022498,-.022498,.026812,0.0*
1,1,.006,-.022498,.026812*
20,1,.006,-.022498,.026812,-.0175,.030311,0.0*
1,1,.006,-.0175,.030311*
20,1,.006,-.0175,.030311,-.011971,.032889,0.0*
1,1,.006,-.011971,.032889*
20,1,.006,-.011971,.032889,-.006078,.034468,0.0*
1,1,.006,-.006078,.034468*
20,1,.006,-.006078,.034468,0.0,.035,0.0*
1,1,.006,0.0,.035*
20,1,.006,0.0,.035,.006078,.034468,0.0*
1,1,.006,.006078,.034468*
20,1,.006,.006078,.034468,.011971,.032889,0.0*
1,1,.006,.011971,.032889*
20,1,.006,.011971,.032889,.0175,.030311,0.0*
1,1,.006,.0175,.030311*
20,1,.006,.0175,.030311,.022498,.026812,0.0*
1,1,.006,.022498,.026812*
20,1,.006,.022498,.026812,.026812,.022498,0.0*
1,1,.006,.026812,.022498*
20,1,.006,.026812,.022498,.030311,.0175,0.0*
1,1,.006,.030311,.0175*
20,1,.006,.030311,.0175,.032889,.011971,0.0*
1,1,.006,.032889,.011971*
20,1,.006,.032889,.011971,.034468,.006078,0.0*
1,1,.006,.034468,.006078*
20,1,.006,.034468,.006078,.035,0.0,0.0*
1,1,.006,.035,0.0*
1,1,.006,-.0295,.01041*
20,1,.006,-.0295,.01041,-.02082,-.01041,0.0*
1,1,.006,-.02082,-.01041*
20,1,.006,-.02082,-.01041,-.01214,.01041,0.0*
1,1,.006,-.01214,.01041*
1,1,.006,.00001,-.01041*
20,1,.006,.00001,-.01041,.00001,.01041,0.0*
1,1,.006,.00001,.01041*
20,1,.006,.00001,.01041,-.00415,.00625,0.0*
1,1,.006,-.00415,.00625*
1,1,.006,-.00415,-.01041*
20,1,.006,-.00415,-.01041,.00417,-.01041,0.0*
1,1,.006,.00417,-.01041*
1,1,.006,.02084,.01041*
20,1,.006,.02084,.01041,.01806,.00972,0.0*
1,1,.006,.01806,.00972*
20,1,.006,.01806,.00972,.01598,.00798,0.0*
1,1,.006,.01598,.00798*
20,1,.006,.01598,.00798,.01459,.0059,0.0*
1,1,.006,.01459,.0059*
20,1,.006,.01459,.0059,.01355,.00312,0.0*
1,1,.006,.01355,.00312*
20,1,.006,.01355,.00312,.01321,0.0,0.0*
1,1,.006,.01321,0.0*
20,1,.006,.01321,0.0,.01355,-.00312,0.0*
1,1,.006,.01355,-.00312*
20,1,.006,.01355,-.00312,.01459,-.0059,0.0*
1,1,.006,.01459,-.0059*
20,1,.006,.01459,-.0059,.01598,-.00798,0.0*
1,1,.006,.01598,-.00798*
20,1,.006,.01598,-.00798,.01806,-.00972,0.0*
1,1,.006,.01806,-.00972*
20,1,.006,.01806,-.00972,.02084,-.01041,0.0*
1,1,.006,.02084,-.01041*
20,1,.006,.02084,-.01041,.02362,-.00972,0.0*
1,1,.006,.02362,-.00972*
20,1,.006,.02362,-.00972,.0257,-.00798,0.0*
1,1,.006,.0257,-.00798*
20,1,.006,.0257,-.00798,.02709,-.0059,0.0*
1,1,.006,.02709,-.0059*
20,1,.006,.02709,-.0059,.02813,-.00312,0.0*
1,1,.006,.02813,-.00312*
20,1,.006,.02813,-.00312,.02847,0.0,0.0*
1,1,.006,.02847,0.0*
20,1,.006,.02847,0.0,.02813,.00312,0.0*
1,1,.006,.02813,.00312*
20,1,.006,.02813,.00312,.02709,.0059,0.0*
1,1,.006,.02709,.0059*
20,1,.006,.02709,.0059,.0257,.00798,0.0*
1,1,.006,.0257,.00798*
20,1,.006,.0257,.00798,.02362,.00972,0.0*
1,1,.006,.02362,.00972*
20,1,.006,.02362,.00972,.02084,.01041,0.0*
1,1,.006,.02084,.01041*
%
%ADD13MACRO13*%
%AMMACRO21*
1,1,.006,0.0,.035*
20,1,.006,0.0,.035,.030311,-.0175,0.0*
1,1,.006,.030311,-.0175*
20,1,.006,.030311,-.0175,-.030311,-.0175,0.0*
1,1,.006,-.030311,-.0175*
20,1,.006,-.030311,-.0175,0.0,.035,0.0*
1,1,.006,0.0,.035*
1,1,.006,-.01433,-.00918*
20,1,.006,-.01433,-.00918,-.01433,.00184,0.0*
1,1,.006,-.01433,.00184*
1,1,.006,-.01433,.00018*
20,1,.006,-.01433,.00018,-.01341,.0011,0.0*
1,1,.006,-.01341,.0011*
20,1,.006,-.01341,.0011,-.01249,.00165,0.0*
1,1,.006,-.01249,.00165*
20,1,.006,-.01249,.00165,-.01102,.00184,0.0*
1,1,.006,-.01102,.00184*
20,1,.006,-.01102,.00184,-.00973,.00165,0.0*
1,1,.006,-.00973,.00165*
20,1,.006,-.00973,.00165,-.00845,.00073,0.0*
1,1,.006,-.00845,.00073*
20,1,.006,-.00845,.00073,-.0079,-.00055,0.0*
1,1,.006,-.0079,-.00055*
20,1,.006,-.0079,-.00055,-.00771,-.00184,0.0*
1,1,.006,-.00771,-.00184*
20,1,.006,-.00771,-.00184,-.0079,-.00312,0.0*
1,1,.006,-.0079,-.00312*
20,1,.006,-.0079,-.00312,-.00845,-.00441,0.0*
1,1,.006,-.00845,-.00441*
20,1,.006,-.00845,-.00441,-.00955,-.00514,0.0*
1,1,.006,-.00955,-.00514*
20,1,.006,-.00955,-.00514,-.01102,-.00551,0.0*
1,1,.006,-.01102,-.00551*
20,1,.006,-.01102,-.00551,-.01231,-.00533,0.0*
1,1,.006,-.01231,-.00533*
20,1,.006,-.01231,-.00533,-.01359,-.00478,0.0*
1,1,.006,-.01359,-.00478*
20,1,.006,-.01359,-.00478,-.01433,-.00404,0.0*
1,1,.006,-.01433,-.00404*
1,1,.006,-.00256,-.00551*
20,1,.006,-.00256,-.00551,-.00256,.00184,0.0*
1,1,.006,-.00256,.00184*
1,1,.006,-.00256,.00037*
20,1,.006,-.00256,.00037,-.00164,.0011,0.0*
1,1,.006,-.00164,.0011*
20,1,.006,-.00164,.0011,-.00072,.00165,0.0*
1,1,.006,-.00072,.00165*
20,1,.006,-.00072,.00165,.00056,.00184,0.0*
1,1,.006,.00056,.00184*
20,1,.006,.00056,.00184,.00148,.00165,0.0*
1,1,.006,.00148,.00165*
20,1,.006,.00148,.00165,.00258,.0011,0.0*
1,1,.006,.00258,.0011*
1,1,.006,.01104,.00184*
20,1,.006,.01104,.00184,.01104,-.00551,0.0*
1,1,.006,.01104,-.00551*
1,1,.006,.01104,.00478*
20,1,.006,.01104,.00478,.01067,.00496,0.0*
1,1,.006,.01067,.00496*
20,1,.006,.01067,.00496,.01067,.00533,0.0*
1,1,.006,.01067,.00533*
20,1,.006,.01067,.00533,.01104,.00551,0.0*
1,1,.006,.01104,.00551*
20,1,.006,.01104,.00551,.01141,.00533,0.0*
1,1,.006,.01141,.00533*
20,1,.006,.01141,.00533,.01141,.00496,0.0*
1,1,.006,.01141,.00496*
20,1,.006,.01141,.00496,.01104,.00478,0.0*
1,1,.006,.01104,.00478*
%
%ADD21MACRO21*%
%AMMACRO30*
1,1,.006,0.0,.035*
20,1,.006,0.0,.035,.030311,-.0175,0.0*
1,1,.006,.030311,-.0175*
20,1,.006,.030311,-.0175,-.030311,-.0175,0.0*
1,1,.006,-.030311,-.0175*
20,1,.006,-.030311,-.0175,0.0,.035,0.0*
1,1,.006,0.0,.035*
1,1,.006,-.01433,-.00918*
20,1,.006,-.01433,-.00918,-.01433,.00184,0.0*
1,1,.006,-.01433,.00184*
1,1,.006,-.01433,.00018*
20,1,.006,-.01433,.00018,-.01341,.0011,0.0*
1,1,.006,-.01341,.0011*
20,1,.006,-.01341,.0011,-.01249,.00165,0.0*
1,1,.006,-.01249,.00165*
20,1,.006,-.01249,.00165,-.01102,.00184,0.0*
1,1,.006,-.01102,.00184*
20,1,.006,-.01102,.00184,-.00973,.00165,0.0*
1,1,.006,-.00973,.00165*
20,1,.006,-.00973,.00165,-.00845,.00073,0.0*
1,1,.006,-.00845,.00073*
20,1,.006,-.00845,.00073,-.0079,-.00055,0.0*
1,1,.006,-.0079,-.00055*
20,1,.006,-.0079,-.00055,-.00771,-.00184,0.0*
1,1,.006,-.00771,-.00184*
20,1,.006,-.00771,-.00184,-.0079,-.00312,0.0*
1,1,.006,-.0079,-.00312*
20,1,.006,-.0079,-.00312,-.00845,-.00441,0.0*
1,1,.006,-.00845,-.00441*
20,1,.006,-.00845,-.00441,-.00955,-.00514,0.0*
1,1,.006,-.00955,-.00514*
20,1,.006,-.00955,-.00514,-.01102,-.00551,0.0*
1,1,.006,-.01102,-.00551*
20,1,.006,-.01102,-.00551,-.01231,-.00533,0.0*
1,1,.006,-.01231,-.00533*
20,1,.006,-.01231,-.00533,-.01359,-.00478,0.0*
1,1,.006,-.01359,-.00478*
20,1,.006,-.01359,-.00478,-.01433,-.00404,0.0*
1,1,.006,-.01433,-.00404*
1,1,.006,-.00256,-.00551*
20,1,.006,-.00256,-.00551,-.00256,.00184,0.0*
1,1,.006,-.00256,.00184*
1,1,.006,-.00256,.00037*
20,1,.006,-.00256,.00037,-.00164,.0011,0.0*
1,1,.006,-.00164,.0011*
20,1,.006,-.00164,.0011,-.00072,.00165,0.0*
1,1,.006,-.00072,.00165*
20,1,.006,-.00072,.00165,.00056,.00184,0.0*
1,1,.006,.00056,.00184*
20,1,.006,.00056,.00184,.00148,.00165,0.0*
1,1,.006,.00148,.00165*
20,1,.006,.00148,.00165,.00258,.0011,0.0*
1,1,.006,.00258,.0011*
1,1,.006,.01435,-.00918*
20,1,.006,.01435,-.00918,.01435,.00184,0.0*
1,1,.006,.01435,.00184*
1,1,.006,.01435,.00018*
20,1,.006,.01435,.00018,.01343,.0011,0.0*
1,1,.006,.01343,.0011*
20,1,.006,.01343,.0011,.01233,.00165,0.0*
1,1,.006,.01233,.00165*
20,1,.006,.01233,.00165,.01104,.00184,0.0*
1,1,.006,.01104,.00184*
20,1,.006,.01104,.00184,.00994,.00165,0.0*
1,1,.006,.00994,.00165*
20,1,.006,.00994,.00165,.00865,.00073,0.0*
1,1,.006,.00865,.00073*
20,1,.006,.00865,.00073,.00792,-.00055,0.0*
1,1,.006,.00792,-.00055*
20,1,.006,.00792,-.00055,.00773,-.00184,0.0*
1,1,.006,.00773,-.00184*
20,1,.006,.00773,-.00184,.00792,-.00312,0.0*
1,1,.006,.00792,-.00312*
20,1,.006,.00792,-.00312,.00865,-.00441,0.0*
1,1,.006,.00865,-.00441*
20,1,.006,.00865,-.00441,.00994,-.00533,0.0*
1,1,.006,.00994,-.00533*
20,1,.006,.00994,-.00533,.01104,-.00551,0.0*
1,1,.006,.01104,-.00551*
20,1,.006,.01104,-.00551,.01233,-.00533,0.0*
1,1,.006,.01233,-.00533*
20,1,.006,.01233,-.00533,.01343,-.00478,0.0*
1,1,.006,.01343,-.00478*
20,1,.006,.01343,-.00478,.01435,-.00386,0.0*
1,1,.006,.01435,-.00386*
%
%ADD30MACRO30*%
%AMMACRO24*
1,1,.006,.075,0.0*
20,1,.006,.075,0.0,.0375,.064952,0.0*
1,1,.006,.0375,.064952*
20,1,.006,.0375,.064952,-.0375,.064952,0.0*
1,1,.006,-.0375,.064952*
20,1,.006,-.0375,.064952,-.075,0.0,0.0*
1,1,.006,-.075,0.0*
20,1,.006,-.075,0.0,-.0375,-.064952,0.0*
1,1,.006,-.0375,-.064952*
20,1,.006,-.0375,-.064952,.0375,-.064952,0.0*
1,1,.006,.0375,-.064952*
20,1,.006,.0375,-.064952,.075,0.0,0.0*
1,1,.006,.075,0.0*
1,1,.006,-.03675,-.01837*
20,1,.006,-.03675,-.01837,-.03675,.01838,0.0*
1,1,.006,-.03675,.01838*
20,1,.006,-.03675,.01838,-.0441,.01103,0.0*
1,1,.006,-.0441,.01103*
1,1,.006,-.0441,-.01837*
20,1,.006,-.0441,-.01837,-.0294,-.01837,0.0*
1,1,.006,-.0294,-.01837*
1,1,.006,-.01346,-.01286*
20,1,.006,-.01346,-.01286,-.00979,-.01592,0.0*
1,1,.006,-.00979,-.01592*
20,1,.006,-.00979,-.01592,-.0055,-.01776,0.0*
1,1,.006,-.0055,-.01776*
20,1,.006,-.0055,-.01776,.00001,-.01837,0.0*
1,1,.006,.00001,-.01837*
20,1,.006,.00001,-.01837,.00553,-.01715,0.0*
1,1,.006,.00553,-.01715*
20,1,.006,.00553,-.01715,.00981,-.0147,0.0*
1,1,.006,.00981,-.0147*
20,1,.006,.00981,-.0147,.01288,-.01041,0.0*
1,1,.006,.01288,-.01041*
20,1,.006,.01288,-.01041,.01349,-.00551,0.0*
1,1,.006,.01349,-.00551*
20,1,.006,.01349,-.00551,.01227,-.00061,0.0*
1,1,.006,.01227,-.00061*
20,1,.006,.01227,-.00061,.0092,.00246,0.0*
1,1,.006,.0092,.00246*
20,1,.006,.0092,.00246,.00491,.0049,0.0*
1,1,.006,.00491,.0049*
20,1,.006,.00491,.0049,.00063,.00552,0.0*
1,1,.006,.00063,.00552*
20,1,.006,.00063,.00552,-.00366,.0049,0.0*
1,1,.006,-.00366,.0049*
20,1,.006,-.00366,.0049,-.00917,.00246,0.0*
1,1,.006,-.00917,.00246*
20,1,.006,-.00917,.00246,-.00734,.01838,0.0*
1,1,.006,-.00734,.01838*
20,1,.006,-.00734,.01838,.0092,.01838,0.0*
1,1,.006,.0092,.01838*
1,1,.006,.03677,.01838*
20,1,.006,.03677,.01838,.03187,.01716,0.0*
1,1,.006,.03187,.01716*
20,1,.006,.03187,.01716,.0282,.01409,0.0*
1,1,.006,.0282,.01409*
20,1,.006,.0282,.01409,.02575,.01042,0.0*
1,1,.006,.02575,.01042*
20,1,.006,.02575,.01042,.02391,.00552,0.0*
1,1,.006,.02391,.00552*
20,1,.006,.02391,.00552,.0233,0.0,0.0*
1,1,.006,.0233,0.0*
20,1,.006,.0233,0.0,.02391,-.00551,0.0*
1,1,.006,.02391,-.00551*
20,1,.006,.02391,-.00551,.02575,-.01041,0.0*
1,1,.006,.02575,-.01041*
20,1,.006,.02575,-.01041,.0282,-.01408,0.0*
1,1,.006,.0282,-.01408*
20,1,.006,.0282,-.01408,.03187,-.01715,0.0*
1,1,.006,.03187,-.01715*
20,1,.006,.03187,-.01715,.03677,-.01837,0.0*
1,1,.006,.03677,-.01837*
20,1,.006,.03677,-.01837,.04167,-.01715,0.0*
1,1,.006,.04167,-.01715*
20,1,.006,.04167,-.01715,.04535,-.01408,0.0*
1,1,.006,.04535,-.01408*
20,1,.006,.04535,-.01408,.0478,-.01041,0.0*
1,1,.006,.0478,-.01041*
20,1,.006,.0478,-.01041,.04964,-.00551,0.0*
1,1,.006,.04964,-.00551*
20,1,.006,.04964,-.00551,.05025,0.0,0.0*
1,1,.006,.05025,0.0*
20,1,.006,.05025,0.0,.04964,.00552,0.0*
1,1,.006,.04964,.00552*
20,1,.006,.04964,.00552,.0478,.01042,0.0*
1,1,.006,.0478,.01042*
20,1,.006,.0478,.01042,.04535,.01409,0.0*
1,1,.006,.04535,.01409*
20,1,.006,.04535,.01409,.04167,.01716,0.0*
1,1,.006,.04167,.01716*
20,1,.006,.04167,.01716,.03677,.01838,0.0*
1,1,.006,.03677,.01838*
%
%ADD24MACRO24*%
%AMMACRO18*
1,1,.006,.0625,0.0*
20,1,.006,.0625,0.0,.03125,.054127,0.0*
1,1,.006,.03125,.054127*
20,1,.006,.03125,.054127,-.03125,.054127,0.0*
1,1,.006,-.03125,.054127*
20,1,.006,-.03125,.054127,-.0625,0.0,0.0*
1,1,.006,-.0625,0.0*
20,1,.006,-.0625,0.0,-.03125,-.054127,0.0*
1,1,.006,-.03125,-.054127*
20,1,.006,-.03125,-.054127,.03125,-.054127,0.0*
1,1,.006,.03125,-.054127*
20,1,.006,.03125,-.054127,.0625,0.0,0.0*
1,1,.006,.0625,0.0*
1,1,.006,-.02143,-.02552*
20,1,.006,-.02143,-.02552,-.02143,.0051,0.0*
1,1,.006,-.02143,.0051*
1,1,.006,-.02143,.00051*
20,1,.006,-.02143,.00051,-.02399,.00306,0.0*
1,1,.006,-.02399,.00306*
20,1,.006,-.02399,.00306,-.02705,.00459,0.0*
1,1,.006,-.02705,.00459*
20,1,.006,-.02705,.00459,-.03062,.0051,0.0*
1,1,.006,-.03062,.0051*
20,1,.006,-.03062,.0051,-.03368,.00459,0.0*
1,1,.006,-.03368,.00459*
20,1,.006,-.03368,.00459,-.03725,.00204,0.0*
1,1,.006,-.03725,.00204*
20,1,.006,-.03725,.00204,-.0393,-.00153,0.0*
1,1,.006,-.0393,-.00153*
20,1,.006,-.0393,-.00153,-.03981,-.0051,0.0*
1,1,.006,-.03981,-.0051*
20,1,.006,-.03981,-.0051,-.0393,-.00868,0.0*
1,1,.006,-.0393,-.00868*
20,1,.006,-.0393,-.00868,-.03725,-.01225,0.0*
1,1,.006,-.03725,-.01225*
20,1,.006,-.03725,-.01225,-.03368,-.0148,0.0*
1,1,.006,-.03368,-.0148*
20,1,.006,-.03368,-.0148,-.03062,-.01531,0.0*
1,1,.006,-.03062,-.01531*
20,1,.006,-.03062,-.01531,-.02705,-.0148,0.0*
1,1,.006,-.02705,-.0148*
20,1,.006,-.02705,-.0148,-.02399,-.01327,0.0*
1,1,.006,-.02399,-.01327*
20,1,.006,-.02399,-.01327,-.02143,-.01072,0.0*
1,1,.006,-.02143,-.01072*
1,1,.006,-.01275,.0051*
20,1,.006,-.01275,.0051,-.00662,-.01531,0.0*
1,1,.006,-.00662,-.01531*
20,1,.006,-.00662,-.01531,.00001,.0051,0.0*
1,1,.006,.00001,.0051*
20,1,.006,.00001,.0051,.00664,-.01531,0.0*
1,1,.006,.00664,-.01531*
20,1,.006,.00664,-.01531,.01277,.0051,0.0*
1,1,.006,.01277,.0051*
1,1,.006,.03064,.01531*
20,1,.006,.03064,.01531,.03064,-.01531,0.0*
1,1,.006,.03064,-.01531*
1,1,.006,.0235,.0051*
20,1,.006,.0235,.0051,.03778,.0051,0.0*
1,1,.006,.03778,.0051*
%
%ADD18MACRO18*%
%AMMACRO16*
1,1,.006,.062,0.0*
20,1,.006,.062,0.0,.031,.053694,0.0*
1,1,.006,.031,.053694*
20,1,.006,.031,.053694,-.031,.053694,0.0*
1,1,.006,-.031,.053694*
20,1,.006,-.031,.053694,-.062,0.0,0.0*
1,1,.006,-.062,0.0*
20,1,.006,-.062,0.0,-.031,-.053694,0.0*
1,1,.006,-.031,-.053694*
20,1,.006,-.031,-.053694,.031,-.053694,0.0*
1,1,.006,.031,-.053694*
20,1,.006,.031,-.053694,.062,0.0,0.0*
1,1,.006,.062,0.0*
1,1,.006,-.03038,-.01519*
20,1,.006,-.03038,-.01519,-.03038,.01519,0.0*
1,1,.006,-.03038,.01519*
20,1,.006,-.03038,.01519,-.03646,.00911,0.0*
1,1,.006,-.03646,.00911*
1,1,.006,-.03646,-.01519*
20,1,.006,-.03646,-.01519,-.0243,-.01519,0.0*
1,1,.006,-.0243,-.01519*
1,1,.006,-.00961,.01013*
20,1,.006,-.00961,.01013,-.00657,.01316,0.0*
1,1,.006,-.00657,.01316*
20,1,.006,-.00657,.01316,-.00303,.01468,0.0*
1,1,.006,-.00303,.01468*
20,1,.006,-.00303,.01468,.00102,.01519,0.0*
1,1,.006,.00102,.01519*
20,1,.006,.00102,.01519,.00609,.01418,0.0*
1,1,.006,.00609,.01418*
20,1,.006,.00609,.01418,.00963,.01165,0.0*
1,1,.006,.00963,.01165*
20,1,.006,.00963,.01165,.01064,.00861,0.0*
1,1,.006,.01064,.00861*
20,1,.006,.01064,.00861,.01014,.00557,0.0*
1,1,.006,.01014,.00557*
20,1,.006,.01014,.00557,.00811,.00304,0.0*
1,1,.006,.00811,.00304*
20,1,.006,.00811,.00304,-.00202,-.00203,0.0*
1,1,.006,-.00202,-.00203*
20,1,.006,-.00202,-.00203,-.00657,-.00557,0.0*
1,1,.006,-.00657,-.00557*
20,1,.006,-.00657,-.00557,-.00961,-.01063,0.0*
1,1,.006,-.00961,-.01063*
20,1,.006,-.00961,-.01063,-.01062,-.01519,0.0*
1,1,.006,-.01062,-.01519*
20,1,.006,-.01062,-.01519,.01064,-.01519,0.0*
1,1,.006,.01064,-.01519*
1,1,.006,.03648,-.01519*
20,1,.006,.03648,-.01519,.03648,.01519,0.0*
1,1,.006,.03648,.01519*
20,1,.006,.03648,.01519,.01774,-.00658,0.0*
1,1,.006,.01774,-.00658*
20,1,.006,.01774,-.00658,.04306,-.00658,0.0*
1,1,.006,.04306,-.00658*
%
%ADD16MACRO16*%
%AMMACRO23*
1,1,.006,-.063,-.0315*
20,1,.006,-.063,-.0315,-.063,.0315,0.0*
1,1,.006,-.063,.0315*
20,1,.006,-.063,.0315,-.062043,.04244,0.0*
1,1,.006,-.062043,.04244*
20,1,.006,-.062043,.04244,-.059201,.053047,0.0*
1,1,.006,-.059201,.053047*
20,1,.006,-.059201,.053047,-.05456,.063,0.0*
1,1,.006,-.05456,.063*
20,1,.006,-.05456,.063,-.048261,.071996,0.0*
1,1,.006,-.048261,.071996*
20,1,.006,-.048261,.071996,-.040496,.079761,0.0*
1,1,.006,-.040496,.079761*
20,1,.006,-.040496,.079761,-.0315,.08606,0.0*
1,1,.006,-.0315,.08606*
20,1,.006,-.0315,.08606,-.021547,.090701,0.0*
1,1,.006,-.021547,.090701*
20,1,.006,-.021547,.090701,-.01094,.093543,0.0*
1,1,.006,-.01094,.093543*
20,1,.006,-.01094,.093543,0.0,.0945,0.0*
1,1,.006,0.0,.0945*
20,1,.006,0.0,.0945,.01094,.093543,0.0*
1,1,.006,.01094,.093543*
20,1,.006,.01094,.093543,.021547,.090701,0.0*
1,1,.006,.021547,.090701*
20,1,.006,.021547,.090701,.0315,.08606,0.0*
1,1,.006,.0315,.08606*
20,1,.006,.0315,.08606,.040496,.079761,0.0*
1,1,.006,.040496,.079761*
20,1,.006,.040496,.079761,.048261,.071996,0.0*
1,1,.006,.048261,.071996*
20,1,.006,.048261,.071996,.05456,.063,0.0*
1,1,.006,.05456,.063*
20,1,.006,.05456,.063,.059201,.053047,0.0*
1,1,.006,.059201,.053047*
20,1,.006,.059201,.053047,.062043,.04244,0.0*
1,1,.006,.062043,.04244*
20,1,.006,.062043,.04244,.063,.0315,0.0*
1,1,.006,.063,.0315*
20,1,.006,.063,.0315,.063,-.0315,0.0*
1,1,.006,.063,-.0315*
20,1,.006,.063,-.0315,.062043,-.04244,0.0*
1,1,.006,.062043,-.04244*
20,1,.006,.062043,-.04244,.059201,-.053047,0.0*
1,1,.006,.059201,-.053047*
20,1,.006,.059201,-.053047,.05456,-.063,0.0*
1,1,.006,.05456,-.063*
20,1,.006,.05456,-.063,.048261,-.071996,0.0*
1,1,.006,.048261,-.071996*
20,1,.006,.048261,-.071996,.040496,-.079761,0.0*
1,1,.006,.040496,-.079761*
20,1,.006,.040496,-.079761,.0315,-.08606,0.0*
1,1,.006,.0315,-.08606*
20,1,.006,.0315,-.08606,.021547,-.090701,0.0*
1,1,.006,.021547,-.090701*
20,1,.006,.021547,-.090701,.01094,-.093543,0.0*
1,1,.006,.01094,-.093543*
20,1,.006,.01094,-.093543,0.0,-.0945,0.0*
1,1,.006,0.0,-.0945*
20,1,.006,0.0,-.0945,-.01094,-.093543,0.0*
1,1,.006,-.01094,-.093543*
20,1,.006,-.01094,-.093543,-.021547,-.090701,0.0*
1,1,.006,-.021547,-.090701*
20,1,.006,-.021547,-.090701,-.0315,-.08606,0.0*
1,1,.006,-.0315,-.08606*
20,1,.006,-.0315,-.08606,-.040496,-.079761,0.0*
1,1,.006,-.040496,-.079761*
20,1,.006,-.040496,-.079761,-.048261,-.071996,0.0*
1,1,.006,-.048261,-.071996*
20,1,.006,-.048261,-.071996,-.05456,-.063,0.0*
1,1,.006,-.05456,-.063*
20,1,.006,-.05456,-.063,-.059201,-.053047,0.0*
1,1,.006,-.059201,-.053047*
20,1,.006,-.059201,-.053047,-.062043,-.04244,0.0*
1,1,.006,-.062043,-.04244*
20,1,.006,-.062043,-.04244,-.063,-.0315,0.0*
1,1,.006,-.063,-.0315*
1,1,.006,-.0588,-.00735*
20,1,.006,-.0588,-.00735,-.0441,.02205,0.0*
1,1,.006,-.0441,.02205*
20,1,.006,-.0441,.02205,-.0294,-.00735,0.0*
1,1,.006,-.0294,-.00735*
1,1,.006,-.0441,.02205*
20,1,.006,-.0441,.02205,-.0441,-.03675,0.0*
1,1,.006,-.0441,-.03675*
1,1,.006,-.01616,-.02205*
20,1,.006,-.01616,-.02205,-.01616,.02205,0.0*
1,1,.006,-.01616,.02205*
20,1,.006,-.01616,.02205,-.00146,.02205,0.0*
1,1,.006,-.00146,.02205*
20,1,.006,-.00146,.02205,.00442,.01984,0.0*
1,1,.006,.00442,.01984*
20,1,.006,.00442,.01984,.00883,.0169,0.0*
1,1,.006,.00883,.0169*
20,1,.006,.00883,.0169,.01251,.0125,0.0*
1,1,.006,.01251,.0125*
20,1,.006,.01251,.0125,.01545,.00735,0.0*
1,1,.006,.01545,.00735*
20,1,.006,.01545,.00735,.01618,0.0,0.0*
1,1,.006,.01618,0.0*
20,1,.006,.01618,0.0,.01545,-.00735,0.0*
1,1,.006,.01545,-.00735*
20,1,.006,.01545,-.00735,.01251,-.0125,0.0*
1,1,.006,.01251,-.0125*
20,1,.006,.01251,-.0125,.00883,-.01691,0.0*
1,1,.006,.00883,-.01691*
20,1,.006,.00883,-.01691,.00442,-.01985,0.0*
1,1,.006,.00442,-.01985*
20,1,.006,.00442,-.01985,-.00146,-.02205,0.0*
1,1,.006,-.00146,-.02205*
20,1,.006,-.00146,-.02205,-.01616,-.02205,0.0*
1,1,.006,-.01616,-.02205*
1,1,.006,.02868,-.01617*
20,1,.006,.02868,-.01617,.03457,-.01985,0.0*
1,1,.006,.03457,-.01985*
20,1,.006,.03457,-.01985,.04118,-.02205,0.0*
1,1,.006,.04118,-.02205*
20,1,.006,.04118,-.02205,.04706,-.02205,0.0*
1,1,.006,.04706,-.02205*
20,1,.006,.04706,-.02205,.05294,-.01985,0.0*
1,1,.006,.05294,-.01985*
20,1,.006,.05294,-.01985,.05735,-.01617,0.0*
1,1,.006,.05735,-.01617*
20,1,.006,.05735,-.01617,.05956,-.01102,0.0*
1,1,.006,.05956,-.01102*
20,1,.006,.05956,-.01102,.05809,-.00588,0.0*
1,1,.006,.05809,-.00588*
20,1,.006,.05809,-.00588,.05441,-.00147,0.0*
1,1,.006,.05441,-.00147*
20,1,.006,.05441,-.00147,.04779,.00147,0.0*
1,1,.006,.04779,.00147*
20,1,.006,.04779,.00147,.03898,.00294,0.0*
1,1,.006,.03898,.00294*
20,1,.006,.03898,.00294,.03383,.00588,0.0*
1,1,.006,.03383,.00588*
20,1,.006,.03383,.00588,.03162,.01102,0.0*
1,1,.006,.03162,.01102*
20,1,.006,.03162,.01102,.0331,.01617,0.0*
1,1,.006,.0331,.01617*
20,1,.006,.0331,.01617,.03677,.01984,0.0*
1,1,.006,.03677,.01984*
20,1,.006,.03677,.01984,.04191,.02205,0.0*
1,1,.006,.04191,.02205*
20,1,.006,.04191,.02205,.04706,.02205,0.0*
1,1,.006,.04706,.02205*
20,1,.006,.04706,.02205,.05221,.02058,0.0*
1,1,.006,.05221,.02058*
20,1,.006,.05221,.02058,.05662,.0169,0.0*
1,1,.006,.05662,.0169*
%
%ADD23MACRO23*%
%AMMACRO28*
1,1,.006,.067,0.0*
20,1,.006,.067,0.0,.0335,.058024,0.0*
1,1,.006,.0335,.058024*
20,1,.006,.0335,.058024,-.0335,.058024,0.0*
1,1,.006,-.0335,.058024*
20,1,.006,-.0335,.058024,-.067,0.0,0.0*
1,1,.006,-.067,0.0*
20,1,.006,-.067,0.0,-.0335,-.058024,0.0*
1,1,.006,-.0335,-.058024*
20,1,.006,-.0335,-.058024,.0335,-.058024,0.0*
1,1,.006,.0335,-.058024*
20,1,.006,.0335,-.058024,.067,0.0,0.0*
1,1,.006,.067,0.0*
1,1,.006,-.03283,-.01641*
20,1,.006,-.03283,-.01641,-.03283,.01642,0.0*
1,1,.006,-.03283,.01642*
20,1,.006,-.03283,.01642,-.03939,.00985,0.0*
1,1,.006,-.03939,.00985*
1,1,.006,-.03939,-.01641*
20,1,.006,-.03939,-.01641,-.02626,-.01641,0.0*
1,1,.006,-.02626,-.01641*
1,1,.006,-.01202,-.00984*
20,1,.006,-.01202,-.00984,-.00874,-.01367,0.0*
1,1,.006,-.00874,-.01367*
20,1,.006,-.00874,-.01367,-.00436,-.01586,0.0*
1,1,.006,-.00436,-.01586*
20,1,.006,-.00436,-.01586,.00056,-.01641,0.0*
1,1,.006,.00056,-.01641*
20,1,.006,.00056,-.01641,.00494,-.01586,0.0*
1,1,.006,.00494,-.01586*
20,1,.006,.00494,-.01586,.00932,-.01313,0.0*
1,1,.006,.00932,-.01313*
20,1,.006,.00932,-.01313,.01205,-.00984,0.0*
1,1,.006,.01205,-.00984*
20,1,.006,.01205,-.00984,.0126,-.00656,0.0*
1,1,.006,.0126,-.00656*
20,1,.006,.0126,-.00656,.01151,-.00273,0.0*
1,1,.006,.01151,-.00273*
20,1,.006,.01151,-.00273,.00768,0.0,0.0*
1,1,.006,.00768,0.0*
20,1,.006,.00768,0.0,.00384,.0011,0.0*
1,1,.006,.00384,.0011*
20,1,.006,.00384,.0011,-.00108,.0011,0.0*
1,1,.006,-.00108,.0011*
1,1,.006,.00384,.0011*
20,1,.006,.00384,.0011,.00713,.00274,0.0*
1,1,.006,.00713,.00274*
20,1,.006,.00713,.00274,.00986,.00548,0.0*
1,1,.006,.00986,.00548*
20,1,.006,.00986,.00548,.01096,.00876,0.0*
1,1,.006,.01096,.00876*
20,1,.006,.01096,.00876,.00986,.01204,0.0*
1,1,.006,.00986,.01204*
20,1,.006,.00986,.01204,.00713,.01478,0.0*
1,1,.006,.00713,.01478*
20,1,.006,.00713,.01478,.0022,.01642,0.0*
1,1,.006,.0022,.01642*
20,1,.006,.0022,.01642,-.00272,.01587,0.0*
1,1,.006,-.00272,.01587*
20,1,.006,-.00272,.01587,-.00765,.01368,0.0*
1,1,.006,-.00765,.01368*
1,1,.006,.03942,-.01641*
20,1,.006,.03942,-.01641,.03942,.01642,0.0*
1,1,.006,.03942,.01642*
20,1,.006,.03942,.01642,.01918,-.00711,0.0*
1,1,.006,.01918,-.00711*
20,1,.006,.01918,-.00711,.04653,-.00711,0.0*
1,1,.006,.04653,-.00711*
%
%ADD28MACRO28*%
%AMMACRO29*
1,1,.006,.035,0.0*
20,1,.006,.035,0.0,.034468,-.006078,0.0*
1,1,.006,.034468,-.006078*
20,1,.006,.034468,-.006078,.032889,-.011971,0.0*
1,1,.006,.032889,-.011971*
20,1,.006,.032889,-.011971,.030311,-.0175,0.0*
1,1,.006,.030311,-.0175*
20,1,.006,.030311,-.0175,.026812,-.022498,0.0*
1,1,.006,.026812,-.022498*
20,1,.006,.026812,-.022498,.022498,-.026812,0.0*
1,1,.006,.022498,-.026812*
20,1,.006,.022498,-.026812,.0175,-.030311,0.0*
1,1,.006,.0175,-.030311*
20,1,.006,.0175,-.030311,.011971,-.032889,0.0*
1,1,.006,.011971,-.032889*
20,1,.006,.011971,-.032889,.006078,-.034468,0.0*
1,1,.006,.006078,-.034468*
20,1,.006,.006078,-.034468,0.0,-.035,0.0*
1,1,.006,0.0,-.035*
20,1,.006,0.0,-.035,-.006078,-.034468,0.0*
1,1,.006,-.006078,-.034468*
20,1,.006,-.006078,-.034468,-.011971,-.032889,0.0*
1,1,.006,-.011971,-.032889*
20,1,.006,-.011971,-.032889,-.0175,-.030311,0.0*
1,1,.006,-.0175,-.030311*
20,1,.006,-.0175,-.030311,-.022498,-.026812,0.0*
1,1,.006,-.022498,-.026812*
20,1,.006,-.022498,-.026812,-.026812,-.022498,0.0*
1,1,.006,-.026812,-.022498*
20,1,.006,-.026812,-.022498,-.030311,-.0175,0.0*
1,1,.006,-.030311,-.0175*
20,1,.006,-.030311,-.0175,-.032889,-.011971,0.0*
1,1,.006,-.032889,-.011971*
20,1,.006,-.032889,-.011971,-.034468,-.006078,0.0*
1,1,.006,-.034468,-.006078*
20,1,.006,-.034468,-.006078,-.035,0.0,0.0*
1,1,.006,-.035,0.0*
20,1,.006,-.035,0.0,-.034468,.006078,0.0*
1,1,.006,-.034468,.006078*
20,1,.006,-.034468,.006078,-.032889,.011971,0.0*
1,1,.006,-.032889,.011971*
20,1,.006,-.032889,.011971,-.030311,.0175,0.0*
1,1,.006,-.030311,.0175*
20,1,.006,-.030311,.0175,-.026812,.022498,0.0*
1,1,.006,-.026812,.022498*
20,1,.006,-.026812,.022498,-.022498,.026812,0.0*
1,1,.006,-.022498,.026812*
20,1,.006,-.022498,.026812,-.0175,.030311,0.0*
1,1,.006,-.0175,.030311*
20,1,.006,-.0175,.030311,-.011971,.032889,0.0*
1,1,.006,-.011971,.032889*
20,1,.006,-.011971,.032889,-.006078,.034468,0.0*
1,1,.006,-.006078,.034468*
20,1,.006,-.006078,.034468,0.0,.035,0.0*
1,1,.006,0.0,.035*
20,1,.006,0.0,.035,.006078,.034468,0.0*
1,1,.006,.006078,.034468*
20,1,.006,.006078,.034468,.011971,.032889,0.0*
1,1,.006,.011971,.032889*
20,1,.006,.011971,.032889,.0175,.030311,0.0*
1,1,.006,.0175,.030311*
20,1,.006,.0175,.030311,.022498,.026812,0.0*
1,1,.006,.022498,.026812*
20,1,.006,.022498,.026812,.026812,.022498,0.0*
1,1,.006,.026812,.022498*
20,1,.006,.026812,.022498,.030311,.0175,0.0*
1,1,.006,.030311,.0175*
20,1,.006,.030311,.0175,.032889,.011971,0.0*
1,1,.006,.032889,.011971*
20,1,.006,.032889,.011971,.034468,.006078,0.0*
1,1,.006,.034468,.006078*
20,1,.006,.034468,.006078,.035,0.0,0.0*
1,1,.006,.035,0.0*
1,1,.006,-.01804,.00069*
20,1,.006,-.01804,.00069,-.01666,.00173,0.0*
1,1,.006,-.01666,.00173*
20,1,.006,-.01666,.00173,-.01562,.00347,0.0*
1,1,.006,-.01562,.00347*
20,1,.006,-.01562,.00347,-.01492,.0059,0.0*
1,1,.006,-.01492,.0059*
20,1,.006,-.01492,.0059,-.01562,.00798,0.0*
1,1,.006,-.01562,.00798*
20,1,.006,-.01562,.00798,-.017,.00937,0.0*
1,1,.006,-.017,.00937*
20,1,.006,-.017,.00937,-.01943,.01041,0.0*
1,1,.006,-.01943,.01041*
20,1,.006,-.01943,.01041,-.0288,.01041,0.0*
1,1,.006,-.0288,.01041*
20,1,.006,-.0288,.01041,-.0288,-.01041,0.0*
1,1,.006,-.0288,-.01041*
20,1,.006,-.0288,-.01041,-.01735,-.01041,0.0*
1,1,.006,-.01735,-.01041*
20,1,.006,-.01735,-.01041,-.01492,-.00902,0.0*
1,1,.006,-.01492,-.00902*
20,1,.006,-.01492,-.00902,-.01353,-.00694,0.0*
1,1,.006,-.01353,-.00694*
20,1,.006,-.01353,-.00694,-.01284,-.00451,0.0*
1,1,.006,-.01284,-.00451*
20,1,.006,-.01284,-.00451,-.01353,-.00208,0.0*
1,1,.006,-.01353,-.00208*
20,1,.006,-.01353,-.00208,-.01562,0.0,0.0*
1,1,.006,-.01562,0.0*
20,1,.006,-.01562,0.0,-.01804,.00069,0.0*
1,1,.006,-.01804,.00069*
20,1,.006,-.01804,.00069,-.0288,.00069,0.0*
1,1,.006,-.0288,.00069*
1,1,.006,.00209,0.0*
20,1,.006,.00209,0.0,.00903,0.0,0.0*
1,1,.006,.00903,0.0*
20,1,.006,.00903,0.0,.00903,-.00625,0.0*
1,1,.006,.00903,-.00625*
20,1,.006,.00903,-.00625,.00695,-.00833,0.0*
1,1,.006,.00695,-.00833*
20,1,.006,.00695,-.00833,.00452,-.00972,0.0*
1,1,.006,.00452,-.00972*
20,1,.006,.00452,-.00972,.00105,-.01041,0.0*
1,1,.006,.00105,-.01041*
20,1,.006,.00105,-.01041,-.00242,-.00972,0.0*
1,1,.006,-.00242,-.00972*
20,1,.006,-.00242,-.00972,-.00485,-.00833,0.0*
1,1,.006,-.00485,-.00833*
20,1,.006,-.00485,-.00833,-.00693,-.00625,0.0*
1,1,.006,-.00693,-.00625*
20,1,.006,-.00693,-.00625,-.00832,-.00382,0.0*
1,1,.006,-.00832,-.00382*
20,1,.006,-.00832,-.00382,-.00901,-.00104,0.0*
1,1,.006,-.00901,-.00104*
20,1,.006,-.00901,-.00104,-.00901,.00139,0.0*
1,1,.006,-.00901,.00139*
20,1,.006,-.00901,.00139,-.00832,.00347,0.0*
1,1,.006,-.00832,.00347*
20,1,.006,-.00832,.00347,-.00693,.0059,0.0*
1,1,.006,-.00693,.0059*
20,1,.006,-.00693,.0059,-.00485,.00798,0.0*
1,1,.006,-.00485,.00798*
20,1,.006,-.00485,.00798,-.00277,.00937,0.0*
1,1,.006,-.00277,.00937*
20,1,.006,-.00277,.00937,.00001,.01041,0.0*
1,1,.006,.00001,.01041*
20,1,.006,.00001,.01041,.00244,.01041,0.0*
1,1,.006,.00244,.01041*
20,1,.006,.00244,.01041,.00521,.00972,0.0*
1,1,.006,.00521,.00972*
20,1,.006,.00521,.00972,.0073,.00833,0.0*
1,1,.006,.0073,.00833*
1,1,.006,.01216,-.01041*
20,1,.006,.01216,-.01041,.02084,.01041,0.0*
1,1,.006,.02084,.01041*
20,1,.006,.02084,.01041,.02952,-.01041,0.0*
1,1,.006,.02952,-.01041*
1,1,.006,.02639,-.00312*
20,1,.006,.02639,-.00312,.01529,-.00312,0.0*
1,1,.006,.01529,-.00312*
%
%ADD29MACRO29*%
%AMMACRO27*
1,1,.006,0.0,.035*
20,1,.006,0.0,.035,.030311,-.0175,0.0*
1,1,.006,.030311,-.0175*
20,1,.006,.030311,-.0175,-.030311,-.0175,0.0*
1,1,.006,-.030311,-.0175*
20,1,.006,-.030311,-.0175,0.0,.035,0.0*
1,1,.006,0.0,.035*
1,1,.006,-.01433,-.00918*
20,1,.006,-.01433,-.00918,-.01433,.00184,0.0*
1,1,.006,-.01433,.00184*
1,1,.006,-.01433,.00018*
20,1,.006,-.01433,.00018,-.01341,.0011,0.0*
1,1,.006,-.01341,.0011*
20,1,.006,-.01341,.0011,-.01249,.00165,0.0*
1,1,.006,-.01249,.00165*
20,1,.006,-.01249,.00165,-.01102,.00184,0.0*
1,1,.006,-.01102,.00184*
20,1,.006,-.01102,.00184,-.00973,.00165,0.0*
1,1,.006,-.00973,.00165*
20,1,.006,-.00973,.00165,-.00845,.00073,0.0*
1,1,.006,-.00845,.00073*
20,1,.006,-.00845,.00073,-.0079,-.00055,0.0*
1,1,.006,-.0079,-.00055*
20,1,.006,-.0079,-.00055,-.00771,-.00184,0.0*
1,1,.006,-.00771,-.00184*
20,1,.006,-.00771,-.00184,-.0079,-.00312,0.0*
1,1,.006,-.0079,-.00312*
20,1,.006,-.0079,-.00312,-.00845,-.00441,0.0*
1,1,.006,-.00845,-.00441*
20,1,.006,-.00845,-.00441,-.00955,-.00514,0.0*
1,1,.006,-.00955,-.00514*
20,1,.006,-.00955,-.00514,-.01102,-.00551,0.0*
1,1,.006,-.01102,-.00551*
20,1,.006,-.01102,-.00551,-.01231,-.00533,0.0*
1,1,.006,-.01231,-.00533*
20,1,.006,-.01231,-.00533,-.01359,-.00478,0.0*
1,1,.006,-.01359,-.00478*
20,1,.006,-.01359,-.00478,-.01433,-.00404,0.0*
1,1,.006,-.01433,-.00404*
1,1,.006,-.00385,-.00882*
20,1,.006,-.00385,-.00882,-.00274,-.00918,0.0*
1,1,.006,-.00274,-.00918*
20,1,.006,-.00274,-.00918,-.00128,-.00882,0.0*
1,1,.006,-.00128,-.00882*
20,1,.006,-.00128,-.00882,-.00036,-.00808,0.0*
1,1,.006,-.00036,-.00808*
20,1,.006,-.00036,-.00808,.00038,-.00716,0.0*
1,1,.006,.00038,-.00716*
20,1,.006,.00038,-.00716,.00148,-.00422,0.0*
1,1,.006,.00148,-.00422*
20,1,.006,.00148,-.00422,.00387,.00184,0.0*
1,1,.006,.00387,.00184*
1,1,.006,-.00201,.00184*
20,1,.006,-.00201,.00184,.00148,-.00422,0.0*
1,1,.006,.00148,-.00422*
1,1,.006,.00792,.00184*
20,1,.006,.00792,.00184,.00792,-.00331,0.0*
1,1,.006,.00792,-.00331*
20,1,.006,.00792,-.00331,.00865,-.00459,0.0*
1,1,.006,.00865,-.00459*
20,1,.006,.00865,-.00459,.00975,-.00533,0.0*
1,1,.006,.00975,-.00533*
20,1,.006,.00975,-.00533,.01104,-.00551,0.0*
1,1,.006,.01104,-.00551*
20,1,.006,.01104,-.00551,.01233,-.00533,0.0*
1,1,.006,.01233,-.00533*
20,1,.006,.01233,-.00533,.01343,-.00459,0.0*
1,1,.006,.01343,-.00459*
20,1,.006,.01343,-.00459,.01416,-.00331,0.0*
1,1,.006,.01416,-.00331*
1,1,.006,.01416,-.00551*
20,1,.006,.01416,-.00551,.01416,.00184,0.0*
1,1,.006,.01416,.00184*
%
%ADD27MACRO27*%
%AMMACRO19*
1,1,.006,0.0,.035*
20,1,.006,0.0,.035,.030311,-.0175,0.0*
1,1,.006,.030311,-.0175*
20,1,.006,.030311,-.0175,-.030311,-.0175,0.0*
1,1,.006,-.030311,-.0175*
20,1,.006,-.030311,-.0175,0.0,.035,0.0*
1,1,.006,0.0,.035*
1,1,.006,-.01102,.00551*
20,1,.006,-.01102,.00551,-.01249,.00514,0.0*
1,1,.006,-.01249,.00514*
20,1,.006,-.01249,.00514,-.01359,.00422,0.0*
1,1,.006,-.01359,.00422*
20,1,.006,-.01359,.00422,-.01433,.00312,0.0*
1,1,.006,-.01433,.00312*
20,1,.006,-.01433,.00312,-.01488,.00165,0.0*
1,1,.006,-.01488,.00165*
20,1,.006,-.01488,.00165,-.01506,0.0,0.0*
1,1,.006,-.01506,0.0*
20,1,.006,-.01506,0.0,-.01488,-.00165,0.0*
1,1,.006,-.01488,-.00165*
20,1,.006,-.01488,-.00165,-.01433,-.00312,0.0*
1,1,.006,-.01433,-.00312*
20,1,.006,-.01433,-.00312,-.01359,-.00422,0.0*
1,1,.006,-.01359,-.00422*
20,1,.006,-.01359,-.00422,-.01249,-.00514,0.0*
1,1,.006,-.01249,-.00514*
20,1,.006,-.01249,-.00514,-.01102,-.00551,0.0*
1,1,.006,-.01102,-.00551*
20,1,.006,-.01102,-.00551,-.00955,-.00514,0.0*
1,1,.006,-.00955,-.00514*
20,1,.006,-.00955,-.00514,-.00845,-.00422,0.0*
1,1,.006,-.00845,-.00422*
20,1,.006,-.00845,-.00422,-.00771,-.00312,0.0*
1,1,.006,-.00771,-.00312*
20,1,.006,-.00771,-.00312,-.00716,-.00165,0.0*
1,1,.006,-.00716,-.00165*
20,1,.006,-.00716,-.00165,-.00698,0.0,0.0*
1,1,.006,-.00698,0.0*
20,1,.006,-.00698,0.0,-.00716,.00165,0.0*
1,1,.006,-.00716,.00165*
20,1,.006,-.00716,.00165,-.00771,.00312,0.0*
1,1,.006,-.00771,.00312*
20,1,.006,-.00771,.00312,-.00845,.00422,0.0*
1,1,.006,-.00845,.00422*
20,1,.006,-.00845,.00422,-.00955,.00514,0.0*
1,1,.006,-.00955,.00514*
20,1,.006,-.00955,.00514,-.01102,.00551,0.0*
1,1,.006,-.01102,.00551*
1,1,.006,.00221,-.00551*
20,1,.006,.00221,-.00551,.00221,.00551,0.0*
1,1,.006,.00221,.00551*
20,1,.006,.00221,.00551,-.00458,-.00239,0.0*
1,1,.006,-.00458,-.00239*
20,1,.006,-.00458,-.00239,.0046,-.00239,0.0*
1,1,.006,.0046,-.00239*
1,1,.006,.01104,-.00551*
20,1,.006,.01104,-.00551,.01104,.00551,0.0*
1,1,.006,.01104,.00551*
20,1,.006,.01104,.00551,.00884,.00331,0.0*
1,1,.006,.00884,.00331*
1,1,.006,.00884,-.00551*
20,1,.006,.00884,-.00551,.01324,-.00551,0.0*
1,1,.006,.01324,-.00551*
%
%ADD19MACRO19*%
%AMMACRO15*
1,1,.006,.063,0.0*
20,1,.006,.063,0.0,.0315,.05456,0.0*
1,1,.006,.0315,.05456*
20,1,.006,.0315,.05456,-.0315,.05456,0.0*
1,1,.006,-.0315,.05456*
20,1,.006,-.0315,.05456,-.063,0.0,0.0*
1,1,.006,-.063,0.0*
20,1,.006,-.063,0.0,-.0315,-.05456,0.0*
1,1,.006,-.0315,-.05456*
20,1,.006,-.0315,-.05456,.0315,-.05456,0.0*
1,1,.006,.0315,-.05456*
20,1,.006,.0315,-.05456,.063,0.0,0.0*
1,1,.006,.063,0.0*
1,1,.006,-.03087,-.01543*
20,1,.006,-.03087,-.01543,-.03087,.01544,0.0*
1,1,.006,-.03087,.01544*
20,1,.006,-.03087,.01544,-.03704,.00927,0.0*
1,1,.006,-.03704,.00927*
1,1,.006,-.03704,-.01543*
20,1,.006,-.03704,-.01543,-.02469,-.01543,0.0*
1,1,.006,-.02469,-.01543*
1,1,.006,-.00976,.0103*
20,1,.006,-.00976,.0103,-.00667,.01338,0.0*
1,1,.006,-.00667,.01338*
20,1,.006,-.00667,.01338,-.00307,.01493,0.0*
1,1,.006,-.00307,.01493*
20,1,.006,-.00307,.01493,.00104,.01544,0.0*
1,1,.006,.00104,.01544*
20,1,.006,.00104,.01544,.00619,.01441,0.0*
1,1,.006,.00619,.01441*
20,1,.006,.00619,.01441,.00979,.01184,0.0*
1,1,.006,.00979,.01184*
20,1,.006,.00979,.01184,.01082,.00875,0.0*
1,1,.006,.01082,.00875*
20,1,.006,.01082,.00875,.01031,.00566,0.0*
1,1,.006,.01031,.00566*
20,1,.006,.01031,.00566,.00825,.00309,0.0*
1,1,.006,.00825,.00309*
20,1,.006,.00825,.00309,-.00204,-.00205,0.0*
1,1,.006,-.00204,-.00205*
20,1,.006,-.00204,-.00205,-.00667,-.00565,0.0*
1,1,.006,-.00667,-.00565*
20,1,.006,-.00667,-.00565,-.00976,-.0108,0.0*
1,1,.006,-.00976,-.0108*
20,1,.006,-.00976,-.0108,-.01079,-.01543,0.0*
1,1,.006,-.01079,-.01543*
20,1,.006,-.01079,-.01543,.01082,-.01543,0.0*
1,1,.006,.01082,-.01543*
1,1,.006,.02112,-.00257*
20,1,.006,.02112,-.00257,.02472,.00103,0.0*
1,1,.006,.02472,.00103*
20,1,.006,.02472,.00103,.02781,.00309,0.0*
1,1,.006,.02781,.00309*
20,1,.006,.02781,.00309,.03192,.00412,0.0*
1,1,.006,.03192,.00412*
20,1,.006,.03192,.00412,.03553,.00309,0.0*
1,1,.006,.03553,.00309*
20,1,.006,.03553,.00309,.0381,.00103,0.0*
1,1,.006,.0381,.00103*
20,1,.006,.0381,.00103,.04016,-.00205,0.0*
1,1,.006,.04016,-.00205*
20,1,.006,.04016,-.00205,.04067,-.00565,0.0*
1,1,.006,.04067,-.00565*
20,1,.006,.04067,-.00565,.04016,-.00874,0.0*
1,1,.006,.04016,-.00874*
20,1,.006,.04016,-.00874,.0381,-.01183,0.0*
1,1,.006,.0381,-.01183*
20,1,.006,.0381,-.01183,.03501,-.0144,0.0*
1,1,.006,.03501,-.0144*
20,1,.006,.03501,-.0144,.03141,-.01543,0.0*
1,1,.006,.03141,-.01543*
20,1,.006,.03141,-.01543,.02729,-.0144,0.0*
1,1,.006,.02729,-.0144*
20,1,.006,.02729,-.0144,.02369,-.01131,0.0*
1,1,.006,.02369,-.01131*
20,1,.006,.02369,-.01131,.02163,-.00668,0.0*
1,1,.006,.02163,-.00668*
20,1,.006,.02163,-.00668,.02112,-.00154,0.0*
1,1,.006,.02112,-.00154*
20,1,.006,.02112,-.00154,.02215,.00515,0.0*
1,1,.006,.02215,.00515*
20,1,.006,.02215,.00515,.02369,.00875,0.0*
1,1,.006,.02369,.00875*
20,1,.006,.02369,.00875,.02626,.01235,0.0*
1,1,.006,.02626,.01235*
20,1,.006,.02626,.01235,.02987,.01493,0.0*
1,1,.006,.02987,.01493*
20,1,.006,.02987,.01493,.03347,.01544,0.0*
1,1,.006,.03347,.01544*
20,1,.006,.03347,.01544,.03707,.01441,0.0*
1,1,.006,.03707,.01441*
20,1,.006,.03707,.01441,.03964,.01184,0.0*
1,1,.006,.03964,.01184*
%
%ADD15MACRO15*%
%AMMACRO10*
1,1,.006,0.0,.035*
20,1,.006,0.0,.035,.030311,-.0175,0.0*
1,1,.006,.030311,-.0175*
20,1,.006,.030311,-.0175,-.030311,-.0175,0.0*
1,1,.006,-.030311,-.0175*
20,1,.006,-.030311,-.0175,0.0,.035,0.0*
1,1,.006,0.0,.035*
1,1,.006,-.01102,.00551*
20,1,.006,-.01102,.00551,-.01249,.00514,0.0*
1,1,.006,-.01249,.00514*
20,1,.006,-.01249,.00514,-.01359,.00422,0.0*
1,1,.006,-.01359,.00422*
20,1,.006,-.01359,.00422,-.01433,.00312,0.0*
1,1,.006,-.01433,.00312*
20,1,.006,-.01433,.00312,-.01488,.00165,0.0*
1,1,.006,-.01488,.00165*
20,1,.006,-.01488,.00165,-.01506,0.0,0.0*
1,1,.006,-.01506,0.0*
20,1,.006,-.01506,0.0,-.01488,-.00165,0.0*
1,1,.006,-.01488,-.00165*
20,1,.006,-.01488,-.00165,-.01433,-.00312,0.0*
1,1,.006,-.01433,-.00312*
20,1,.006,-.01433,-.00312,-.01359,-.00422,0.0*
1,1,.006,-.01359,-.00422*
20,1,.006,-.01359,-.00422,-.01249,-.00514,0.0*
1,1,.006,-.01249,-.00514*
20,1,.006,-.01249,-.00514,-.01102,-.00551,0.0*
1,1,.006,-.01102,-.00551*
20,1,.006,-.01102,-.00551,-.00955,-.00514,0.0*
1,1,.006,-.00955,-.00514*
20,1,.006,-.00955,-.00514,-.00845,-.00422,0.0*
1,1,.006,-.00845,-.00422*
20,1,.006,-.00845,-.00422,-.00771,-.00312,0.0*
1,1,.006,-.00771,-.00312*
20,1,.006,-.00771,-.00312,-.00716,-.00165,0.0*
1,1,.006,-.00716,-.00165*
20,1,.006,-.00716,-.00165,-.00698,0.0,0.0*
1,1,.006,-.00698,0.0*
20,1,.006,-.00698,0.0,-.00716,.00165,0.0*
1,1,.006,-.00716,.00165*
20,1,.006,-.00716,.00165,-.00771,.00312,0.0*
1,1,.006,-.00771,.00312*
20,1,.006,-.00771,.00312,-.00845,.00422,0.0*
1,1,.006,-.00845,.00422*
20,1,.006,-.00845,.00422,-.00955,.00514,0.0*
1,1,.006,-.00955,.00514*
20,1,.006,-.00955,.00514,-.01102,.00551,0.0*
1,1,.006,-.01102,.00551*
1,1,.006,-.00348,-.00092*
20,1,.006,-.00348,-.00092,-.00219,.00037,0.0*
1,1,.006,-.00219,.00037*
20,1,.006,-.00219,.00037,-.00109,.0011,0.0*
1,1,.006,-.00109,.0011*
20,1,.006,-.00109,.0011,.00038,.00147,0.0*
1,1,.006,.00038,.00147*
20,1,.006,.00038,.00147,.00166,.0011,0.0*
1,1,.006,.00166,.0011*
20,1,.006,.00166,.0011,.00258,.00037,0.0*
1,1,.006,.00258,.00037*
20,1,.006,.00258,.00037,.00332,-.00073,0.0*
1,1,.006,.00332,-.00073*
20,1,.006,.00332,-.00073,.0035,-.00202,0.0*
1,1,.006,.0035,-.00202*
20,1,.006,.0035,-.00202,.00332,-.00312,0.0*
1,1,.006,.00332,-.00312*
20,1,.006,.00332,-.00312,.00258,-.00422,0.0*
1,1,.006,.00258,-.00422*
20,1,.006,.00258,-.00422,.00148,-.00514,0.0*
1,1,.006,.00148,-.00514*
20,1,.006,.00148,-.00514,.00019,-.00551,0.0*
1,1,.006,.00019,-.00551*
20,1,.006,.00019,-.00551,-.00128,-.00514,0.0*
1,1,.006,-.00128,-.00514*
20,1,.006,-.00128,-.00514,-.00256,-.00404,0.0*
1,1,.006,-.00256,-.00404*
20,1,.006,-.00256,-.00404,-.0033,-.00239,0.0*
1,1,.006,-.0033,-.00239*
20,1,.006,-.0033,-.00239,-.00348,-.00055,0.0*
1,1,.006,-.00348,-.00055*
20,1,.006,-.00348,-.00055,-.00311,.00184,0.0*
1,1,.006,-.00311,.00184*
20,1,.006,-.00311,.00184,-.00256,.00312,0.0*
1,1,.006,-.00256,.00312*
20,1,.006,-.00256,.00312,-.00164,.00441,0.0*
1,1,.006,-.00164,.00441*
20,1,.006,-.00164,.00441,-.00036,.00533,0.0*
1,1,.006,-.00036,.00533*
20,1,.006,-.00036,.00533,.00093,.00551,0.0*
1,1,.006,.00093,.00551*
20,1,.006,.00093,.00551,.00221,.00514,0.0*
1,1,.006,.00221,.00514*
20,1,.006,.00221,.00514,.00313,.00422,0.0*
1,1,.006,.00313,.00422*
1,1,.006,.01067,-.00551*
20,1,.006,.01067,-.00551,.01104,-.00312,0.0*
1,1,.006,.01104,-.00312*
20,1,.006,.01104,-.00312,.01159,-.0011,0.0*
1,1,.006,.01159,-.0011*
20,1,.006,.01159,-.0011,.01233,.00073,0.0*
1,1,.006,.01233,.00073*
20,1,.006,.01233,.00073,.01324,.00275,0.0*
1,1,.006,.01324,.00275*
20,1,.006,.01324,.00275,.01471,.00551,0.0*
1,1,.006,.01471,.00551*
20,1,.006,.01471,.00551,.00737,.00551,0.0*
1,1,.006,.00737,.00551*
%
%ADD10MACRO10*%
%ADD32C,.006*%
G75*
%LPD*%
G75*
G36*
G01X1170840Y746907D02*
X1171641D01*
Y746905D01*
X1173741D01*
Y686605D01*
X1178741Y666605D01*
X1188741D01*
X1193741Y686605D01*
Y746529D01*
X1195641D01*
X1196610D01*
Y836529D01*
X1196601Y851251D01*
X1193404Y845465D01*
X1188741Y836605D01*
X1173741Y846605D01*
X1173630Y846690D01*
X1171874Y847876D01*
X1171846Y847894D01*
X1170840Y848501D01*
Y746907D01*
G37*
G54D10*
X-56709Y43008D03*
X-61709Y56192D03*
X-51709D03*
X-61100Y250316D03*
X-56100Y263500D03*
X-61000Y382816D03*
X-56000Y396000D03*
X-51100Y250316D03*
X-51000Y382816D03*
X-30000Y43000D03*
X-35000Y56184D03*
X-25000D03*
X-25100Y250316D03*
X-35100D03*
X-30100Y263500D03*
X-36000Y418816D03*
X-26000D03*
X-31000Y432000D03*
X768750Y133175D03*
G54D11*
X0Y-100000D03*
G54D20*
X63898Y24764D03*
X73898D03*
X90472D03*
X100472D03*
X117047D03*
X127047D03*
X211142D03*
X221142D03*
X237717D03*
X247717D03*
X768750Y189875D03*
Y218225D03*
G54D30*
X372604Y-455313D03*
Y-430313D03*
X372664Y-223791D03*
Y-198791D03*
X372576Y-177041D03*
Y-152041D03*
X372664Y4481D03*
Y29481D03*
X372604Y51231D03*
Y76231D03*
X372664Y373753D03*
Y398753D03*
X393692Y-481375D03*
X382604Y-455313D03*
X393692Y-456375D03*
X382604Y-430313D03*
X382664Y-223791D03*
Y-198791D03*
X382576Y-177041D03*
Y-152041D03*
X393780Y-128853D03*
Y-103853D03*
X393750Y-82222D03*
Y-57222D03*
X382664Y4481D03*
Y29481D03*
X382604Y51231D03*
Y76231D03*
X393750Y200538D03*
Y225538D03*
Y247050D03*
Y272050D03*
X382664Y373753D03*
X393750Y398810D03*
X382664Y398753D03*
X393750Y423810D03*
X403692Y-481375D03*
Y-456375D03*
X403780Y-128853D03*
Y-103853D03*
X403750Y-82222D03*
D03*
Y-57222D03*
D03*
Y200538D03*
D03*
Y225538D03*
D03*
Y247050D03*
D03*
Y272050D03*
D03*
Y398810D03*
D03*
Y423810D03*
D03*
X413750Y-82222D03*
Y-57222D03*
Y200538D03*
Y225538D03*
Y247050D03*
Y272050D03*
Y398810D03*
Y423810D03*
X768750Y-65275D03*
G54D21*
X65945Y297776D03*
X768750Y-93625D03*
G54D12*
X0Y0D03*
G54D13*
X3000Y8494D03*
Y28494D03*
Y48494D03*
Y68494D03*
Y88494D03*
Y108494D03*
Y128494D03*
Y148494D03*
Y168494D03*
Y188494D03*
Y208494D03*
Y228494D03*
Y248494D03*
Y268494D03*
Y288494D03*
Y308494D03*
Y342126D03*
Y362126D03*
Y382126D03*
Y402126D03*
Y422126D03*
Y442126D03*
X9407Y10554D03*
X12900Y105500D03*
X19200Y102700D03*
X12500Y102000D03*
X16626Y195848D03*
X19129D03*
Y193048D03*
X16626D03*
X19129Y204248D03*
X17000Y208017D03*
Y211541D03*
X16626Y198648D03*
Y201448D03*
X19129Y198648D03*
Y201448D03*
X16626Y204248D03*
X17000Y215713D03*
Y219288D03*
X15922Y224568D03*
Y227168D03*
X18422Y224568D03*
Y227168D03*
X18000Y240900D03*
Y237900D03*
Y249900D03*
Y246900D03*
Y243900D03*
X15688Y259063D03*
X13736Y299891D03*
X6200Y312900D03*
X8300Y314700D03*
X13736Y303280D03*
X13827Y325310D03*
X13869Y352239D03*
X14000Y401700D03*
Y406700D03*
Y404200D03*
X17700Y427600D03*
X14600Y422500D03*
X14700Y425000D03*
X22218Y3000D03*
X27323Y25842D03*
X23723Y123791D03*
Y120791D03*
X32223Y123791D03*
Y120791D03*
X25200Y116300D03*
X31890Y110400D03*
X23736Y127758D03*
Y130758D03*
X32236Y127758D03*
Y130758D03*
X31920Y186610D03*
X21250Y206220D03*
X21000Y227000D03*
Y224500D03*
X21135Y236587D03*
X21205Y232767D03*
X21135Y240667D03*
Y243737D03*
X24690Y246467D03*
Y251967D03*
X21135Y246837D03*
X21035Y249937D03*
X24690Y249267D03*
X22237Y301237D03*
X30638Y301213D03*
X22237Y311481D03*
Y308592D03*
X30638Y309068D03*
X30700Y315500D03*
X25811Y319400D03*
X32000Y326300D03*
X23535Y329990D03*
X23810Y322534D03*
X31300Y329900D03*
X31000Y342500D03*
X34300Y375000D03*
X26300Y374400D03*
X31600Y379600D03*
X33100Y392100D03*
X32700Y395381D03*
X20600Y428900D03*
X25202Y425329D03*
X29400Y430900D03*
X23677Y422419D03*
X32100Y432800D03*
X20225Y447671D03*
X22692Y466518D03*
X42218Y3000D03*
X35044Y35751D03*
X45500Y41500D03*
X43926Y62248D03*
X35304Y58317D03*
X45500Y92500D03*
X45276Y98488D03*
X40340Y100710D03*
X45001Y95144D03*
X40723Y123791D03*
Y120791D03*
X49223Y123791D03*
Y121291D03*
X38300Y109200D03*
X48500Y112559D03*
X40736Y127758D03*
Y130758D03*
X49236Y127758D03*
Y130758D03*
X36599Y189016D03*
X37360Y194050D03*
X37823Y198346D03*
X47714Y212227D03*
X47948Y201000D03*
X39493Y222932D03*
X41993D03*
X44149Y227332D03*
X39493Y220332D03*
X41993D03*
X44149Y224732D03*
X48059Y214825D03*
X48023Y217860D03*
X39800Y213800D03*
X35700Y218000D03*
X40500Y236900D03*
X35600Y241200D03*
Y238200D03*
X41574Y255937D03*
X46220Y277170D03*
X47440Y301336D03*
Y308691D03*
X39039Y309044D03*
X47440Y312080D03*
X39039Y304278D03*
X43500Y317100D03*
X48420Y321616D03*
X44200Y332000D03*
X44525Y324000D03*
X39100Y321600D03*
X35500Y340500D03*
Y335000D03*
X44220Y341008D03*
X44500Y344000D03*
Y355500D03*
X37400Y359900D03*
X44500Y348000D03*
X44525Y360000D03*
X35100Y352400D03*
X44500Y351600D03*
X38200Y364855D03*
X35900Y363025D03*
X37800Y371225D03*
X44525Y364000D03*
Y368000D03*
X37300Y375000D03*
X44525Y376000D03*
X37875Y377925D03*
X44525Y387800D03*
X37735Y391200D03*
X44525Y391650D03*
X35101Y381610D03*
X44525Y384000D03*
X47075Y391730D03*
X44500Y380000D03*
X44490Y397850D03*
X44525Y394150D03*
X36911Y394915D03*
X37067Y398337D03*
X44341Y406480D03*
X44330Y401450D03*
X36600Y408600D03*
X39530Y409100D03*
X42900Y412900D03*
X41200Y429100D03*
X43600Y422800D03*
X42200Y435900D03*
X48050Y436350D03*
X46100Y422800D03*
X40848Y448440D03*
X62218Y3000D03*
X54200Y25400D03*
X53000Y41500D03*
X58976Y36402D03*
X53600Y44100D03*
X56348Y36210D03*
X59425Y53075D03*
X50508Y57459D03*
X50710Y54724D03*
X57500Y75500D03*
X60000D03*
X55000Y76000D03*
X63086Y65762D03*
X52120Y78373D03*
X59240Y67242D03*
X52502Y80978D03*
X53434Y106562D03*
X53400Y102788D03*
X52155Y121218D03*
X60112Y113992D03*
X53267Y109094D03*
X59945Y120630D03*
X60411Y130200D03*
X52237Y129522D03*
X61123Y133070D03*
X52876Y195712D03*
X52410Y190190D03*
X57141Y209341D03*
X59900Y199900D03*
X52050Y208760D03*
X64050Y201010D03*
X58823Y213531D03*
X52000Y230400D03*
X63300Y237600D03*
X51600Y241200D03*
X59850Y235830D03*
X51010Y233570D03*
X49700Y242900D03*
X50567Y238630D03*
X50700Y250400D03*
X62500Y272500D03*
X58654Y290605D03*
X58900Y288075D03*
X54660Y311660D03*
X60561Y314843D03*
X60613Y312012D03*
X64230Y303210D03*
X56600Y320500D03*
Y324300D03*
X63000Y324100D03*
X56600Y318000D03*
X52820Y325200D03*
X60225Y336099D03*
X57400Y345400D03*
X52900Y360000D03*
X52600Y376600D03*
X58035Y370100D03*
X54400Y374700D03*
X55294Y369729D03*
X52475Y364000D03*
X52765Y390200D03*
X59500Y394000D03*
X58620Y408779D03*
X63200Y408600D03*
X52330Y413350D03*
X59097Y433502D03*
X57470Y426544D03*
X51535D03*
X59511Y424477D03*
X60622Y431273D03*
X64122D03*
X56250Y424200D03*
X52750D03*
X56482Y450344D03*
X62600Y450700D03*
X54100Y448600D03*
X56500Y447600D03*
X63563Y460100D03*
X56476D03*
X56482Y456844D03*
Y453344D03*
X63569Y456844D03*
Y453344D03*
X76500Y66500D03*
X65928Y76500D03*
X68500Y66500D03*
X75280Y75704D03*
X72500Y66500D03*
X74757Y89745D03*
Y92745D03*
Y86745D03*
X66830Y122329D03*
X72044Y132312D03*
X71970Y135893D03*
X69195Y135799D03*
X69285Y132321D03*
X67126Y128100D03*
X66874Y130590D03*
X68335Y141369D03*
X68375Y144100D03*
X68434Y149506D03*
X68432Y152147D03*
X70580Y167179D03*
X72300Y159400D03*
X68600Y159160D03*
X76442Y166907D03*
X73550Y166680D03*
X67330Y169267D03*
X68960Y173300D03*
X75284Y180800D03*
X65301Y187762D03*
X67486Y186414D03*
X75300Y183875D03*
X71146Y186489D03*
X71370Y188993D03*
X67386Y191935D03*
X67486Y188977D03*
X74046Y186490D03*
X71600Y200900D03*
X72150Y204810D03*
X76670Y208772D03*
X75000Y214000D03*
X72500D03*
X70453Y222900D03*
X72000Y235925D03*
X70900Y241500D03*
X71100Y233575D03*
X67700Y229725D03*
X65801Y253145D03*
X68990Y257000D03*
X77010Y256645D03*
X65755Y256045D03*
X73011Y246365D03*
X77384Y253769D03*
X68800Y253300D03*
X65800Y260875D03*
X76500Y270700D03*
X74000Y270800D03*
X68990Y260465D03*
X76284Y280470D03*
X77900Y274700D03*
X70000Y280000D03*
X78600Y283970D03*
X75960Y284049D03*
X65100Y282475D03*
X72700Y301200D03*
X75870Y290700D03*
X78770Y290708D03*
X75300Y305150D03*
X69500Y308700D03*
X64567Y306665D03*
X73400Y313700D03*
X73000Y323400D03*
X68500Y325100D03*
X76900Y323000D03*
X76500Y325500D03*
X78700Y340000D03*
X71000Y394400D03*
X67900Y400525D03*
X69057Y419700D03*
X77860Y408678D03*
X77592Y413437D03*
X66319Y413492D03*
X67000Y408800D03*
X69700D03*
X78800Y423800D03*
X66297Y433002D03*
X71035Y426543D03*
X76770D03*
X69030Y422653D03*
X68100Y425400D03*
X71200Y431700D03*
X72150Y424199D03*
X75650D03*
X77600Y431400D03*
X79010Y445750D03*
X72800Y437900D03*
X70650Y460100D03*
X77500D03*
X82218Y3000D03*
X91700Y66500D03*
X86500Y75000D03*
X88000Y66500D03*
X84500D03*
X90151Y68985D03*
X91358Y89745D03*
Y92745D03*
Y86745D03*
X86700Y119100D03*
X92500Y116200D03*
X89256Y135056D03*
X86100Y153340D03*
X89170Y141540D03*
X89200Y138800D03*
X86100Y155840D03*
X83410Y161020D03*
X86100Y158390D03*
X83520Y158520D03*
X81800Y188500D03*
X80788Y190812D03*
X82370Y197010D03*
X90900Y222850D03*
X81600Y241500D03*
X91300Y252900D03*
X80300Y243700D03*
X80270Y247830D03*
X84000Y261375D03*
X90800Y258225D03*
X83500Y266900D03*
X84016Y258230D03*
X91500Y267000D03*
X85672Y283985D03*
X81864Y297900D03*
X85600Y298100D03*
X90923Y293520D03*
X82200Y308700D03*
X82022Y303350D03*
X84126Y311790D03*
X79600Y312000D03*
X85500Y323400D03*
Y326700D03*
X93288Y330289D03*
X85600Y335000D03*
X81900Y337100D03*
X81700Y342600D03*
X86300Y397600D03*
X90500D03*
X82500D03*
X89487Y408435D03*
X87600Y414500D03*
X87800Y410300D03*
X84801Y409760D03*
X92500Y408630D03*
X86481Y407871D03*
X81552Y409660D03*
X93259Y424200D03*
X88565Y426535D03*
X79600Y426400D03*
X92001Y450402D03*
X82256Y445577D03*
X85276Y445550D03*
X81990Y448085D03*
X85490D03*
X92870Y437831D03*
X89700Y437900D03*
X84823Y460100D03*
X91909Y458275D03*
X92801Y452793D03*
X102218Y3000D03*
X107000Y44500D03*
X104575Y62369D03*
X102190Y63225D03*
X104600Y50501D03*
X104575Y67581D03*
X95400Y66500D03*
X98000Y75500D03*
X98500Y66500D03*
X102190Y66725D03*
X107124Y71004D03*
X108800Y91900D03*
X104425Y82500D03*
X106000Y91900D03*
X108727Y99153D03*
X100000Y98500D03*
X105916Y109952D03*
X100360Y116500D03*
X101230Y127010D03*
X96400Y137475D03*
X102999Y131799D03*
X108270Y138630D03*
X95950Y152900D03*
X95944Y149687D03*
X103500Y240619D03*
X95300Y247100D03*
X97177Y263320D03*
X102600Y267000D03*
X107200Y265000D03*
X106800Y262076D03*
X97440Y283590D03*
X106100Y282900D03*
X100700Y293600D03*
X108551Y294241D03*
X99990Y311200D03*
X105000Y311900D03*
X105100Y309300D03*
X94400Y311100D03*
Y307200D03*
X96457Y323194D03*
X105755Y327719D03*
X103000Y323800D03*
X95060Y327625D03*
X106852Y323292D03*
X97800Y325700D03*
X97608Y335534D03*
X99026Y338368D03*
X103180Y336286D03*
X108108Y395100D03*
X103400Y420000D03*
X95280Y412500D03*
X98100Y412400D03*
X105500Y418200D03*
X100457Y409100D03*
X98300Y407600D03*
X108500Y408680D03*
X104112Y422946D03*
X95845Y424755D03*
X97156Y450437D03*
X94560Y443287D03*
X100225Y443127D03*
X106700Y447730D03*
X95770Y437920D03*
X95870Y445483D03*
X99370D03*
X103900Y447640D03*
X98996Y458275D03*
X106083D03*
X96301Y452793D03*
X122218Y3000D03*
X111000Y44600D03*
X119000D03*
X115000Y44500D03*
X122500Y58000D03*
X118500Y75500D03*
X116500Y74000D03*
X109121Y69500D03*
X119700Y89200D03*
X116560Y88651D03*
X123710Y82300D03*
X123740Y79791D03*
X115025Y104800D03*
X120726Y105000D03*
X115200Y98200D03*
X120724Y108937D03*
X120626Y123500D03*
X112000D03*
X116200Y115100D03*
X109350Y115501D03*
X109200Y118500D03*
Y128500D03*
X118990Y131580D03*
X109670Y136060D03*
X118692Y137304D03*
X120800Y147200D03*
X117800D03*
X113000Y160700D03*
X115400Y159500D03*
X113000Y158000D03*
X122156Y157844D03*
X122900Y170100D03*
X123120Y213088D03*
X119060Y199695D03*
X123790Y227656D03*
X118300Y237500D03*
X123690Y230156D03*
X122876Y242800D03*
X117840Y242200D03*
X112200Y234520D03*
X116143Y230790D03*
X111400Y254680D03*
X122876Y245300D03*
X120020Y254430D03*
X119105Y251511D03*
X121720Y265330D03*
X117400Y266500D03*
X109800Y264928D03*
X111100Y273700D03*
X120070D03*
X115000D03*
X111177Y293471D03*
X120600D03*
X110565Y296331D03*
X118009Y313810D03*
Y311200D03*
X115535Y335235D03*
X115600Y337900D03*
X114700Y351200D03*
X121200Y359200D03*
X111330Y357800D03*
X120200Y361600D03*
X114700Y348500D03*
X111460Y361770D03*
X115000Y369500D03*
X111869Y365454D03*
X121175Y385125D03*
X110900Y378500D03*
X123100Y390600D03*
X119200Y406175D03*
X122600Y394600D03*
X119026Y393332D03*
X119791Y412301D03*
X113000Y416200D03*
X119500Y433600D03*
X111510Y434710D03*
X121700Y424005D03*
X123170Y433200D03*
X127900Y45000D03*
X129575Y57375D03*
X126425Y57000D03*
X133000Y59900D03*
X130500Y74700D03*
X129300Y82650D03*
X131470Y81260D03*
X129500Y91475D03*
X129328Y122500D03*
X126575Y111416D03*
X131528Y114271D03*
X135500Y138000D03*
Y135000D03*
X134400Y127652D03*
X131700Y131000D03*
X132828Y138400D03*
X133500Y146800D03*
X138458Y146458D03*
X133500Y149385D03*
X124500Y167100D03*
X126500Y158000D03*
X133690Y158100D03*
X136190D03*
X126300Y176575D03*
X126500Y174000D03*
X137900Y179160D03*
X125700Y183700D03*
X135000Y206900D03*
X124338Y204742D03*
X124779Y201633D03*
X126153Y199079D03*
X135000Y221200D03*
X132500Y221900D03*
X138100Y213600D03*
X124226Y225194D03*
X134358Y230069D03*
X130167Y234733D03*
X128900Y255898D03*
X133000Y256100D03*
X128760Y265726D03*
X127600Y259700D03*
X131216Y280187D03*
X135315Y279813D03*
X125100Y273720D03*
X128760Y273701D03*
X137083Y278045D03*
X137196Y274491D03*
X132420Y273811D03*
X138600Y295900D03*
X124016Y313784D03*
X135462Y313727D03*
X124100Y311100D03*
X129800Y325800D03*
X138590Y345710D03*
X124400Y345300D03*
X125910Y335006D03*
X125900Y337600D03*
X133300Y334100D03*
X136000Y341000D03*
X133100Y358900D03*
X133000Y361500D03*
X132600Y350090D03*
X124350Y352450D03*
X129776Y374500D03*
X138700Y376600D03*
X133640Y390524D03*
X126340Y382700D03*
X125174Y393916D03*
X124287Y406262D03*
X127300Y392600D03*
X135300Y399900D03*
X137900Y399500D03*
X131540Y394690D03*
X132700Y402700D03*
X129900Y415583D03*
X133500Y409110D03*
X133070Y420874D03*
X134300Y416414D03*
X136230Y423935D03*
X124500Y424005D03*
X132070Y433110D03*
X133572Y423935D03*
X125930Y433110D03*
X138750Y451500D03*
X138500Y457250D03*
X138750Y454500D03*
X142218Y3000D03*
X147947Y9800D03*
X146800Y79000D03*
X140869Y89055D03*
X145000Y90700D03*
X142400Y91300D03*
X141100Y86500D03*
X141700Y96929D03*
X140869Y104803D03*
Y120551D03*
Y112677D03*
X148819Y123197D03*
X143400Y121700D03*
X141220Y123070D03*
X147600Y117000D03*
X151800Y116500D03*
X152800Y111600D03*
X148819Y125697D03*
X149800Y138100D03*
X145185Y134214D03*
X142892Y136645D03*
X142000Y146000D03*
X143269Y150456D03*
X150155Y145086D03*
X152556Y147683D03*
X148400Y155765D03*
X146300Y161010D03*
X153134Y178572D03*
X140554Y168887D03*
X153200Y170990D03*
X140554Y171688D03*
X150619Y178646D03*
X145296Y188835D03*
X140830Y192530D03*
X153051Y187354D03*
X150005Y184973D03*
X149100Y189963D03*
X144280Y195130D03*
X151940Y203710D03*
X151900Y213200D03*
X143980Y199674D03*
X147800Y200789D03*
X140903Y199421D03*
X152500Y199500D03*
X146390Y224040D03*
X146000Y216350D03*
X141954Y224274D03*
X142300Y216300D03*
X145500Y227700D03*
X153100Y234800D03*
X142085Y230549D03*
X151040Y237870D03*
X145580Y248082D03*
X141280Y256310D03*
X142780Y266830D03*
X149215Y267745D03*
X152400Y284400D03*
X150240Y277940D03*
X152400Y293400D03*
X152500Y289425D03*
X150293Y302117D03*
X147500Y289405D03*
X150293Y315493D03*
X151320Y322700D03*
X142500Y345800D03*
X148600Y336300D03*
X142202Y334000D03*
X142300Y336700D03*
X144800D03*
X144700Y334100D03*
X153419Y341978D03*
X143945Y354146D03*
X148316Y359086D03*
X141045Y355309D03*
X150900Y360325D03*
X151695Y357900D03*
X149500Y356700D03*
X141000Y358500D03*
X140700Y370252D03*
X139200Y372510D03*
X149000Y383070D03*
X152100Y378400D03*
X143300Y396400D03*
X140300Y395100D03*
X141520Y399700D03*
X139400Y392460D03*
X151265Y399500D03*
X142511Y393690D03*
X146600Y410600D03*
X153079Y412000D03*
X149600Y410500D03*
X139700Y415100D03*
X150000Y414750D03*
X143000Y414600D03*
X140600Y412300D03*
X152100Y425700D03*
X145365Y426050D03*
X148060Y423500D03*
X148100Y433400D03*
X152200Y423100D03*
X148041Y426700D03*
X138987Y423935D03*
X151398Y449930D03*
X149041Y458750D03*
X162218Y3000D03*
X165700Y11100D03*
X166719Y75874D03*
X158246Y78872D03*
X168297Y93976D03*
X164429Y93991D03*
X158873Y93976D03*
X166500Y96400D03*
X163423Y96281D03*
X159923D03*
X166200Y105500D03*
X158420Y116610D03*
X159700Y112000D03*
X155530Y116640D03*
X156200Y111600D03*
X162657Y117297D03*
X154050Y137100D03*
X159000Y135000D03*
X166700Y132360D03*
X156406Y129203D03*
X162419Y131032D03*
X155325Y139440D03*
X153954Y145086D03*
X161900Y150500D03*
X165690Y149622D03*
X156481Y155933D03*
X162200Y158200D03*
X159900Y155600D03*
X161240Y177820D03*
X161237Y181735D03*
Y185815D03*
X161240Y190477D03*
X166361Y209794D03*
X156467Y203500D03*
X162594Y212585D03*
Y210085D03*
X166140Y205955D03*
X165381Y201274D03*
X166308Y225189D03*
X153744Y217435D03*
X153800Y214900D03*
X162653Y218843D03*
X159643Y226484D03*
X162200Y221376D03*
X167200Y222600D03*
X155800Y234700D03*
X161200Y233600D03*
X165500Y236100D03*
X157200Y240000D03*
X156970Y255000D03*
X165013Y254986D03*
X160973D03*
X164500Y266000D03*
X163690Y268610D03*
X160590Y263300D03*
X156970Y263250D03*
X164800Y263300D03*
X158750Y284949D03*
X168392Y298493D03*
X168300Y301100D03*
X162100Y291600D03*
X161400Y307600D03*
X162160Y313560D03*
X164500Y314800D03*
X155000Y321100D03*
X164790Y341100D03*
X168557Y341221D03*
X158459Y340898D03*
X158467Y344067D03*
X163800Y356800D03*
X161300Y354600D03*
X164318Y389102D03*
X157282D03*
X156900Y385700D03*
X154500Y387350D03*
X159050Y387334D03*
X162550D03*
X165500Y386000D03*
X155452Y401000D03*
X154000Y414750D03*
X160540Y416912D03*
X165194Y428688D03*
X157294Y435623D03*
X167008Y430718D03*
X167865Y427771D03*
X163700Y422119D03*
X159396Y449408D03*
X160700Y445550D03*
X158100Y442700D03*
X160852Y460118D03*
X168029Y456660D03*
X157500Y453390D03*
X182218Y3000D03*
X176900Y14625D03*
X178200Y76145D03*
X175700Y76245D03*
X173853Y93991D03*
X182925Y84300D03*
X179900Y91300D03*
X181960Y99260D03*
X169700Y102250D03*
X176300Y98700D03*
X172847Y96281D03*
X169347D03*
X180333Y114292D03*
X179500Y116800D03*
X182000Y117200D03*
X171600Y114000D03*
X182865Y113706D03*
X174600Y114000D03*
X169100Y113900D03*
X182103Y132294D03*
X170867Y128211D03*
X178290Y128824D03*
X176550Y125210D03*
X178284Y132394D03*
X170610Y131900D03*
X174436Y132394D03*
X168800Y126800D03*
X172100Y146300D03*
X176000Y140500D03*
X172890Y153260D03*
X171700Y156900D03*
X169500Y180200D03*
X170800Y193100D03*
X172621Y208300D03*
X173800Y225400D03*
X170400Y214700D03*
X172400Y220700D03*
X175300Y240000D03*
X174400Y249136D03*
Y254736D03*
X179846Y255150D03*
X176900Y270100D03*
X174292Y263300D03*
X171592Y263312D03*
X168710Y272256D03*
X172977Y277000D03*
X182435Y281797D03*
X179217Y278528D03*
X168656Y275156D03*
X181194Y294074D03*
X182232Y296424D03*
X173880Y312430D03*
X174232Y304333D03*
X176563Y310917D03*
X176533Y314049D03*
X170550Y304050D03*
X169077Y308677D03*
X170561Y306631D03*
X182372Y325961D03*
X181050Y332250D03*
X171098Y341224D03*
X182700Y342216D03*
X169200Y349400D03*
X180600Y360200D03*
X180350Y368650D03*
X177500Y369100D03*
X177082Y387402D03*
X178850Y385634D03*
X182350D03*
X169669Y399419D03*
X172550Y398690D03*
X172530Y420950D03*
X182750Y426750D03*
X172530Y429470D03*
X171400Y450600D03*
X189400Y69600D03*
X187272Y84472D03*
X191312Y84512D03*
X190200Y100500D03*
X198281Y101286D03*
X184800Y100300D03*
X187700Y99000D03*
X187400Y101500D03*
X190800Y117200D03*
X193096Y115600D03*
X190744Y114456D03*
X187069Y116800D03*
X184729Y115820D03*
X187360Y132425D03*
X195983Y132294D03*
X191482Y129294D03*
X186200Y125600D03*
X184000Y140500D03*
X196577Y141185D03*
X189700Y140400D03*
X196827Y240349D03*
X191693Y236370D03*
X185897Y249936D03*
X196240Y253430D03*
X193084Y257400D03*
X194567Y255288D03*
X187400Y255700D03*
X191583Y261363D03*
X190900Y271700D03*
X193386Y269142D03*
X184200Y264900D03*
X185000Y270700D03*
X189228Y280655D03*
X195370Y273297D03*
X183625Y273500D03*
X196200Y278200D03*
X196100Y281820D03*
X187623Y297475D03*
X196443Y294065D03*
X185725Y307320D03*
X192448Y308314D03*
X195031Y307182D03*
X194600Y313300D03*
X197853Y307200D03*
X197155Y314223D03*
X190465Y344426D03*
X190600Y337900D03*
X183800Y345400D03*
X197775Y346617D03*
X194800Y341700D03*
X191408Y357451D03*
X197450Y356560D03*
X190922Y350990D03*
X196050Y358770D03*
X191420Y354710D03*
X190965Y348090D03*
X197711Y349250D03*
X195000Y373900D03*
X197400Y367600D03*
Y370250D03*
X184118Y387402D03*
X197620Y385425D03*
X190050Y389140D03*
X190100Y392270D03*
X191843Y403995D03*
X189054Y397500D03*
X194500Y402600D03*
X185875Y415051D03*
X185245Y417500D03*
X190270Y409962D03*
X189762Y429177D03*
X189766Y432050D03*
X189838Y434910D03*
X186300Y448700D03*
X185000Y451500D03*
X189600Y459800D03*
X185000Y454000D03*
Y456500D03*
X191780Y453300D03*
Y456700D03*
X202218Y3000D03*
X207700Y59100D03*
X204300Y60600D03*
X201500Y61000D03*
X209142Y53664D03*
X213100Y69300D03*
X209500Y92326D03*
X211800Y93870D03*
X201900Y83300D03*
X209824Y106122D03*
X203600Y117000D03*
X199940Y117500D03*
X211370Y117000D03*
X208200Y111760D03*
X203970Y125500D03*
X199985Y132294D03*
X212757Y127064D03*
X212727Y129654D03*
X208627Y132394D03*
X208576Y128957D03*
X204120Y132294D03*
X200000Y128764D03*
X208500Y126057D03*
X212727Y132154D03*
X211200Y140513D03*
X205598Y140480D03*
X203542Y213254D03*
X206200Y255385D03*
X198990Y247811D03*
X200680Y257540D03*
X206051Y247911D03*
X211265Y267300D03*
X205500Y258300D03*
X201100Y265120D03*
X201000Y262500D03*
X203090Y269229D03*
X205590Y269129D03*
X205130Y282000D03*
X204258Y286691D03*
X213258Y273265D03*
X207220Y301180D03*
X204560Y301130D03*
X212911Y293869D03*
X206430Y298780D03*
X199729Y314565D03*
X198672Y318175D03*
X208628Y324665D03*
X200300Y328800D03*
X207750Y366500D03*
X208000Y373240D03*
X200222Y398150D03*
X213200Y399166D03*
X199880Y402846D03*
X203180Y416371D03*
X207539Y408686D03*
X200000Y407040D03*
X207278Y416022D03*
X198600Y426600D03*
X202513Y434800D03*
X198405D03*
X211865Y444520D03*
X199000Y444500D03*
X205200Y445400D03*
X213225Y442220D03*
X200000Y455800D03*
X209300Y457700D03*
X222218Y3000D03*
X214306Y62233D03*
X219600Y74000D03*
X215800Y69300D03*
X218600D03*
Y92100D03*
X221300D03*
X224330Y83210D03*
X224958Y107236D03*
X219900Y101300D03*
X222890Y101240D03*
X215294Y117094D03*
X226887Y117297D03*
X223300Y117400D03*
X221500Y125100D03*
X225284Y132294D03*
Y129294D03*
X217262Y132294D03*
X221278D03*
X225300Y125200D03*
X227700Y151900D03*
X221000Y243000D03*
X220100Y237200D03*
X223800Y254800D03*
X227316Y256700D03*
X215100Y244100D03*
X215500Y247111D03*
X216800Y255550D03*
X215510Y253310D03*
X225275Y246000D03*
X217500Y264000D03*
X219900Y267100D03*
X227232Y270539D03*
X222833Y261668D03*
X225441Y282267D03*
X219722Y286728D03*
X227841Y275773D03*
X219339Y284138D03*
X219359Y281580D03*
X226500Y273000D03*
X223672Y290735D03*
X223646Y293960D03*
X215600Y316800D03*
X213610Y308800D03*
X214400Y303997D03*
X226100Y325065D03*
X217300Y322800D03*
X225867Y345033D03*
X225650Y337520D03*
X221000Y343800D03*
X216405Y335970D03*
X214175Y333740D03*
X221000Y352000D03*
X223160Y362600D03*
X224632Y369825D03*
X225700Y362500D03*
X213490Y373690D03*
X226710Y364815D03*
X223420Y367080D03*
X220515Y384900D03*
X217390Y401340D03*
X222986Y400323D03*
X222225Y407650D03*
X216725D03*
X219050Y418850D03*
X217725Y410150D03*
X221225D03*
X226830Y435170D03*
X225000Y433100D03*
X219250Y422150D03*
X213900Y436000D03*
X217100Y436100D03*
X218085Y444520D03*
X224000Y449100D03*
X216725Y442220D03*
X222200Y458700D03*
X215000Y458600D03*
X242218Y3000D03*
X233000Y47100D03*
X237000Y47200D03*
X230800Y57613D03*
X234537Y74638D03*
X239347Y79457D03*
X230600Y91700D03*
X239660Y91920D03*
X232150Y82480D03*
X237280Y107510D03*
X229000Y101000D03*
X240160Y107000D03*
X240710Y99570D03*
X232325Y101230D03*
X236648Y100739D03*
X242812Y117501D03*
X238900Y114800D03*
X234500Y117500D03*
X230293Y117417D03*
X239900Y117550D03*
X239206Y112300D03*
X242800Y132200D03*
X231100Y125600D03*
X233511Y132594D03*
X234900Y126100D03*
X229396Y132294D03*
X242195Y141003D03*
X230535Y244564D03*
X237700Y257387D03*
X237730Y248085D03*
X242690Y255300D03*
X230000Y255700D03*
X232773Y269532D03*
X232300Y261200D03*
X242940Y268500D03*
X233033Y266483D03*
X229630Y264404D03*
X242087Y271427D03*
X238531Y263081D03*
X231900Y272700D03*
X241188Y279347D03*
X242700Y306800D03*
X228800Y302700D03*
X240500Y316575D03*
X236688Y311217D03*
X238400Y304200D03*
X228800Y305500D03*
X235400Y303800D03*
X241400Y328100D03*
X242592Y330683D03*
X243010Y323400D03*
X230445Y325945D03*
X233468Y341046D03*
X235000Y335300D03*
X231689Y334896D03*
X233500Y346911D03*
Y343911D03*
X233300Y356890D03*
X231500Y352500D03*
X233650Y359628D03*
X233800Y354300D03*
X233600Y371500D03*
X230287Y373100D03*
X233800Y390118D03*
X228230Y390390D03*
X232470Y382280D03*
X233600Y377300D03*
X233790Y384490D03*
X239750Y394970D03*
X236670Y394550D03*
X236860Y407300D03*
X229900Y436600D03*
X236900Y440565D03*
X239500Y447750D03*
X235400Y451600D03*
X231250Y447000D03*
X235200Y449100D03*
X231400Y449500D03*
X241436Y445784D03*
X240200Y450650D03*
X228200Y459100D03*
X236221Y454400D03*
X240010Y456000D03*
X240210Y453400D03*
X231400Y452000D03*
X248359Y46559D03*
X252925Y54000D03*
X249475Y55812D03*
X248700Y75900D03*
X255750Y77350D03*
X246200Y74600D03*
X253000Y77500D03*
X250000Y73000D03*
X250900Y90900D03*
X255000Y82700D03*
X257800Y82800D03*
X256900Y87300D03*
X251200Y93800D03*
X254397Y103697D03*
X244987Y103528D03*
X251113Y102919D03*
X252300Y107664D03*
X245391Y99589D03*
X251900Y100100D03*
X255213Y106099D03*
X249988Y105792D03*
X246488D03*
X244208Y97302D03*
X247200Y117400D03*
X253100Y119900D03*
X245310Y113910D03*
X252374Y132159D03*
X245500Y127800D03*
X245520Y130600D03*
X251354Y152877D03*
X249300Y237600D03*
X247689Y247929D03*
X253110Y254909D03*
X252639Y247885D03*
X256700Y263800D03*
X255700Y260000D03*
X247470Y269990D03*
X253388Y273655D03*
X250288Y273581D03*
X251459Y286542D03*
Y283542D03*
X246200Y299700D03*
X246514Y294325D03*
Y296825D03*
X254355Y300577D03*
X247923Y316400D03*
X248900Y304900D03*
X247923Y319000D03*
X253320Y323327D03*
X243750Y369730D03*
X243700Y372730D03*
X244790Y375910D03*
X243410Y381323D03*
X248800Y385700D03*
X252350Y412850D03*
X257810Y435100D03*
X245300Y445800D03*
X246700Y451500D03*
X246500Y448500D03*
X243375Y448375D03*
X246700Y454100D03*
X262218Y3000D03*
X267022Y12166D03*
X269095Y34625D03*
X260970Y42441D03*
X259000Y47500D03*
X268500Y45500D03*
X268675Y74400D03*
X267168Y93768D03*
X260132D03*
X259894Y90072D03*
X263102Y91725D03*
X260050Y87026D03*
X259759Y103651D03*
X259500Y101100D03*
X265801Y106040D03*
X260970Y98600D03*
X258713Y106099D03*
X268435Y121476D03*
X271602Y121400D03*
X269561Y130987D03*
X271300Y132900D03*
X269493Y138604D03*
X260200Y132395D03*
X260388Y125001D03*
X263294Y153366D03*
X263030Y150846D03*
X268442Y153299D03*
X265942D03*
Y150799D03*
X268442D03*
X269004Y144450D03*
Y141950D03*
X269133Y164982D03*
X265226D03*
X268339Y222126D03*
X272300Y251000D03*
X258628Y247600D03*
X258475Y254872D03*
X267100Y265000D03*
X269016Y266991D03*
X259500Y263700D03*
X262730Y267600D03*
X258000Y266300D03*
X266600Y268700D03*
X262700Y265100D03*
X258000Y284900D03*
X266200Y300500D03*
X266250Y297900D03*
X266200Y294800D03*
X261500Y290440D03*
X266300Y307500D03*
X264265Y315817D03*
X262930Y325300D03*
X259420Y345930D03*
X271100Y346575D03*
X259420Y343230D03*
Y340630D03*
X265922Y354238D03*
X271990Y362360D03*
X272100Y396300D03*
X265320Y392290D03*
X265100Y395100D03*
X272400Y392400D03*
X265100Y424000D03*
X266300Y435900D03*
X271500Y446800D03*
X271710Y449840D03*
X266727Y443185D03*
X261700Y439700D03*
X265130Y440070D03*
X261100Y443500D03*
X269534Y459061D03*
X269561Y456044D03*
X282218Y3000D03*
X277000Y41982D03*
X282440Y51941D03*
X274219Y51641D03*
X277000Y51665D03*
X274500Y58000D03*
X279934Y51688D03*
X286000Y67975D03*
X279800Y72700D03*
X274400Y90019D03*
X273400Y92800D03*
X276400Y92300D03*
X287578Y84092D03*
X283500Y89500D03*
X278300Y95019D03*
X274760Y105140D03*
X275386Y102710D03*
X280910Y102880D03*
X279200Y114100D03*
X285250Y117250D03*
X274200Y109500D03*
X274500Y131629D03*
X279600Y131400D03*
X283500Y126000D03*
X275960Y126010D03*
X273450Y125050D03*
X280744Y142070D03*
X283248Y142046D03*
X280616Y150971D03*
X283616D03*
X287555Y142419D03*
X285899Y153542D03*
X283399D03*
X278155Y176085D03*
X279457Y171318D03*
X286000Y242100D03*
X279983Y235254D03*
X282483D03*
X283974Y251372D03*
X286800Y251400D03*
X276200Y251500D03*
X280082Y251328D03*
X280030Y267098D03*
Y264098D03*
X284357Y264027D03*
X285911Y269899D03*
X281889D03*
X287755Y287538D03*
X282911Y279569D03*
X281300Y308800D03*
X287050Y305850D03*
X276660Y316900D03*
X276155Y329999D03*
X273355Y330001D03*
X285860Y336131D03*
X277500Y348469D03*
X275520Y357910D03*
X277290Y355820D03*
X277572Y351198D03*
X276100Y375900D03*
X287725Y363473D03*
X287761Y366200D03*
X287500Y376900D03*
X276145Y366455D03*
X276100Y381500D03*
X284614Y387136D03*
X283664Y379236D03*
X273100Y381500D03*
X285191Y390840D03*
X287630Y389378D03*
X275700Y403500D03*
X277700Y406100D03*
X287476Y396680D03*
X281300Y419300D03*
X278200Y408700D03*
X287500Y416100D03*
X278409Y433722D03*
X276400Y431810D03*
X275100Y427682D03*
X274619Y424725D03*
X283622Y447155D03*
X275138Y451215D03*
X276632Y439502D03*
X283674Y449975D03*
X277563Y460028D03*
X283707Y459398D03*
X283715Y452769D03*
X302218Y3000D03*
X300600Y10591D03*
X288856Y12166D03*
X295402Y48051D03*
X290245Y46978D03*
X300425Y54516D03*
X290000Y67975D03*
X300070Y84000D03*
X300856Y104059D03*
X301151Y108649D03*
X294600Y106900D03*
X294800Y111800D03*
X298975Y118900D03*
X301000Y121016D03*
X295075Y119100D03*
X301936Y135797D03*
X294200Y128800D03*
X301000Y129900D03*
X290200Y129500D03*
X293693Y152232D03*
X290889Y152318D03*
X298005Y151118D03*
Y148618D03*
Y146118D03*
X292204Y142610D03*
X301936Y143897D03*
X301507Y195435D03*
X301120Y226421D03*
X296734Y216079D03*
X301120Y229810D03*
X290586Y234844D03*
X288086D03*
X301120Y235626D03*
Y238765D03*
X299138Y244513D03*
X302687Y275497D03*
X291500Y287670D03*
Y285170D03*
X298840Y279640D03*
X291300Y315900D03*
X296938Y325700D03*
X301500Y326500D03*
X290000Y335600D03*
X300700Y341300D03*
X295500Y354920D03*
X296780Y371500D03*
X298748Y390118D03*
X297399Y397382D03*
X290800Y438300D03*
X291623Y447747D03*
X291703Y450819D03*
X291689Y453912D03*
Y456912D03*
Y459912D03*
X295729Y453912D03*
Y456912D03*
Y459912D03*
X297738Y452418D03*
Y458418D03*
Y455418D03*
X313977Y33400D03*
X303575Y54516D03*
X316025Y60200D03*
X309570Y84000D03*
X316066Y108407D03*
X307400Y122300D03*
X304436Y135897D03*
X307500Y125635D03*
X315900Y125900D03*
X313800Y124300D03*
X307560Y128500D03*
X305936Y143897D03*
X309936D03*
X313936D03*
X307487Y219503D03*
X304987D03*
X310449Y218617D03*
X317110Y219140D03*
X309521Y229786D03*
Y238741D03*
X307500Y256500D03*
X305000Y252400D03*
X307600Y252300D03*
X307800Y259200D03*
X302800Y286200D03*
X311670Y285160D03*
X302879Y282487D03*
Y279686D03*
X309700Y294789D03*
X315810Y293450D03*
X312315Y293207D03*
X317430Y295665D03*
X314820Y296128D03*
X314201Y302361D03*
X314180Y299440D03*
X303077Y297519D03*
X306500Y301500D03*
X314132Y310178D03*
X314170Y307020D03*
X309500Y315000D03*
X304000Y305000D03*
X303000Y309200D03*
X311000Y320500D03*
X315075Y366500D03*
X308906Y362637D03*
X314340Y373296D03*
X311925Y366475D03*
X312226Y382766D03*
X308500Y382100D03*
X314985Y397639D03*
Y394639D03*
X314969Y456527D03*
X322218Y3000D03*
X319175Y60200D03*
X321800Y60055D03*
X322600Y76100D03*
X331881Y108593D03*
Y104577D03*
X320500Y100400D03*
X331881Y112608D03*
X324011Y118843D03*
X324023Y121943D03*
Y115643D03*
X320765Y114582D03*
X318000Y117200D03*
X329297Y134594D03*
Y129890D03*
X321276Y134532D03*
X321349Y130044D03*
X331741Y138243D03*
Y125796D03*
X320239Y151075D03*
X317936Y143897D03*
X323509Y153377D03*
X329005Y152657D03*
X328087Y141608D03*
X321600Y142100D03*
X323384Y157378D03*
X331405Y157411D03*
X323384Y165378D03*
Y161378D03*
X331405Y164911D03*
Y159911D03*
Y154911D03*
Y167411D03*
X323384Y169378D03*
Y173378D03*
Y177378D03*
X331405Y177411D03*
Y179911D03*
Y174911D03*
Y169911D03*
Y182926D03*
Y172411D03*
Y187411D03*
Y192411D03*
Y189911D03*
X320054Y195163D03*
X319601Y201140D03*
X326932Y205685D03*
X326733Y209885D03*
X321045Y210257D03*
X320937Y212839D03*
X326733Y201485D03*
X320054Y198663D03*
X326323Y226349D03*
X317922Y226373D03*
X326731Y213648D03*
X320931Y215387D03*
X326323Y229738D03*
X317922Y229762D03*
Y238717D03*
Y235328D03*
X326323Y235304D03*
Y238693D03*
X327162Y278972D03*
X317670Y291430D03*
X330900Y314700D03*
X325007Y328608D03*
Y326008D03*
X327704Y328635D03*
Y326035D03*
X325007Y323508D03*
X327704Y323535D03*
X325038Y356890D03*
X329925Y356016D03*
X325320Y390118D03*
X325200Y383900D03*
X331500Y383300D03*
X332470Y397092D03*
Y394092D03*
X325593Y406500D03*
X329093D03*
X318593D03*
X322093D03*
X331646Y466536D03*
X342218Y3000D03*
X337375Y76600D03*
X342900Y66100D03*
X339900Y69100D03*
Y66000D03*
X339908Y104577D03*
Y108593D03*
X342200Y100500D03*
X342180Y106900D03*
X339101Y121128D03*
X339908Y112609D03*
X333278Y151129D03*
X339369Y151952D03*
X339800Y154911D03*
Y159911D03*
Y165911D03*
X339939Y162911D03*
X339800Y169911D03*
Y176911D03*
Y179911D03*
X339812Y173380D03*
X339800Y182926D03*
Y185911D03*
Y189911D03*
X337083Y197000D03*
X337400Y193449D03*
X337004Y206113D03*
X334723Y226349D03*
Y229738D03*
X334724Y238669D03*
Y235280D03*
X337467Y236984D03*
X336312Y286352D03*
X336461Y283202D03*
X340612Y278972D03*
X339700Y295900D03*
Y293000D03*
X347100Y313700D03*
X342604Y318773D03*
X345500Y342690D03*
X335475Y358500D03*
X335700Y376400D03*
X335500Y363200D03*
X335708Y372008D03*
X334600Y383300D03*
X334112Y447668D03*
X351331Y20788D03*
Y40788D03*
Y60788D03*
Y80788D03*
Y100788D03*
Y120788D03*
Y140788D03*
Y160788D03*
Y180788D03*
Y200788D03*
Y220788D03*
Y240788D03*
Y260788D03*
Y280788D03*
Y300788D03*
X349290Y337646D03*
X351331Y357531D03*
Y377531D03*
Y397531D03*
Y417531D03*
Y437531D03*
X373420Y-447134D03*
X370905D03*
Y-443881D03*
X373420D03*
X376346Y-447134D03*
X375904Y-438145D03*
X374975Y-435380D03*
X372211Y-440841D03*
X375964Y-215959D03*
X374666Y-218571D03*
X373480Y-210223D03*
X370965D03*
Y-206970D03*
X376406Y-206985D03*
X373480Y-206970D03*
X372271Y-213263D03*
X375876Y-159873D03*
X372183Y-162569D03*
X373392Y-168862D03*
X370877D03*
Y-165609D03*
X373392D03*
X376318Y-168862D03*
X374947Y-157108D03*
X375964Y12313D03*
X374666Y9701D03*
X373480Y18049D03*
X370965D03*
X372271Y15009D03*
X370965Y21302D03*
X376406Y21287D03*
X373480Y21302D03*
X373420Y59410D03*
X370905D03*
Y62663D03*
X373420D03*
X376346Y59410D03*
X375904Y68399D03*
X374975Y71164D03*
X372211Y65703D03*
X375964Y381585D03*
X374666Y378973D03*
X372271Y384281D03*
X376406Y390559D03*
X373480Y387321D03*
Y390574D03*
X370965Y387321D03*
Y390574D03*
X391993Y-473196D03*
Y-469943D03*
X381788Y-443881D03*
X384303D03*
Y-447134D03*
X378862Y-447119D03*
X381788Y-447134D03*
X379304Y-438145D03*
X380602Y-435533D03*
X382997Y-440841D03*
X379364Y-215959D03*
X380293Y-218724D03*
X383057Y-213263D03*
X381848Y-206970D03*
X384363D03*
Y-210223D03*
X381848D03*
X378922Y-206970D03*
X379276Y-159873D03*
X381760Y-165609D03*
X384275D03*
Y-168862D03*
X378834Y-168847D03*
X381760Y-168862D03*
X382969Y-162569D03*
X380574Y-157261D03*
X392081Y-115285D03*
Y-112032D03*
X391950Y-74043D03*
Y-70790D03*
X379364Y12313D03*
X380293Y9548D03*
X383057Y15009D03*
X384363Y18049D03*
X381848D03*
Y21302D03*
X384363D03*
X378922D03*
X381788Y62663D03*
X384303D03*
Y59410D03*
X378862Y59425D03*
X381788Y59410D03*
X379304Y68399D03*
X380602Y71011D03*
X382997Y65703D03*
X391950Y214106D03*
Y217359D03*
Y255229D03*
Y258482D03*
X379364Y381585D03*
X380293Y378820D03*
X378922Y390574D03*
X381848D03*
Y387321D03*
X384363Y390574D03*
Y387321D03*
X383057Y384281D03*
X391950Y412378D03*
Y415631D03*
X405391Y-473196D03*
X399950Y-473181D03*
X402876Y-473196D03*
X394508D03*
X397434D03*
X396992Y-464207D03*
X400392D03*
X396063Y-461442D03*
X401690Y-461595D03*
X402876Y-469943D03*
X405391D03*
X404085Y-466903D03*
X393299D03*
X394508Y-469943D03*
X397080Y-121021D03*
X400480D03*
X401409Y-123786D03*
X395782Y-123633D03*
X394596Y-115285D03*
X393387Y-118325D03*
X404173D03*
X405479Y-115285D03*
X402964D03*
X397522Y-112047D03*
X394596Y-112032D03*
X402964D03*
X405479D03*
X400038D03*
X399450Y-74028D03*
X394450Y-74043D03*
Y-70790D03*
X396950Y-74043D03*
X405050D03*
X402550D03*
X405050Y-70790D03*
X402550D03*
X393357Y-67750D03*
X403643D03*
X393357Y211066D03*
X403857D03*
X394450Y217359D03*
Y214106D03*
X396950Y217359D03*
X399450Y217344D03*
X402450Y217359D03*
X404950D03*
X402450Y214106D03*
X404950D03*
X394450Y255229D03*
X396950D03*
X399450Y255244D03*
X405050Y255229D03*
X402550D03*
X394450Y258482D03*
X393357Y261522D03*
X405050Y258482D03*
X402550D03*
X403643Y261522D03*
X394450Y415631D03*
Y412378D03*
X396950Y415631D03*
X399450Y415616D03*
X393357Y409338D03*
X402450Y415631D03*
X404950D03*
X402450Y412378D03*
X404950D03*
X403857Y409338D03*
X415550Y-70790D03*
Y-74043D03*
X413050D03*
Y-70790D03*
X410550Y-74043D03*
X408050Y-74028D03*
X414143Y-67750D03*
Y211066D03*
X415550Y214106D03*
Y217359D03*
X413050D03*
Y214106D03*
X410550Y217359D03*
X408050Y217344D03*
X415550Y255229D03*
X413050D03*
X410550D03*
X408050Y255244D03*
X415550Y258482D03*
X413050D03*
X414143Y261522D03*
X415550Y412378D03*
Y415631D03*
X413050D03*
Y412378D03*
X410550Y415631D03*
X408050Y415616D03*
X414143Y409338D03*
X768750Y274925D03*
G54D31*
X441000Y-444000D03*
Y-454000D03*
X451000D03*
Y-444000D03*
Y-355000D03*
X441000D03*
X451000Y-345000D03*
X441000D03*
Y-323400D03*
Y-333400D03*
X451000D03*
Y-323400D03*
Y-245000D03*
Y-235000D03*
X441000D03*
Y-245000D03*
X451000Y-225000D03*
X441000D03*
X451000Y-215000D03*
X441000D03*
Y-136600D03*
Y-126600D03*
X451000D03*
Y-136600D03*
Y-117000D03*
X441000D03*
X451000Y-107000D03*
X441000D03*
Y-18000D03*
Y-8000D03*
X451000D03*
Y-18000D03*
X441000Y2000D03*
X451000D03*
X441000Y12000D03*
X451000D03*
Y96000D03*
Y106000D03*
X441000D03*
Y96000D03*
Y116000D03*
X451000D03*
X441000Y126000D03*
X451000D03*
Y200000D03*
Y210000D03*
X441000D03*
Y200000D03*
X451000Y220000D03*
X441000D03*
X451000Y230000D03*
X441000D03*
Y304000D03*
Y314000D03*
X451000D03*
Y304000D03*
Y326000D03*
X441000D03*
X451000Y336000D03*
X441000D03*
Y420000D03*
X451000D03*
X441000Y430000D03*
X451000D03*
X768750Y388325D03*
G54D22*
X62458Y346425D03*
Y343275D03*
Y390481D03*
X68757Y352724D03*
X71906Y355873D03*
X75056Y359023D03*
X65607Y349574D03*
X71906D03*
X68757D03*
X75056Y352724D03*
Y349574D03*
X78206Y355873D03*
X65607D03*
X68757Y359023D03*
X71906D03*
X75056Y355873D03*
X71906Y352724D03*
X68757Y355873D03*
X78206Y374733D03*
Y362173D03*
X75056D03*
X71906Y371584D03*
X75056Y365322D03*
X68757D03*
Y371584D03*
X75056Y374733D03*
X71906D03*
X68757D03*
X65607D03*
X71906Y362173D03*
X78206Y365322D03*
Y371584D03*
X75056Y377883D03*
X68757Y384182D03*
X65607Y387332D03*
X75018Y381033D03*
X68757Y377883D03*
X78206Y381033D03*
X65607D03*
X71906Y377883D03*
X65607Y384182D03*
X68719Y381033D03*
X78206Y377883D03*
X71906Y387332D03*
X71869Y381033D03*
X71906Y384182D03*
X90766Y349574D03*
X81355Y355873D03*
X90766Y352724D03*
X87617Y349574D03*
X90766Y355873D03*
X87617D03*
X90766Y359023D03*
X81355Y349574D03*
X87617Y359023D03*
Y365322D03*
Y371584D03*
X81355Y365322D03*
Y371584D03*
X90766Y374733D03*
Y362173D03*
X81355D03*
X87617D03*
X81355Y374733D03*
X87617D03*
X90766Y371584D03*
Y365322D03*
X81355Y377883D03*
Y387332D03*
Y384182D03*
X87617D03*
X90766Y377883D03*
X87617Y390481D03*
X81355Y381033D03*
X87617Y387332D03*
X90766Y381033D03*
X87617Y377883D03*
X90766Y390481D03*
Y387332D03*
Y384182D03*
X92360Y394175D03*
X89210D03*
X103365Y346425D03*
X106564Y346400D03*
X100215Y352724D03*
X103383Y349556D03*
X93916Y359023D03*
X97066Y355873D03*
X93916Y349574D03*
X97066D03*
X106515Y352724D03*
X106514Y349574D03*
X97066Y352724D03*
X100215Y355873D03*
X93916D03*
X100215Y349574D03*
X103383Y387350D03*
X100215Y384182D03*
X93916Y377883D03*
X97066Y381033D03*
X100215Y387332D03*
X97066D03*
X93916Y384182D03*
X97066D03*
X100215Y381033D03*
X93916D03*
Y387332D03*
X166300Y212300D03*
X175359Y153286D03*
X175196Y159748D03*
X178346Y162898D03*
Y156599D03*
X181495Y159748D03*
Y156599D03*
Y166047D03*
Y162898D03*
X178346Y159748D03*
Y172347D03*
X181495Y178646D03*
Y175496D03*
Y181795D03*
X174569Y180202D03*
X175196Y172347D03*
X173000Y170200D03*
X181495Y169197D03*
X178346Y184945D03*
X181495D03*
Y197506D03*
X178346D03*
Y191244D03*
X181495D03*
X175196Y197506D03*
X174336Y192800D03*
X178346Y188095D03*
Y200655D03*
Y210104D03*
X181495Y206955D03*
X175196Y210104D03*
X178346Y206955D03*
X175196Y203805D03*
X178346D03*
X171836Y200655D03*
Y198300D03*
X181495Y200655D03*
X178346Y213254D03*
Y225852D03*
X181495Y219553D03*
X175196Y213254D03*
X181495Y225852D03*
Y222703D03*
X174600Y217800D03*
X181495Y216403D03*
X174079Y234604D03*
X175196Y229002D03*
X181495D03*
X187794Y153449D03*
X192400Y152804D03*
X184645Y153449D03*
X197243Y156599D03*
X187794Y159748D03*
X197243Y166047D03*
X194094Y162898D03*
Y159748D03*
X197243Y162898D03*
X184645Y156599D03*
X187794Y162898D03*
Y166047D03*
X184645Y162898D03*
Y159748D03*
X190944Y162898D03*
X194094Y166047D03*
X187794Y178646D03*
X197243D03*
X187794Y181795D03*
X194094Y169197D03*
X190944Y172347D03*
Y175496D03*
X197243D03*
X190944Y178646D03*
Y181795D03*
X187794Y175496D03*
X184645Y178646D03*
X190944Y169197D03*
X184645D03*
Y172347D03*
X187794Y169197D03*
X197243Y191244D03*
Y197506D03*
Y184945D03*
X190944Y197506D03*
Y184945D03*
Y188095D03*
Y191244D03*
X187794Y197506D03*
Y184945D03*
X184645Y197506D03*
Y184945D03*
Y191244D03*
Y188095D03*
X197243Y203805D03*
X184645Y206955D03*
X197243Y200655D03*
X190944D03*
Y210104D03*
Y203805D03*
X187794Y200655D03*
X184645Y210104D03*
Y200655D03*
Y203805D03*
X187794Y210104D03*
X190944Y219553D03*
X194094Y225852D03*
X187794Y219553D03*
X197243D03*
X187794Y213254D03*
X190944D03*
Y222702D03*
X197243Y225852D03*
Y222703D03*
X184645Y225852D03*
X187794Y222703D03*
X184645D03*
Y213254D03*
X194094Y219553D03*
Y232151D03*
X184645D03*
X187794Y229002D03*
X197243Y235301D03*
X194094Y229002D03*
X197243D03*
Y232151D03*
X209842Y153449D03*
X206692Y156599D03*
X209842D03*
X203542Y166047D03*
Y162898D03*
X200393Y159748D03*
X209842Y162898D03*
X200393Y166047D03*
X206692D03*
X212991D03*
X206692Y159748D03*
X209842Y169197D03*
X203542D03*
X212991D03*
X206692D03*
X212991Y181795D03*
X206692Y178646D03*
X209842Y181795D03*
X200393Y169197D03*
X206692Y181795D03*
X203542Y175496D03*
X206692D03*
X209842D03*
X200393D03*
X203542Y191244D03*
X206692D03*
X209842Y184945D03*
X200393Y191244D03*
X203542Y197506D03*
X209842D03*
X212991Y184945D03*
Y197506D03*
X203542Y210104D03*
X212991Y206955D03*
Y210104D03*
X209842D03*
X200393D03*
X203542Y200655D03*
X209842D03*
X203542Y206955D03*
X212991Y203805D03*
X206692Y206955D03*
X209842D03*
X200393D03*
X212991Y200655D03*
Y219553D03*
Y213254D03*
X200393D03*
Y219553D03*
X212991Y222740D03*
X209842Y213254D03*
Y225852D03*
X203542Y222703D03*
X200393Y225852D03*
X206692Y219553D03*
X203542D03*
X209842Y222703D03*
X212991Y225890D03*
X206692Y225852D03*
X203542Y229002D03*
Y232151D03*
X209746Y235397D03*
X203542Y235301D03*
X209842Y232151D03*
X200393D03*
X206692D03*
X212991D03*
X209842Y229002D03*
X225658Y153369D03*
X225552Y156599D03*
Y159748D03*
X222402Y162898D03*
X219253Y166047D03*
X225552Y162898D03*
X222402Y166047D03*
X219253Y159748D03*
Y162898D03*
Y156599D03*
X222402D03*
X217697Y174852D03*
X219253Y178646D03*
X225552D03*
X222402Y169197D03*
Y178646D03*
X225552Y181795D03*
X214547Y174852D03*
X225552Y169197D03*
X219253D03*
X219290Y191207D03*
X225552Y184945D03*
Y197543D03*
Y191244D03*
Y188095D03*
X222402Y191244D03*
X219253Y197506D03*
X222402D03*
X219253Y188095D03*
X222402Y206955D03*
X219253Y200655D03*
Y206955D03*
Y210104D03*
Y203805D03*
X222402Y213254D03*
X219253D03*
X216141Y222703D03*
X225590Y222720D03*
X216103Y219591D03*
X219253Y219553D03*
X225552D03*
X222402D03*
X222440Y225852D03*
X219290Y222703D03*
X219253Y232151D03*
X225552Y229002D03*
X219253D03*
X235001Y153449D03*
X228702Y162898D03*
X238150D03*
X235001Y166047D03*
X238150D03*
X228702Y159748D03*
Y166047D03*
X238150Y156599D03*
X231851D03*
Y162898D03*
Y159748D03*
X235001Y162898D03*
Y159748D03*
X238150D03*
X241300D03*
X228702Y169197D03*
X238150D03*
X231851D03*
Y178646D03*
X235001Y169197D03*
X241300Y175496D03*
Y178646D03*
Y172347D03*
X235001Y178646D03*
Y175496D03*
X228702Y181795D03*
Y178646D03*
X231851Y191244D03*
X241300D03*
X235001Y184945D03*
X228702Y191244D03*
X235001Y188095D03*
Y191244D03*
Y197506D03*
X241300Y184945D03*
Y197506D03*
Y188095D03*
X235001Y200655D03*
Y206955D03*
X228702Y200655D03*
X235001Y203805D03*
X231851D03*
X228702D03*
X241300Y200655D03*
Y210104D03*
X235001D03*
X231851D03*
X228702D03*
X235001Y219553D03*
X241300Y213254D03*
X238150Y219553D03*
X238188Y225852D03*
X228702Y219553D03*
X228739Y213254D03*
X235038Y225890D03*
X228739Y225852D03*
X238150Y222703D03*
X231889Y219591D03*
Y222740D03*
X235038D03*
X228739Y216441D03*
X241338Y225890D03*
X238630Y235654D03*
X231851Y232151D03*
X241300D03*
X231851Y229002D03*
X241300D03*
X239870Y237596D03*
X242870D03*
X235038Y229039D03*
X255492Y152905D03*
X244450Y156599D03*
X250749Y159748D03*
X244450D03*
X247637Y162898D03*
X247599Y166047D03*
X253898Y172347D03*
Y178646D03*
X247599Y181795D03*
Y175496D03*
X253898Y169197D03*
X257048Y172347D03*
X250749Y181795D03*
X244450D03*
X250749Y175496D03*
Y178646D03*
X247599Y172347D03*
X244450Y175496D03*
X250749Y172347D03*
X247599Y178646D03*
X244450D03*
Y172347D03*
Y169197D03*
X253898Y191244D03*
Y184945D03*
X247599Y197506D03*
Y188095D03*
X244450Y197506D03*
X247599Y191244D03*
X253898Y197506D03*
X250749D03*
X247599Y184945D03*
X244450Y188095D03*
X250749D03*
X244450Y184945D03*
X250749Y191244D03*
X244450D03*
X247599Y203805D03*
X253898Y206955D03*
Y200655D03*
X250749Y203805D03*
X247599Y206955D03*
Y210104D03*
X250749Y206955D03*
X247599Y200655D03*
X257048Y206955D03*
X250749Y200655D03*
X257048D03*
X250749Y210104D03*
X244450Y203805D03*
X250749Y222703D03*
Y225852D03*
X253898Y219553D03*
Y222703D03*
X257048Y225890D03*
Y219553D03*
X250749D03*
X257048Y213254D03*
X250749D03*
X247599D03*
X253898D03*
X247637Y225852D03*
X250749Y232151D03*
X257048Y235301D03*
X244020Y235518D03*
X244487Y229002D03*
X244450Y232151D03*
X247599D03*
X253898D03*
X257048D03*
X250749Y229002D03*
X253898D03*
X250749Y235301D03*
X253898D03*
X268510Y179088D03*
X262880Y178977D03*
X267722Y176791D03*
X264222D03*
X270472Y188488D03*
X264118Y188095D03*
X268391Y207262D03*
X260269Y207358D03*
X266080Y207262D03*
X262580D03*
X269391Y214593D03*
X261269Y214657D03*
X263580Y214593D03*
X267080D03*
X285980Y163487D03*
X285482Y168102D03*
X286105Y172936D03*
Y182385D03*
X273644Y174267D03*
X282975Y172975D03*
X286105Y176085D03*
X285482Y190187D03*
X286105Y197989D03*
Y185534D03*
Y194839D03*
Y201139D03*
Y204288D03*
Y213721D03*
X289110Y163487D03*
X292260D03*
X295410Y169786D03*
X292404Y176085D03*
X289254Y172792D03*
X292260Y169643D03*
X295410Y179235D03*
X292384Y172936D03*
X289254Y176085D03*
Y182385D03*
X292260Y179235D03*
X289111D03*
X297372Y196616D03*
X292361Y197970D03*
X292404Y191690D03*
X289254D03*
X292404Y185534D03*
Y194983D03*
X295410Y194839D03*
X295411Y185534D03*
X289254D03*
Y197989D03*
X289091Y204331D03*
X289254Y210587D03*
X292404D03*
X289254Y201139D03*
X295410Y210587D03*
X289254Y213737D03*
X308008Y163487D03*
X311158D03*
X308008Y166637D03*
X314307Y163487D03*
X314930Y168140D03*
X311301Y182385D03*
X314930Y171289D03*
Y177588D03*
X305002Y176085D03*
Y169786D03*
X308152D03*
X311158Y169643D03*
X308152Y172936D03*
Y176085D03*
Y182385D03*
X305002Y179235D03*
X308152D03*
X314930Y180738D03*
Y174439D03*
X311158Y185534D03*
X314307Y191690D03*
X308008D03*
X311158D03*
X308008Y188540D03*
Y185391D03*
Y198133D03*
X314307Y185534D03*
X311158Y188540D03*
X308008Y194839D03*
X311158Y197989D03*
X314307Y194839D03*
Y197989D03*
X311158Y204288D03*
X314307Y207438D03*
X303940Y212664D03*
X311158Y201139D03*
X308008Y207438D03*
X308152Y204432D03*
X305002D03*
X308008Y210731D03*
X305002Y210587D03*
X314307Y201139D03*
Y204288D03*
Y210587D03*
X308460Y214178D03*
X311158Y213737D03*
X314307D03*
X768750Y331625D03*
G54D32*
G01X2010999Y-388000D02*
Y1475775D01*
X-407000D01*
Y-386798D01*
Y-755294D01*
Y-793716D01*
X-368578D01*
X1942346D01*
X2010999D01*
Y-725063D01*
Y-388000D01*
G01X-358229Y783332D02*
X-370729D01*
X-368229Y781472D01*
G01X-358229D02*
Y785192D01*
G01X-370729Y795732D02*
X-370312Y794492D01*
X-369271Y793562D01*
X-368021Y792942D01*
X-366354Y792477D01*
X-364479Y792322D01*
X-362604Y792477D01*
X-360937Y792942D01*
X-359687Y793562D01*
X-358646Y794492D01*
X-358229Y795732D01*
X-358646Y796972D01*
X-359687Y797902D01*
X-360937Y798522D01*
X-362604Y798987D01*
X-364479Y799142D01*
X-366354Y798987D01*
X-368021Y798522D01*
X-369271Y797902D01*
X-370312Y796972D01*
X-370729Y795732D01*
G01X-358229Y804102D02*
X-370729D01*
X-360312Y808132D01*
X-370729Y812162D01*
X-358229D01*
G01Y816502D02*
X-370729D01*
X-360312Y820532D01*
X-370729Y824562D01*
X-358229D01*
G01X-283140Y788152D02*
X-357244D01*
G01X-283994Y827522D02*
X-357244D01*
G01X-360000Y1038700D02*
Y1046700D01*
X-361200Y1045100D01*
G01Y1038700D02*
X-358800D01*
G01X-352000Y1046700D02*
X-352800Y1046433D01*
X-353400Y1045767D01*
X-353800Y1044967D01*
X-354100Y1043900D01*
X-354200Y1042700D01*
X-354100Y1041500D01*
X-353800Y1040433D01*
X-353400Y1039633D01*
X-352800Y1038967D01*
X-352000Y1038700D01*
X-351200Y1038967D01*
X-350600Y1039633D01*
X-350200Y1040433D01*
X-349900Y1041500D01*
X-349800Y1042700D01*
X-349900Y1043900D01*
X-350200Y1044967D01*
X-350600Y1045767D01*
X-351200Y1046433D01*
X-352000Y1046700D01*
G01X-344000Y1038433D02*
X-344200Y1038567D01*
Y1038833D01*
X-344000Y1038967D01*
X-343800Y1038833D01*
Y1038567D01*
X-344000Y1038433D01*
G01X-337900Y1038700D02*
Y1046700D01*
X-334100D01*
G01X-335500Y1042833D02*
X-337900D01*
G01X-328000Y1038700D02*
X-328800Y1038833D01*
X-329500Y1039367D01*
X-330100Y1040167D01*
X-330500Y1041100D01*
X-330700Y1042167D01*
Y1043233D01*
X-330500Y1044300D01*
X-330100Y1045233D01*
X-329500Y1046033D01*
X-328800Y1046567D01*
X-328000Y1046700D01*
X-327200Y1046567D01*
X-326500Y1046033D01*
X-325900Y1045233D01*
X-325500Y1044300D01*
X-325300Y1043233D01*
Y1042167D01*
X-325500Y1041100D01*
X-325900Y1040167D01*
X-326500Y1039367D01*
X-327200Y1038833D01*
X-328000Y1038700D01*
G01X-322000D02*
Y1046700D01*
X-319500D01*
X-318700Y1046300D01*
X-318200Y1045767D01*
X-318000Y1044700D01*
X-318200Y1043633D01*
X-318800Y1042967D01*
X-319500Y1042567D01*
X-322000D01*
G01X-319500D02*
X-318000Y1038700D01*
G01X-304000Y1046700D02*
Y1038700D01*
G01X-306300Y1046700D02*
X-301700D01*
G01X-298100Y1038700D02*
Y1046700D01*
G01X-293900D02*
Y1038700D01*
G01Y1042700D02*
X-298100D01*
G01X-286000Y1038700D02*
X-290000D01*
Y1046700D01*
X-286000D01*
G01X-287600Y1042833D02*
X-290000D01*
G01X-274000Y1038700D02*
Y1046700D01*
X-271600D01*
X-270800Y1046300D01*
X-270200Y1045367D01*
X-270000Y1044300D01*
X-270200Y1043233D01*
X-270700Y1042433D01*
X-271600Y1042033D01*
X-274000D01*
G01X-264000Y1046700D02*
Y1038700D01*
G01X-266300Y1046700D02*
X-261700D01*
G01X-258100Y1038700D02*
Y1046700D01*
G01X-253900D02*
Y1038700D01*
G01Y1042700D02*
X-258100D01*
G01X-240000Y1046700D02*
Y1038700D01*
G01X-242300Y1046700D02*
X-237700D01*
G01X-232000Y1038700D02*
X-232800Y1038833D01*
X-233500Y1039367D01*
X-234100Y1040167D01*
X-234500Y1041100D01*
X-234700Y1042167D01*
Y1043233D01*
X-234500Y1044300D01*
X-234100Y1045233D01*
X-233500Y1046033D01*
X-232800Y1046567D01*
X-232000Y1046700D01*
X-231200Y1046567D01*
X-230500Y1046033D01*
X-229900Y1045233D01*
X-229500Y1044300D01*
X-229300Y1043233D01*
Y1042167D01*
X-229500Y1041100D01*
X-229900Y1040167D01*
X-230500Y1039367D01*
X-231200Y1038833D01*
X-232000Y1038700D01*
G01X-224000D02*
X-224800Y1038833D01*
X-225500Y1039367D01*
X-226100Y1040167D01*
X-226500Y1041100D01*
X-226700Y1042167D01*
Y1043233D01*
X-226500Y1044300D01*
X-226100Y1045233D01*
X-225500Y1046033D01*
X-224800Y1046567D01*
X-224000Y1046700D01*
X-223200Y1046567D01*
X-222500Y1046033D01*
X-221900Y1045233D01*
X-221500Y1044300D01*
X-221300Y1043233D01*
Y1042167D01*
X-221500Y1041100D01*
X-221900Y1040167D01*
X-222500Y1039367D01*
X-223200Y1038833D01*
X-224000Y1038700D01*
G01X-218000Y1046700D02*
Y1038700D01*
X-214000D01*
G01X-209200Y1046700D02*
X-206800D01*
G01X-208000D02*
Y1038700D01*
G01X-209200D02*
X-206800D01*
G01X-202300D02*
Y1046700D01*
X-197700Y1038700D01*
Y1046700D01*
G01X-191400Y1042700D02*
X-189400D01*
Y1040300D01*
X-190000Y1039500D01*
X-190700Y1038967D01*
X-191700Y1038700D01*
X-192700Y1038967D01*
X-193400Y1039500D01*
X-194000Y1040300D01*
X-194400Y1041233D01*
X-194600Y1042300D01*
Y1043233D01*
X-194400Y1044033D01*
X-194000Y1044967D01*
X-193400Y1045767D01*
X-192800Y1046300D01*
X-192000Y1046700D01*
X-191300D01*
X-190500Y1046433D01*
X-189900Y1045900D01*
G01X-178100Y1038700D02*
Y1046700D01*
G01X-173900D02*
Y1038700D01*
G01Y1042700D02*
X-178100D01*
G01X-168000Y1038700D02*
X-168800Y1038833D01*
X-169500Y1039367D01*
X-170100Y1040167D01*
X-170500Y1041100D01*
X-170700Y1042167D01*
Y1043233D01*
X-170500Y1044300D01*
X-170100Y1045233D01*
X-169500Y1046033D01*
X-168800Y1046567D01*
X-168000Y1046700D01*
X-167200Y1046567D01*
X-166500Y1046033D01*
X-165900Y1045233D01*
X-165500Y1044300D01*
X-165300Y1043233D01*
Y1042167D01*
X-165500Y1041100D01*
X-165900Y1040167D01*
X-166500Y1039367D01*
X-167200Y1038833D01*
X-168000Y1038700D01*
G01X-162000Y1046700D02*
Y1038700D01*
X-158000D01*
G01X-150000D02*
X-154000D01*
Y1046700D01*
X-150000D01*
G01X-151600Y1042833D02*
X-154000D01*
G01X-146100Y1039766D02*
X-145300Y1039100D01*
X-144400Y1038700D01*
X-143600D01*
X-142800Y1039100D01*
X-142200Y1039766D01*
X-141900Y1040700D01*
X-142100Y1041633D01*
X-142600Y1042433D01*
X-143500Y1042967D01*
X-144700Y1043233D01*
X-145400Y1043767D01*
X-145700Y1044700D01*
X-145500Y1045633D01*
X-145000Y1046300D01*
X-144300Y1046700D01*
X-143600D01*
X-142900Y1046433D01*
X-142300Y1045767D01*
G01X-131000Y1046700D02*
X-129600Y1038700D01*
X-128000Y1046700D01*
X-126400Y1038700D01*
X-125000Y1046700D01*
G01X-122100Y1038700D02*
Y1046700D01*
G01X-117900D02*
Y1038700D01*
G01Y1042700D02*
X-122100D01*
G01X-113200Y1046700D02*
X-110800D01*
G01X-112000D02*
Y1038700D01*
G01X-113200D02*
X-110800D01*
G01X-101800Y1046033D02*
X-102400Y1046433D01*
X-103100Y1046700D01*
X-103900D01*
X-104800Y1046300D01*
X-105500Y1045633D01*
X-106000Y1044833D01*
X-106400Y1043500D01*
X-106500Y1042300D01*
X-106300Y1041100D01*
X-106000Y1040300D01*
X-105400Y1039500D01*
X-104700Y1038967D01*
X-104000Y1038700D01*
X-103300D01*
X-102600Y1038967D01*
X-102000Y1039367D01*
X-101500Y1039900D01*
G01X-98100Y1038700D02*
Y1046700D01*
G01X-93900D02*
Y1038700D01*
G01Y1042700D02*
X-98100D01*
G01X-82100Y1039766D02*
X-81300Y1039100D01*
X-80400Y1038700D01*
X-79600D01*
X-78800Y1039100D01*
X-78200Y1039766D01*
X-77900Y1040700D01*
X-78100Y1041633D01*
X-78600Y1042433D01*
X-79500Y1042967D01*
X-80700Y1043233D01*
X-81400Y1043767D01*
X-81700Y1044700D01*
X-81500Y1045633D01*
X-81000Y1046300D01*
X-80300Y1046700D01*
X-79600D01*
X-78900Y1046433D01*
X-78300Y1045767D01*
G01X-73200Y1046700D02*
X-70800D01*
G01X-72000D02*
Y1038700D01*
G01X-73200D02*
X-70800D01*
G01X-65900Y1046700D02*
X-62100D01*
X-65900Y1038700D01*
X-62100D01*
G01X-54000D02*
X-58000D01*
Y1046700D01*
X-54000D01*
G01X-55600Y1042833D02*
X-58000D01*
G01X-41200Y1046700D02*
X-38800D01*
G01X-40000D02*
Y1038700D01*
G01X-41200D02*
X-38800D01*
G01X-34100Y1039766D02*
X-33300Y1039100D01*
X-32400Y1038700D01*
X-31600D01*
X-30800Y1039100D01*
X-30200Y1039766D01*
X-29900Y1040700D01*
X-30100Y1041633D01*
X-30600Y1042433D01*
X-31500Y1042967D01*
X-32700Y1043233D01*
X-33400Y1043767D01*
X-33700Y1044700D01*
X-33500Y1045633D01*
X-33000Y1046300D01*
X-32300Y1046700D01*
X-31600D01*
X-30900Y1046433D01*
X-30300Y1045767D01*
G01X-14000Y1038700D02*
X-18000D01*
Y1046700D01*
X-14000D01*
G01X-15600Y1042833D02*
X-18000D01*
G01X-8000Y1038700D02*
X-8800Y1038833D01*
X-9500Y1039367D01*
X-10100Y1040167D01*
X-10500Y1041100D01*
X-10700Y1042167D01*
Y1043233D01*
X-10500Y1044300D01*
X-10100Y1045233D01*
X-9500Y1046033D01*
X-8800Y1046567D01*
X-8000Y1046700D01*
X-7200Y1046567D01*
X-6500Y1046033D01*
X-5900Y1045233D01*
X-5500Y1044300D01*
X-5300Y1043233D01*
Y1042167D01*
X-5500Y1041100D01*
X-5900Y1040167D01*
X-6500Y1039367D01*
X-7200Y1038833D01*
X-8000Y1038700D01*
G01X-7200Y1040833D02*
X-6000Y1038700D01*
G01X-2200Y1046700D02*
Y1040967D01*
X-1800Y1039766D01*
X-1000Y1038967D01*
X0Y1038700D01*
X1000Y1038967D01*
X1800Y1039766D01*
X2200Y1040967D01*
Y1046700D01*
G01X5500Y1038700D02*
X8000Y1046700D01*
X10500Y1038700D01*
G01X9600Y1041500D02*
X6400D01*
G01X14000Y1046700D02*
Y1038700D01*
X18000D01*
G01X32000Y1046700D02*
Y1038700D01*
G01X29700Y1046700D02*
X34300D01*
G01X40000Y1038700D02*
X39200Y1038833D01*
X38500Y1039367D01*
X37900Y1040167D01*
X37500Y1041100D01*
X37300Y1042167D01*
Y1043233D01*
X37500Y1044300D01*
X37900Y1045233D01*
X38500Y1046033D01*
X39200Y1046567D01*
X40000Y1046700D01*
X40800Y1046567D01*
X41500Y1046033D01*
X42100Y1045233D01*
X42500Y1044300D01*
X42700Y1043233D01*
Y1042167D01*
X42500Y1041100D01*
X42100Y1040167D01*
X41500Y1039367D01*
X40800Y1038833D01*
X40000Y1038700D01*
G01X56000D02*
X55200Y1038833D01*
X54500Y1039367D01*
X53900Y1040167D01*
X53500Y1041100D01*
X53300Y1042167D01*
Y1043233D01*
X53500Y1044300D01*
X53900Y1045233D01*
X54500Y1046033D01*
X55200Y1046567D01*
X56000Y1046700D01*
X56800Y1046567D01*
X57500Y1046033D01*
X58100Y1045233D01*
X58500Y1044300D01*
X58700Y1043233D01*
Y1042167D01*
X58500Y1041100D01*
X58100Y1040167D01*
X57500Y1039367D01*
X56800Y1038833D01*
X56000Y1038700D01*
G01X62000D02*
Y1046700D01*
X64500D01*
X65300Y1046300D01*
X65800Y1045767D01*
X66000Y1044700D01*
X65800Y1043633D01*
X65200Y1042967D01*
X64500Y1042567D01*
X62000D01*
G01X64500D02*
X66000Y1038700D01*
G01X77400D02*
Y1046700D01*
X80000Y1040033D01*
X82600Y1046700D01*
Y1038700D01*
G01X88000D02*
X87200Y1038833D01*
X86500Y1039367D01*
X85900Y1040167D01*
X85500Y1041100D01*
X85300Y1042167D01*
Y1043233D01*
X85500Y1044300D01*
X85900Y1045233D01*
X86500Y1046033D01*
X87200Y1046567D01*
X88000Y1046700D01*
X88800Y1046567D01*
X89500Y1046033D01*
X90100Y1045233D01*
X90500Y1044300D01*
X90700Y1043233D01*
Y1042167D01*
X90500Y1041100D01*
X90100Y1040167D01*
X89500Y1039367D01*
X88800Y1038833D01*
X88000Y1038700D01*
G01X94000D02*
Y1046700D01*
X96500D01*
X97300Y1046300D01*
X97800Y1045767D01*
X98000Y1044700D01*
X97800Y1043633D01*
X97200Y1042967D01*
X96500Y1042567D01*
X94000D01*
G01X96500D02*
X98000Y1038700D01*
G01X106000D02*
X102000D01*
Y1046700D01*
X106000D01*
G01X104400Y1042833D02*
X102000D01*
G01X120000Y1046700D02*
Y1038700D01*
G01X117700Y1046700D02*
X122300D01*
G01X125900Y1038700D02*
Y1046700D01*
G01X130100D02*
Y1038700D01*
G01Y1042700D02*
X125900D01*
G01X133500Y1038700D02*
X136000Y1046700D01*
X138500Y1038700D01*
G01X137600Y1041500D02*
X134400D01*
G01X141700Y1038700D02*
Y1046700D01*
X146300Y1038700D01*
Y1046700D01*
G01X159800Y1038700D02*
X160000Y1040433D01*
X160300Y1041900D01*
X160700Y1043233D01*
X161200Y1044700D01*
X162000Y1046700D01*
X158000D01*
G01X168000D02*
X167200Y1046433D01*
X166600Y1045767D01*
X166200Y1044967D01*
X165900Y1043900D01*
X165800Y1042700D01*
X165900Y1041500D01*
X166200Y1040433D01*
X166600Y1039633D01*
X167200Y1038967D01*
X168000Y1038700D01*
X168800Y1038967D01*
X169400Y1039633D01*
X169800Y1040433D01*
X170100Y1041500D01*
X170200Y1042700D01*
X170100Y1043900D01*
X169800Y1044967D01*
X169400Y1045767D01*
X168800Y1046433D01*
X168000Y1046700D01*
G01X181400Y1038700D02*
Y1046700D01*
X184000Y1040033D01*
X186600Y1046700D01*
Y1038700D01*
G01X190800Y1046700D02*
X193200D01*
G01X192000D02*
Y1038700D01*
G01X190800D02*
X193200D01*
G01X198000Y1046700D02*
Y1038700D01*
X202000D01*
G01X208000Y1038433D02*
X207800Y1038567D01*
Y1038833D01*
X208000Y1038967D01*
X208200Y1038833D01*
Y1038567D01*
X208000Y1038433D01*
G01X229700Y1038700D02*
Y1046700D01*
X234300Y1038700D01*
Y1046700D01*
G01X240000Y1038700D02*
X239200Y1038833D01*
X238500Y1039367D01*
X237900Y1040167D01*
X237500Y1041100D01*
X237300Y1042167D01*
Y1043233D01*
X237500Y1044300D01*
X237900Y1045233D01*
X238500Y1046033D01*
X239200Y1046567D01*
X240000Y1046700D01*
X240800Y1046567D01*
X241500Y1046033D01*
X242100Y1045233D01*
X242500Y1044300D01*
X242700Y1043233D01*
Y1042167D01*
X242500Y1041100D01*
X242100Y1040167D01*
X241500Y1039367D01*
X240800Y1038833D01*
X240000Y1038700D01*
G01X245700D02*
Y1046700D01*
X250300Y1038700D01*
Y1046700D01*
G01X254700Y1041367D02*
X257300D01*
G01X262100Y1038700D02*
Y1046700D01*
X265900D01*
G01X264500Y1042833D02*
X262100D01*
G01X269800Y1046700D02*
Y1040967D01*
X270200Y1039766D01*
X271000Y1038967D01*
X272000Y1038700D01*
X273000Y1038967D01*
X273800Y1039766D01*
X274200Y1040967D01*
Y1046700D01*
G01X277700Y1038700D02*
Y1046700D01*
X282300Y1038700D01*
Y1046700D01*
G01X290200Y1046033D02*
X289600Y1046433D01*
X288900Y1046700D01*
X288100D01*
X287200Y1046300D01*
X286500Y1045633D01*
X286000Y1044833D01*
X285600Y1043500D01*
X285500Y1042300D01*
X285700Y1041100D01*
X286000Y1040300D01*
X286600Y1039500D01*
X287300Y1038967D01*
X288000Y1038700D01*
X288700D01*
X289400Y1038967D01*
X290000Y1039367D01*
X290500Y1039900D01*
G01X296000Y1046700D02*
Y1038700D01*
G01X293700Y1046700D02*
X298300D01*
G01X302800D02*
X305200D01*
G01X304000D02*
Y1038700D01*
G01X302800D02*
X305200D01*
G01X312000D02*
X311200Y1038833D01*
X310500Y1039367D01*
X309900Y1040167D01*
X309500Y1041100D01*
X309300Y1042167D01*
Y1043233D01*
X309500Y1044300D01*
X309900Y1045233D01*
X310500Y1046033D01*
X311200Y1046567D01*
X312000Y1046700D01*
X312800Y1046567D01*
X313500Y1046033D01*
X314100Y1045233D01*
X314500Y1044300D01*
X314700Y1043233D01*
Y1042167D01*
X314500Y1041100D01*
X314100Y1040167D01*
X313500Y1039367D01*
X312800Y1038833D01*
X312000Y1038700D01*
G01X317700D02*
Y1046700D01*
X322300Y1038700D01*
Y1046700D01*
G01X325500Y1038700D02*
X328000Y1046700D01*
X330500Y1038700D01*
G01X329600Y1041500D02*
X326400D01*
G01X334000Y1046700D02*
Y1038700D01*
X338000D01*
G01X350000D02*
Y1046700D01*
X352400D01*
X353200Y1046300D01*
X353800Y1045367D01*
X354000Y1044300D01*
X353800Y1043233D01*
X353300Y1042433D01*
X352400Y1042033D01*
X350000D01*
G01X357500Y1038700D02*
X360000Y1046700D01*
X362500Y1038700D01*
G01X361600Y1041500D02*
X358400D01*
G01X365800Y1038700D02*
Y1046700D01*
X367800D01*
X368600Y1046300D01*
X369200Y1045767D01*
X369700Y1044967D01*
X370100Y1044033D01*
X370200Y1042700D01*
X370100Y1041367D01*
X369700Y1040433D01*
X369200Y1039633D01*
X368600Y1039100D01*
X367800Y1038700D01*
X365800D01*
G01X382800Y1046700D02*
X385200D01*
G01X384000D02*
Y1038700D01*
G01X382800D02*
X385200D01*
G01X389900Y1039766D02*
X390700Y1039100D01*
X391600Y1038700D01*
X392400D01*
X393200Y1039100D01*
X393800Y1039766D01*
X394100Y1040700D01*
X393900Y1041633D01*
X393400Y1042433D01*
X392500Y1042967D01*
X391300Y1043233D01*
X390600Y1043767D01*
X390300Y1044700D01*
X390500Y1045633D01*
X391000Y1046300D01*
X391700Y1046700D01*
X392400D01*
X393100Y1046433D01*
X393700Y1045767D01*
G01X406000Y1038700D02*
Y1046700D01*
X408500D01*
X409300Y1046300D01*
X409800Y1045767D01*
X410000Y1044700D01*
X409800Y1043633D01*
X409200Y1042967D01*
X408500Y1042567D01*
X406000D01*
G01X408500D02*
X410000Y1038700D01*
G01X418000D02*
X414000D01*
Y1046700D01*
X418000D01*
G01X416400Y1042833D02*
X414000D01*
G01X424000Y1038700D02*
X423200Y1038833D01*
X422500Y1039367D01*
X421900Y1040167D01*
X421500Y1041100D01*
X421300Y1042167D01*
Y1043233D01*
X421500Y1044300D01*
X421900Y1045233D01*
X422500Y1046033D01*
X423200Y1046567D01*
X424000Y1046700D01*
X424800Y1046567D01*
X425500Y1046033D01*
X426100Y1045233D01*
X426500Y1044300D01*
X426700Y1043233D01*
Y1042167D01*
X426500Y1041100D01*
X426100Y1040167D01*
X425500Y1039367D01*
X424800Y1038833D01*
X424000Y1038700D01*
G01X424800Y1040833D02*
X426000Y1038700D01*
G01X429800Y1046700D02*
Y1040967D01*
X430200Y1039766D01*
X431000Y1038967D01*
X432000Y1038700D01*
X433000Y1038967D01*
X433800Y1039766D01*
X434200Y1040967D01*
Y1046700D01*
G01X438800D02*
X441200D01*
G01X440000D02*
Y1038700D01*
G01X438800D02*
X441200D01*
G01X446000D02*
Y1046700D01*
X448500D01*
X449300Y1046300D01*
X449800Y1045767D01*
X450000Y1044700D01*
X449800Y1043633D01*
X449200Y1042967D01*
X448500Y1042567D01*
X446000D01*
G01X448500D02*
X450000Y1038700D01*
G01X458000D02*
X454000D01*
Y1046700D01*
X458000D01*
G01X456400Y1042833D02*
X454000D01*
G01X461800Y1038700D02*
Y1046700D01*
X463800D01*
X464600Y1046300D01*
X465200Y1045767D01*
X465700Y1044967D01*
X466100Y1044033D01*
X466200Y1042700D01*
X466100Y1041367D01*
X465700Y1040433D01*
X465200Y1039633D01*
X464600Y1039100D01*
X463800Y1038700D01*
X461800D01*
G01X480000Y1046700D02*
Y1038700D01*
G01X477700Y1046700D02*
X482300D01*
G01X488000Y1038700D02*
X487200Y1038833D01*
X486500Y1039367D01*
X485900Y1040167D01*
X485500Y1041100D01*
X485300Y1042167D01*
Y1043233D01*
X485500Y1044300D01*
X485900Y1045233D01*
X486500Y1046033D01*
X487200Y1046567D01*
X488000Y1046700D01*
X488800Y1046567D01*
X489500Y1046033D01*
X490100Y1045233D01*
X490500Y1044300D01*
X490700Y1043233D01*
Y1042167D01*
X490500Y1041100D01*
X490100Y1040167D01*
X489500Y1039367D01*
X488800Y1038833D01*
X488000Y1038700D01*
G01X504800Y1042967D02*
X505200Y1043367D01*
X505500Y1044033D01*
X505700Y1044967D01*
X505500Y1045767D01*
X505100Y1046300D01*
X504400Y1046700D01*
X501700D01*
Y1038700D01*
X505000D01*
X505700Y1039233D01*
X506100Y1040033D01*
X506300Y1040967D01*
X506100Y1041900D01*
X505500Y1042700D01*
X504800Y1042967D01*
X501700D01*
G01X514000Y1038700D02*
X510000D01*
Y1046700D01*
X514000D01*
G01X512400Y1042833D02*
X510000D01*
G01X525500Y1038700D02*
X528000Y1046700D01*
X530500Y1038700D01*
G01X529600Y1041500D02*
X526400D01*
G01X533800Y1038700D02*
Y1046700D01*
X535800D01*
X536600Y1046300D01*
X537200Y1045767D01*
X537700Y1044967D01*
X538100Y1044033D01*
X538200Y1042700D01*
X538100Y1041367D01*
X537700Y1040433D01*
X537200Y1039633D01*
X536600Y1039100D01*
X535800Y1038700D01*
X533800D01*
G01X541800D02*
Y1046700D01*
X543800D01*
X544600Y1046300D01*
X545200Y1045767D01*
X545700Y1044967D01*
X546100Y1044033D01*
X546200Y1042700D01*
X546100Y1041367D01*
X545700Y1040433D01*
X545200Y1039633D01*
X544600Y1039100D01*
X543800Y1038700D01*
X541800D01*
G01X554000D02*
X550000D01*
Y1046700D01*
X554000D01*
G01X552400Y1042833D02*
X550000D01*
G01X557800Y1038700D02*
Y1046700D01*
X559800D01*
X560600Y1046300D01*
X561200Y1045767D01*
X561700Y1044967D01*
X562100Y1044033D01*
X562200Y1042700D01*
X562100Y1041367D01*
X561700Y1040433D01*
X561200Y1039633D01*
X560600Y1039100D01*
X559800Y1038700D01*
X557800D01*
G01X576000Y1046700D02*
Y1038700D01*
G01X573700Y1046700D02*
X578300D01*
G01X584000Y1038700D02*
X583200Y1038833D01*
X582500Y1039367D01*
X581900Y1040167D01*
X581500Y1041100D01*
X581300Y1042167D01*
Y1043233D01*
X581500Y1044300D01*
X581900Y1045233D01*
X582500Y1046033D01*
X583200Y1046567D01*
X584000Y1046700D01*
X584800Y1046567D01*
X585500Y1046033D01*
X586100Y1045233D01*
X586500Y1044300D01*
X586700Y1043233D01*
Y1042167D01*
X586500Y1041100D01*
X586100Y1040167D01*
X585500Y1039367D01*
X584800Y1038833D01*
X584000Y1038700D01*
G01X598000D02*
Y1046700D01*
X600400D01*
X601200Y1046300D01*
X601800Y1045367D01*
X602000Y1044300D01*
X601800Y1043233D01*
X601300Y1042433D01*
X600400Y1042033D01*
X598000D01*
G01X606000Y1038700D02*
Y1046700D01*
X608500D01*
X609300Y1046300D01*
X609800Y1045767D01*
X610000Y1044700D01*
X609800Y1043633D01*
X609200Y1042967D01*
X608500Y1042567D01*
X606000D01*
G01X608500D02*
X610000Y1038700D01*
G01X618000D02*
X614000D01*
Y1046700D01*
X618000D01*
G01X616400Y1042833D02*
X614000D01*
G01X621500Y1046700D02*
X624000Y1038700D01*
X626500Y1046700D01*
G01X634000Y1038700D02*
X630000D01*
Y1046700D01*
X634000D01*
G01X632400Y1042833D02*
X630000D01*
G01X637700Y1038700D02*
Y1046700D01*
X642300Y1038700D01*
Y1046700D01*
G01X648000D02*
Y1038700D01*
G01X645700Y1046700D02*
X650300D01*
G01X664000D02*
Y1038700D01*
G01X661700Y1046700D02*
X666300D01*
G01X669900Y1038700D02*
Y1046700D01*
G01X674100D02*
Y1038700D01*
G01Y1042700D02*
X669900D01*
G01X682000Y1038700D02*
X678000D01*
Y1046700D01*
X682000D01*
G01X680400Y1042833D02*
X678000D01*
G01X694000Y1038700D02*
Y1046700D01*
X696400D01*
X697200Y1046300D01*
X697800Y1045367D01*
X698000Y1044300D01*
X697800Y1043233D01*
X697300Y1042433D01*
X696400Y1042033D01*
X694000D01*
G01X704000Y1038700D02*
X703200Y1038833D01*
X702500Y1039367D01*
X701900Y1040167D01*
X701500Y1041100D01*
X701300Y1042167D01*
Y1043233D01*
X701500Y1044300D01*
X701900Y1045233D01*
X702500Y1046033D01*
X703200Y1046567D01*
X704000Y1046700D01*
X704800Y1046567D01*
X705500Y1046033D01*
X706100Y1045233D01*
X706500Y1044300D01*
X706700Y1043233D01*
Y1042167D01*
X706500Y1041100D01*
X706100Y1040167D01*
X705500Y1039367D01*
X704800Y1038833D01*
X704000Y1038700D01*
G01X712000Y1046700D02*
Y1038700D01*
G01X709700Y1046700D02*
X714300D01*
G01X722000Y1038700D02*
X718000D01*
Y1046700D01*
X722000D01*
G01X720400Y1042833D02*
X718000D01*
G01X725700Y1038700D02*
Y1046700D01*
X730300Y1038700D01*
Y1046700D01*
G01X736000D02*
Y1038700D01*
G01X733700Y1046700D02*
X738300D01*
G01X742800D02*
X745200D01*
G01X744000D02*
Y1038700D01*
G01X742800D02*
X745200D01*
G01X749500D02*
X752000Y1046700D01*
X754500Y1038700D01*
G01X753600Y1041500D02*
X750400D01*
G01X758000Y1046700D02*
Y1038700D01*
X762000D01*
G01X774000D02*
Y1046700D01*
X776400D01*
X777200Y1046300D01*
X777800Y1045367D01*
X778000Y1044300D01*
X777800Y1043233D01*
X777300Y1042433D01*
X776400Y1042033D01*
X774000D01*
G01X781800Y1046700D02*
Y1040967D01*
X782200Y1039766D01*
X783000Y1038967D01*
X784000Y1038700D01*
X785000Y1038967D01*
X785800Y1039766D01*
X786200Y1040967D01*
Y1046700D01*
G01X790000D02*
Y1038700D01*
X794000D01*
G01X798000Y1046700D02*
Y1038700D01*
X802000D01*
G01X813500D02*
X816000Y1046700D01*
X818500Y1038700D01*
G01X817600Y1041500D02*
X814400D01*
G01X821000Y1046700D02*
X822400Y1038700D01*
X824000Y1046700D01*
X825600Y1038700D01*
X827000Y1046700D01*
G01X829500Y1038700D02*
X832000Y1046700D01*
X834500Y1038700D01*
G01X833600Y1041500D02*
X830400D01*
G01X840000Y1038700D02*
Y1042300D01*
X838000Y1046700D01*
G01X842000D02*
X840000Y1042300D01*
G01X848000Y1038433D02*
X847800Y1038567D01*
Y1038833D01*
X848000Y1038967D01*
X848200Y1038833D01*
Y1038567D01*
X848000Y1038433D01*
G01X-361700Y1054633D02*
X-361000Y1053967D01*
X-360200Y1053700D01*
X-359400Y1053967D01*
X-358700Y1054766D01*
X-358200Y1055967D01*
X-358000Y1057167D01*
Y1058633D01*
X-358200Y1059833D01*
X-358700Y1060900D01*
X-359300Y1061433D01*
X-360000Y1061700D01*
X-360800Y1061433D01*
X-361400Y1060900D01*
X-361800Y1060100D01*
X-362000Y1059033D01*
X-361800Y1058100D01*
X-361300Y1057167D01*
X-360700Y1056633D01*
X-360000Y1056500D01*
X-359200Y1056766D01*
X-358600Y1057433D01*
X-358000Y1058633D01*
G01X-352000Y1053433D02*
X-352200Y1053567D01*
Y1053833D01*
X-352000Y1053967D01*
X-351800Y1053833D01*
Y1053567D01*
X-352000Y1053433D01*
G01X-346500Y1053700D02*
X-344000Y1061700D01*
X-341500Y1053700D01*
G01X-342400Y1056500D02*
X-345600D01*
G01X-338300Y1053700D02*
Y1061700D01*
X-333700Y1053700D01*
Y1061700D01*
G01X-328000Y1053700D02*
Y1057300D01*
X-330000Y1061700D01*
G01X-326000D02*
X-328000Y1057300D01*
G01X-314100Y1054766D02*
X-313300Y1054100D01*
X-312400Y1053700D01*
X-311600D01*
X-310800Y1054100D01*
X-310200Y1054766D01*
X-309900Y1055700D01*
X-310100Y1056633D01*
X-310600Y1057433D01*
X-311500Y1057967D01*
X-312700Y1058233D01*
X-313400Y1058767D01*
X-313700Y1059700D01*
X-313500Y1060633D01*
X-313000Y1061300D01*
X-312300Y1061700D01*
X-311600D01*
X-310900Y1061433D01*
X-310300Y1060767D01*
G01X-306000Y1053700D02*
Y1061700D01*
X-303600D01*
X-302800Y1061300D01*
X-302200Y1060367D01*
X-302000Y1059300D01*
X-302200Y1058233D01*
X-302700Y1057433D01*
X-303600Y1057033D01*
X-306000D01*
G01X-294000Y1053700D02*
X-298000D01*
Y1061700D01*
X-294000D01*
G01X-295600Y1057833D02*
X-298000D01*
G01X-285800Y1061033D02*
X-286400Y1061433D01*
X-287100Y1061700D01*
X-287900D01*
X-288800Y1061300D01*
X-289500Y1060633D01*
X-290000Y1059833D01*
X-290400Y1058500D01*
X-290500Y1057300D01*
X-290300Y1056100D01*
X-290000Y1055300D01*
X-289400Y1054500D01*
X-288700Y1053967D01*
X-288000Y1053700D01*
X-287300D01*
X-286600Y1053967D01*
X-286000Y1054367D01*
X-285500Y1054900D01*
G01X-281200Y1061700D02*
X-278800D01*
G01X-280000D02*
Y1053700D01*
G01X-281200D02*
X-278800D01*
G01X-274500D02*
X-272000Y1061700D01*
X-269500Y1053700D01*
G01X-270400Y1056500D02*
X-273600D01*
G01X-266000Y1061700D02*
Y1053700D01*
X-262000D01*
G01X-250200D02*
Y1061700D01*
X-248200D01*
X-247400Y1061300D01*
X-246800Y1060767D01*
X-246300Y1059967D01*
X-245900Y1059033D01*
X-245800Y1057700D01*
X-245900Y1056367D01*
X-246300Y1055433D01*
X-246800Y1054633D01*
X-247400Y1054100D01*
X-248200Y1053700D01*
X-250200D01*
G01X-242000D02*
Y1061700D01*
X-239500D01*
X-238700Y1061300D01*
X-238200Y1060767D01*
X-238000Y1059700D01*
X-238200Y1058633D01*
X-238800Y1057967D01*
X-239500Y1057567D01*
X-242000D01*
G01X-239500D02*
X-238000Y1053700D01*
G01X-233200Y1061700D02*
X-230800D01*
G01X-232000D02*
Y1053700D01*
G01X-233200D02*
X-230800D01*
G01X-226000Y1061700D02*
Y1053700D01*
X-222000D01*
G01X-218000Y1061700D02*
Y1053700D01*
X-214000D01*
G01X-202500D02*
X-200000Y1061700D01*
X-197500Y1053700D01*
G01X-198400Y1056500D02*
X-201600D01*
G01X-194300Y1053700D02*
Y1061700D01*
X-189700Y1053700D01*
Y1061700D01*
G01X-186200Y1053700D02*
Y1061700D01*
X-184200D01*
X-183400Y1061300D01*
X-182800Y1060767D01*
X-182300Y1059967D01*
X-181900Y1059033D01*
X-181800Y1057700D01*
X-181900Y1056367D01*
X-182300Y1055433D01*
X-182800Y1054633D01*
X-183400Y1054100D01*
X-184200Y1053700D01*
X-186200D01*
G01X-170100Y1054766D02*
X-169300Y1054100D01*
X-168400Y1053700D01*
X-167600D01*
X-166800Y1054100D01*
X-166200Y1054766D01*
X-165900Y1055700D01*
X-166100Y1056633D01*
X-166600Y1057433D01*
X-167500Y1057967D01*
X-168700Y1058233D01*
X-169400Y1058767D01*
X-169700Y1059700D01*
X-169500Y1060633D01*
X-169000Y1061300D01*
X-168300Y1061700D01*
X-167600D01*
X-166900Y1061433D01*
X-166300Y1060767D01*
G01X-160000Y1061700D02*
Y1053700D01*
G01X-162300Y1061700D02*
X-157700D01*
G01X-154500Y1053700D02*
X-152000Y1061700D01*
X-149500Y1053700D01*
G01X-150400Y1056500D02*
X-153600D01*
G01X-141800Y1061033D02*
X-142400Y1061433D01*
X-143100Y1061700D01*
X-143900D01*
X-144800Y1061300D01*
X-145500Y1060633D01*
X-146000Y1059833D01*
X-146400Y1058500D01*
X-146500Y1057300D01*
X-146300Y1056100D01*
X-146000Y1055300D01*
X-145400Y1054500D01*
X-144700Y1053967D01*
X-144000Y1053700D01*
X-143300D01*
X-142600Y1053967D01*
X-142000Y1054367D01*
X-141500Y1054900D01*
G01X-138200Y1053700D02*
Y1061700D01*
G01X-134400D02*
X-138200Y1056766D01*
G01X-133800Y1053700D02*
X-136500Y1059033D01*
G01X-126000Y1053700D02*
X-130000D01*
Y1061700D01*
X-126000D01*
G01X-127600Y1057833D02*
X-130000D01*
G01X-122200Y1053700D02*
Y1061700D01*
X-120200D01*
X-119400Y1061300D01*
X-118800Y1060767D01*
X-118300Y1059967D01*
X-117900Y1059033D01*
X-117800Y1057700D01*
X-117900Y1056367D01*
X-118300Y1055433D01*
X-118800Y1054633D01*
X-119400Y1054100D01*
X-120200Y1053700D01*
X-122200D01*
G01X-106100D02*
Y1061700D01*
G01X-101900D02*
Y1053700D01*
G01Y1057700D02*
X-106100D01*
G01X-96000Y1053700D02*
X-96800Y1053833D01*
X-97500Y1054367D01*
X-98100Y1055167D01*
X-98500Y1056100D01*
X-98700Y1057167D01*
Y1058233D01*
X-98500Y1059300D01*
X-98100Y1060233D01*
X-97500Y1061033D01*
X-96800Y1061567D01*
X-96000Y1061700D01*
X-95200Y1061567D01*
X-94500Y1061033D01*
X-93900Y1060233D01*
X-93500Y1059300D01*
X-93300Y1058233D01*
Y1057167D01*
X-93500Y1056100D01*
X-93900Y1055167D01*
X-94500Y1054367D01*
X-95200Y1053833D01*
X-96000Y1053700D01*
G01X-90000Y1061700D02*
Y1053700D01*
X-86000D01*
G01X-78000D02*
X-82000D01*
Y1061700D01*
X-78000D01*
G01X-79600Y1057833D02*
X-82000D01*
G01X-66000Y1053700D02*
Y1061700D01*
X-63600D01*
X-62800Y1061300D01*
X-62200Y1060367D01*
X-62000Y1059300D01*
X-62200Y1058233D01*
X-62700Y1057433D01*
X-63600Y1057033D01*
X-66000D01*
G01X-58000Y1061700D02*
Y1053700D01*
X-54000D01*
G01X-46000D02*
X-50000D01*
Y1061700D01*
X-46000D01*
G01X-47600Y1057833D02*
X-50000D01*
G01X-42500Y1053700D02*
X-40000Y1061700D01*
X-37500Y1053700D01*
G01X-38400Y1056500D02*
X-41600D01*
G01X-34100Y1054766D02*
X-33300Y1054100D01*
X-32400Y1053700D01*
X-31600D01*
X-30800Y1054100D01*
X-30200Y1054766D01*
X-29900Y1055700D01*
X-30100Y1056633D01*
X-30600Y1057433D01*
X-31500Y1057967D01*
X-32700Y1058233D01*
X-33400Y1058767D01*
X-33700Y1059700D01*
X-33500Y1060633D01*
X-33000Y1061300D01*
X-32300Y1061700D01*
X-31600D01*
X-30900Y1061433D01*
X-30300Y1060767D01*
G01X-22000Y1053700D02*
X-26000D01*
Y1061700D01*
X-22000D01*
G01X-23600Y1057833D02*
X-26000D01*
G01X-9900Y1053700D02*
Y1061700D01*
X-6100D01*
G01X-7500Y1057833D02*
X-9900D01*
G01X0Y1053700D02*
X-800Y1053833D01*
X-1500Y1054367D01*
X-2100Y1055167D01*
X-2500Y1056100D01*
X-2700Y1057167D01*
Y1058233D01*
X-2500Y1059300D01*
X-2100Y1060233D01*
X-1500Y1061033D01*
X-800Y1061567D01*
X0Y1061700D01*
X800Y1061567D01*
X1500Y1061033D01*
X2100Y1060233D01*
X2500Y1059300D01*
X2700Y1058233D01*
Y1057167D01*
X2500Y1056100D01*
X2100Y1055167D01*
X1500Y1054367D01*
X800Y1053833D01*
X0Y1053700D01*
G01X6000Y1061700D02*
Y1053700D01*
X10000D01*
G01X14000Y1061700D02*
Y1053700D01*
X18000D01*
G01X24000D02*
X23200Y1053833D01*
X22500Y1054367D01*
X21900Y1055167D01*
X21500Y1056100D01*
X21300Y1057167D01*
Y1058233D01*
X21500Y1059300D01*
X21900Y1060233D01*
X22500Y1061033D01*
X23200Y1061567D01*
X24000Y1061700D01*
X24800Y1061567D01*
X25500Y1061033D01*
X26100Y1060233D01*
X26500Y1059300D01*
X26700Y1058233D01*
Y1057167D01*
X26500Y1056100D01*
X26100Y1055167D01*
X25500Y1054367D01*
X24800Y1053833D01*
X24000Y1053700D01*
G01X29000Y1061700D02*
X30400Y1053700D01*
X32000Y1061700D01*
X33600Y1053700D01*
X35000Y1061700D01*
G01X48000Y1053700D02*
X47200Y1053833D01*
X46500Y1054367D01*
X45900Y1055167D01*
X45500Y1056100D01*
X45300Y1057167D01*
Y1058233D01*
X45500Y1059300D01*
X45900Y1060233D01*
X46500Y1061033D01*
X47200Y1061567D01*
X48000Y1061700D01*
X48800Y1061567D01*
X49500Y1061033D01*
X50100Y1060233D01*
X50500Y1059300D01*
X50700Y1058233D01*
Y1057167D01*
X50500Y1056100D01*
X50100Y1055167D01*
X49500Y1054367D01*
X48800Y1053833D01*
X48000Y1053700D01*
G01X53800Y1061700D02*
Y1055967D01*
X54200Y1054766D01*
X55000Y1053967D01*
X56000Y1053700D01*
X57000Y1053967D01*
X57800Y1054766D01*
X58200Y1055967D01*
Y1061700D01*
G01X64000D02*
Y1053700D01*
G01X61700Y1061700D02*
X66300D01*
G01X70000D02*
Y1053700D01*
X74000D01*
G01X78800Y1061700D02*
X81200D01*
G01X80000D02*
Y1053700D01*
G01X78800D02*
X81200D01*
G01X85700D02*
Y1061700D01*
X90300Y1053700D01*
Y1061700D01*
G01X98000Y1053700D02*
X94000D01*
Y1061700D01*
X98000D01*
G01X96400Y1057833D02*
X94000D01*
G01X104000Y1053433D02*
X103800Y1053567D01*
Y1053833D01*
X104000Y1053967D01*
X104200Y1053833D01*
Y1053567D01*
X104000Y1053433D01*
G01X118000Y1053700D02*
Y1061700D01*
X120400D01*
X121200Y1061300D01*
X121800Y1060367D01*
X122000Y1059300D01*
X121800Y1058233D01*
X121300Y1057433D01*
X120400Y1057033D01*
X118000D01*
G01X128000Y1061700D02*
Y1053700D01*
G01X125700Y1061700D02*
X130300D01*
G01X133900Y1053700D02*
Y1061700D01*
G01X138100D02*
Y1053700D01*
G01Y1057700D02*
X133900D01*
G01X152000Y1061700D02*
Y1053700D01*
G01X149700Y1061700D02*
X154300D01*
G01X160000Y1053700D02*
X159200Y1053833D01*
X158500Y1054367D01*
X157900Y1055167D01*
X157500Y1056100D01*
X157300Y1057167D01*
Y1058233D01*
X157500Y1059300D01*
X157900Y1060233D01*
X158500Y1061033D01*
X159200Y1061567D01*
X160000Y1061700D01*
X160800Y1061567D01*
X161500Y1061033D01*
X162100Y1060233D01*
X162500Y1059300D01*
X162700Y1058233D01*
Y1057167D01*
X162500Y1056100D01*
X162100Y1055167D01*
X161500Y1054367D01*
X160800Y1053833D01*
X160000Y1053700D01*
G01X166000Y1061700D02*
Y1053700D01*
X170000D01*
G01X178000D02*
X174000D01*
Y1061700D01*
X178000D01*
G01X176400Y1057833D02*
X174000D01*
G01X182000Y1053700D02*
Y1061700D01*
X184500D01*
X185300Y1061300D01*
X185800Y1060767D01*
X186000Y1059700D01*
X185800Y1058633D01*
X185200Y1057967D01*
X184500Y1057567D01*
X182000D01*
G01X184500D02*
X186000Y1053700D01*
G01X189500D02*
X192000Y1061700D01*
X194500Y1053700D01*
G01X193600Y1056500D02*
X190400D01*
G01X197700Y1053700D02*
Y1061700D01*
X202300Y1053700D01*
Y1061700D01*
G01X210200Y1061033D02*
X209600Y1061433D01*
X208900Y1061700D01*
X208100D01*
X207200Y1061300D01*
X206500Y1060633D01*
X206000Y1059833D01*
X205600Y1058500D01*
X205500Y1057300D01*
X205700Y1056100D01*
X206000Y1055300D01*
X206600Y1054500D01*
X207300Y1053967D01*
X208000Y1053700D01*
X208700D01*
X209400Y1053967D01*
X210000Y1054367D01*
X210500Y1054900D01*
G01X218000Y1053700D02*
X214000D01*
Y1061700D01*
X218000D01*
G01X216400Y1057833D02*
X214000D01*
G01X232000Y1053433D02*
X231800Y1053567D01*
Y1053833D01*
X232000Y1053967D01*
X232200Y1053833D01*
Y1053567D01*
X232000Y1053433D01*
G01Y1057033D02*
X231800Y1057167D01*
Y1057433D01*
X232000Y1057567D01*
X232200Y1057433D01*
Y1057167D01*
X232000Y1057033D01*
G01X246900Y1056367D02*
X249300D01*
G01X248000Y1058100D02*
Y1054633D01*
G01X254200Y1053433D02*
X257800Y1061700D01*
G01X262700Y1056367D02*
X265300D01*
G01X269800Y1054900D02*
X270400Y1054233D01*
X271100Y1053833D01*
X272000Y1053700D01*
X272900Y1053967D01*
X273600Y1054500D01*
X274100Y1055433D01*
X274200Y1056500D01*
X274000Y1057567D01*
X273500Y1058233D01*
X272800Y1058767D01*
X272100Y1058900D01*
X271400Y1058767D01*
X270500Y1058233D01*
X270800Y1061700D01*
X273500D01*
G01X279500Y1051033D02*
X278500Y1052367D01*
X278000Y1053700D01*
Y1059033D01*
X278500Y1060367D01*
X279500Y1061700D01*
G01X285400Y1053700D02*
Y1061700D01*
X288000Y1055033D01*
X290600Y1061700D01*
Y1053700D01*
G01X294800Y1061700D02*
X297200D01*
G01X296000D02*
Y1053700D01*
G01X294800D02*
X297200D01*
G01X302000Y1061700D02*
Y1053700D01*
X306000D01*
G01X312500Y1051033D02*
X313500Y1052367D01*
X314000Y1053700D01*
Y1059033D01*
X313500Y1060367D01*
X312500Y1061700D01*
G01X319800Y1052233D02*
X320200Y1053967D01*
G01X333700Y1053700D02*
Y1061700D01*
X338300Y1053700D01*
Y1061700D01*
G01X342000Y1053700D02*
Y1061700D01*
X344400D01*
X345200Y1061300D01*
X345800Y1060367D01*
X346000Y1059300D01*
X345800Y1058233D01*
X345300Y1057433D01*
X344400Y1057033D01*
X342000D01*
G01X352000Y1061700D02*
Y1053700D01*
G01X349700Y1061700D02*
X354300D01*
G01X357900Y1053700D02*
Y1061700D01*
G01X362100D02*
Y1053700D01*
G01Y1057700D02*
X357900D01*
G01X376000Y1061700D02*
Y1053700D01*
G01X373700Y1061700D02*
X378300D01*
G01X384000Y1053700D02*
X383200Y1053833D01*
X382500Y1054367D01*
X381900Y1055167D01*
X381500Y1056100D01*
X381300Y1057167D01*
Y1058233D01*
X381500Y1059300D01*
X381900Y1060233D01*
X382500Y1061033D01*
X383200Y1061567D01*
X384000Y1061700D01*
X384800Y1061567D01*
X385500Y1061033D01*
X386100Y1060233D01*
X386500Y1059300D01*
X386700Y1058233D01*
Y1057167D01*
X386500Y1056100D01*
X386100Y1055167D01*
X385500Y1054367D01*
X384800Y1053833D01*
X384000Y1053700D01*
G01X390000Y1061700D02*
Y1053700D01*
X394000D01*
G01X402000D02*
X398000D01*
Y1061700D01*
X402000D01*
G01X400400Y1057833D02*
X398000D01*
G01X406000Y1053700D02*
Y1061700D01*
X408500D01*
X409300Y1061300D01*
X409800Y1060767D01*
X410000Y1059700D01*
X409800Y1058633D01*
X409200Y1057967D01*
X408500Y1057567D01*
X406000D01*
G01X408500D02*
X410000Y1053700D01*
G01X413500D02*
X416000Y1061700D01*
X418500Y1053700D01*
G01X417600Y1056500D02*
X414400D01*
G01X421700Y1053700D02*
Y1061700D01*
X426300Y1053700D01*
Y1061700D01*
G01X434200Y1061033D02*
X433600Y1061433D01*
X432900Y1061700D01*
X432100D01*
X431200Y1061300D01*
X430500Y1060633D01*
X430000Y1059833D01*
X429600Y1058500D01*
X429500Y1057300D01*
X429700Y1056100D01*
X430000Y1055300D01*
X430600Y1054500D01*
X431300Y1053967D01*
X432000Y1053700D01*
X432700D01*
X433400Y1053967D01*
X434000Y1054367D01*
X434500Y1054900D01*
G01X442000Y1053700D02*
X438000D01*
Y1061700D01*
X442000D01*
G01X440400Y1057833D02*
X438000D01*
G01X448000Y1053433D02*
X447800Y1053567D01*
Y1053833D01*
X448000Y1053967D01*
X448200Y1053833D01*
Y1053567D01*
X448000Y1053433D01*
G01Y1057033D02*
X447800Y1057167D01*
Y1057433D01*
X448000Y1057567D01*
X448200Y1057433D01*
Y1057167D01*
X448000Y1057033D01*
G01X462900Y1056367D02*
X465300D01*
G01X464000Y1058100D02*
Y1054633D01*
G01X470200Y1053433D02*
X473800Y1061700D01*
G01X478700Y1056367D02*
X481300D01*
G01X489200Y1053700D02*
Y1061700D01*
X485500Y1055967D01*
X490500D01*
G01X495500Y1051033D02*
X494500Y1052367D01*
X494000Y1053700D01*
Y1059033D01*
X494500Y1060367D01*
X495500Y1061700D01*
G01X501400Y1053700D02*
Y1061700D01*
X504000Y1055033D01*
X506600Y1061700D01*
Y1053700D01*
G01X510800Y1061700D02*
X513200D01*
G01X512000D02*
Y1053700D01*
G01X510800D02*
X513200D01*
G01X518000Y1061700D02*
Y1053700D01*
X522000D01*
G01X528500Y1051033D02*
X529500Y1052367D01*
X530000Y1053700D01*
Y1059033D01*
X529500Y1060367D01*
X528500Y1061700D01*
G01X536000Y1053433D02*
X535800Y1053567D01*
Y1053833D01*
X536000Y1053967D01*
X536200Y1053833D01*
Y1053567D01*
X536000Y1053433D01*
G01X-360000Y1068700D02*
X-359300Y1068833D01*
X-358500Y1069233D01*
X-358000Y1069900D01*
X-357800Y1070833D01*
X-358000Y1071766D01*
X-358600Y1072567D01*
X-359500Y1072967D01*
X-360500D01*
X-361100Y1073233D01*
X-361600Y1073900D01*
X-361800Y1074833D01*
X-361500Y1075767D01*
X-360800Y1076433D01*
X-360000Y1076700D01*
X-359200Y1076433D01*
X-358500Y1075767D01*
X-358200Y1074833D01*
X-358400Y1073900D01*
X-358900Y1073233D01*
X-359500Y1072967D01*
X-360500D01*
X-361400Y1072567D01*
X-362000Y1071766D01*
X-362200Y1070833D01*
X-362000Y1069900D01*
X-361500Y1069233D01*
X-360700Y1068833D01*
X-360000Y1068700D01*
G01X-352000Y1068433D02*
X-352200Y1068567D01*
Y1068833D01*
X-352000Y1068967D01*
X-351800Y1068833D01*
Y1068567D01*
X-352000Y1068433D01*
G01X-346300Y1068700D02*
Y1076700D01*
X-341700Y1068700D01*
Y1076700D01*
G01X-336000Y1068700D02*
X-336800Y1068833D01*
X-337500Y1069367D01*
X-338100Y1070167D01*
X-338500Y1071100D01*
X-338700Y1072167D01*
Y1073233D01*
X-338500Y1074300D01*
X-338100Y1075233D01*
X-337500Y1076033D01*
X-336800Y1076567D01*
X-336000Y1076700D01*
X-335200Y1076567D01*
X-334500Y1076033D01*
X-333900Y1075233D01*
X-333500Y1074300D01*
X-333300Y1073233D01*
Y1072167D01*
X-333500Y1071100D01*
X-333900Y1070167D01*
X-334500Y1069367D01*
X-335200Y1068833D01*
X-336000Y1068700D01*
G01X-328000Y1076700D02*
Y1068700D01*
G01X-330300Y1076700D02*
X-325700D01*
G01X-314500Y1068700D02*
X-312000Y1076700D01*
X-309500Y1068700D01*
G01X-310400Y1071500D02*
X-313600D01*
G01X-306000Y1076700D02*
Y1068700D01*
X-302000D01*
G01X-298000Y1076700D02*
Y1068700D01*
X-294000D01*
G01X-288000D02*
X-288800Y1068833D01*
X-289500Y1069367D01*
X-290100Y1070167D01*
X-290500Y1071100D01*
X-290700Y1072167D01*
Y1073233D01*
X-290500Y1074300D01*
X-290100Y1075233D01*
X-289500Y1076033D01*
X-288800Y1076567D01*
X-288000Y1076700D01*
X-287200Y1076567D01*
X-286500Y1076033D01*
X-285900Y1075233D01*
X-285500Y1074300D01*
X-285300Y1073233D01*
Y1072167D01*
X-285500Y1071100D01*
X-285900Y1070167D01*
X-286500Y1069367D01*
X-287200Y1068833D01*
X-288000Y1068700D01*
G01X-283000Y1076700D02*
X-281600Y1068700D01*
X-280000Y1076700D01*
X-278400Y1068700D01*
X-277000Y1076700D01*
G01X-263200Y1072967D02*
X-262800Y1073367D01*
X-262500Y1074033D01*
X-262300Y1074967D01*
X-262500Y1075767D01*
X-262900Y1076300D01*
X-263600Y1076700D01*
X-266300D01*
Y1068700D01*
X-263000D01*
X-262300Y1069233D01*
X-261900Y1070033D01*
X-261700Y1070967D01*
X-261900Y1071900D01*
X-262500Y1072700D01*
X-263200Y1072967D01*
X-266300D01*
G01X-258000Y1068700D02*
Y1076700D01*
X-255500D01*
X-254700Y1076300D01*
X-254200Y1075767D01*
X-254000Y1074700D01*
X-254200Y1073633D01*
X-254800Y1072967D01*
X-255500Y1072567D01*
X-258000D01*
G01X-255500D02*
X-254000Y1068700D01*
G01X-246000D02*
X-250000D01*
Y1076700D01*
X-246000D01*
G01X-247600Y1072833D02*
X-250000D01*
G01X-242500Y1068700D02*
X-240000Y1076700D01*
X-237500Y1068700D01*
G01X-238400Y1071500D02*
X-241600D01*
G01X-234200Y1068700D02*
Y1076700D01*
G01X-230400D02*
X-234200Y1071766D01*
G01X-229800Y1068700D02*
X-232500Y1074033D01*
G01X-224000Y1068700D02*
X-224800Y1068833D01*
X-225500Y1069367D01*
X-226100Y1070167D01*
X-226500Y1071100D01*
X-226700Y1072167D01*
Y1073233D01*
X-226500Y1074300D01*
X-226100Y1075233D01*
X-225500Y1076033D01*
X-224800Y1076567D01*
X-224000Y1076700D01*
X-223200Y1076567D01*
X-222500Y1076033D01*
X-221900Y1075233D01*
X-221500Y1074300D01*
X-221300Y1073233D01*
Y1072167D01*
X-221500Y1071100D01*
X-221900Y1070167D01*
X-222500Y1069367D01*
X-223200Y1068833D01*
X-224000Y1068700D01*
G01X-218200Y1076700D02*
Y1070967D01*
X-217800Y1069766D01*
X-217000Y1068967D01*
X-216000Y1068700D01*
X-215000Y1068967D01*
X-214200Y1069766D01*
X-213800Y1070967D01*
Y1076700D01*
G01X-208000D02*
Y1068700D01*
G01X-210300Y1076700D02*
X-205700D01*
G01X-193900Y1068700D02*
Y1076700D01*
X-190100D01*
G01X-191500Y1072833D02*
X-193900D01*
G01X-184000Y1068700D02*
X-184800Y1068833D01*
X-185500Y1069367D01*
X-186100Y1070167D01*
X-186500Y1071100D01*
X-186700Y1072167D01*
Y1073233D01*
X-186500Y1074300D01*
X-186100Y1075233D01*
X-185500Y1076033D01*
X-184800Y1076567D01*
X-184000Y1076700D01*
X-183200Y1076567D01*
X-182500Y1076033D01*
X-181900Y1075233D01*
X-181500Y1074300D01*
X-181300Y1073233D01*
Y1072167D01*
X-181500Y1071100D01*
X-181900Y1070167D01*
X-182500Y1069367D01*
X-183200Y1068833D01*
X-184000Y1068700D01*
G01X-178000D02*
Y1076700D01*
X-175500D01*
X-174700Y1076300D01*
X-174200Y1075767D01*
X-174000Y1074700D01*
X-174200Y1073633D01*
X-174800Y1072967D01*
X-175500Y1072567D01*
X-178000D01*
G01X-175500D02*
X-174000Y1068700D01*
G01X-162000Y1076700D02*
Y1068700D01*
X-158000D01*
G01X-154500D02*
X-152000Y1076700D01*
X-149500Y1068700D01*
G01X-150400Y1071500D02*
X-153600D01*
G01X-146100Y1069766D02*
X-145300Y1069100D01*
X-144400Y1068700D01*
X-143600D01*
X-142800Y1069100D01*
X-142200Y1069766D01*
X-141900Y1070700D01*
X-142100Y1071633D01*
X-142600Y1072433D01*
X-143500Y1072967D01*
X-144700Y1073233D01*
X-145400Y1073767D01*
X-145700Y1074700D01*
X-145500Y1075633D01*
X-145000Y1076300D01*
X-144300Y1076700D01*
X-143600D01*
X-142900Y1076433D01*
X-142300Y1075767D01*
G01X-134000Y1068700D02*
X-138000D01*
Y1076700D01*
X-134000D01*
G01X-135600Y1072833D02*
X-138000D01*
G01X-130000Y1068700D02*
Y1076700D01*
X-127500D01*
X-126700Y1076300D01*
X-126200Y1075767D01*
X-126000Y1074700D01*
X-126200Y1073633D01*
X-126800Y1072967D01*
X-127500Y1072567D01*
X-130000D01*
G01X-127500D02*
X-126000Y1068700D01*
G01X-114500Y1076700D02*
X-112000Y1068700D01*
X-109500Y1076700D01*
G01X-105200D02*
X-102800D01*
G01X-104000D02*
Y1068700D01*
G01X-105200D02*
X-102800D01*
G01X-98500D02*
X-96000Y1076700D01*
X-93500Y1068700D01*
G01X-94400Y1071500D02*
X-97600D01*
G01X-82100Y1068700D02*
Y1076700D01*
G01X-77900D02*
Y1068700D01*
G01Y1072700D02*
X-82100D01*
G01X-72000Y1068700D02*
X-72800Y1068833D01*
X-73500Y1069367D01*
X-74100Y1070167D01*
X-74500Y1071100D01*
X-74700Y1072167D01*
Y1073233D01*
X-74500Y1074300D01*
X-74100Y1075233D01*
X-73500Y1076033D01*
X-72800Y1076567D01*
X-72000Y1076700D01*
X-71200Y1076567D01*
X-70500Y1076033D01*
X-69900Y1075233D01*
X-69500Y1074300D01*
X-69300Y1073233D01*
Y1072167D01*
X-69500Y1071100D01*
X-69900Y1070167D01*
X-70500Y1069367D01*
X-71200Y1068833D01*
X-72000Y1068700D01*
G01X-66000Y1076700D02*
Y1068700D01*
X-62000D01*
G01X-54000D02*
X-58000D01*
Y1076700D01*
X-54000D01*
G01X-55600Y1072833D02*
X-58000D01*
G01X-48000Y1068433D02*
X-48200Y1068567D01*
Y1068833D01*
X-48000Y1068967D01*
X-47800Y1068833D01*
Y1068567D01*
X-48000Y1068433D01*
G01X-360200Y1083700D02*
X-360000Y1085433D01*
X-359700Y1086900D01*
X-359300Y1088233D01*
X-358800Y1089700D01*
X-358000Y1091700D01*
X-362000D01*
G01X-352000Y1083433D02*
X-352200Y1083567D01*
Y1083833D01*
X-352000Y1083967D01*
X-351800Y1083833D01*
Y1083567D01*
X-352000Y1083433D01*
G01X-345900Y1083700D02*
Y1091700D01*
X-342100D01*
G01X-343500Y1087833D02*
X-345900D01*
G01X-336000Y1083700D02*
X-336800Y1083833D01*
X-337500Y1084367D01*
X-338100Y1085167D01*
X-338500Y1086100D01*
X-338700Y1087167D01*
Y1088233D01*
X-338500Y1089300D01*
X-338100Y1090233D01*
X-337500Y1091033D01*
X-336800Y1091567D01*
X-336000Y1091700D01*
X-335200Y1091567D01*
X-334500Y1091033D01*
X-333900Y1090233D01*
X-333500Y1089300D01*
X-333300Y1088233D01*
Y1087167D01*
X-333500Y1086100D01*
X-333900Y1085167D01*
X-334500Y1084367D01*
X-335200Y1083833D01*
X-336000Y1083700D01*
G01X-330000D02*
Y1091700D01*
X-327500D01*
X-326700Y1091300D01*
X-326200Y1090767D01*
X-326000Y1089700D01*
X-326200Y1088633D01*
X-326800Y1087967D01*
X-327500Y1087567D01*
X-330000D01*
G01X-327500D02*
X-326000Y1083700D01*
G01X-312000D02*
Y1091700D01*
X-313200Y1090100D01*
G01Y1083700D02*
X-310800D01*
G01X-304000Y1091700D02*
X-304800Y1091433D01*
X-305400Y1090767D01*
X-305800Y1089967D01*
X-306100Y1088900D01*
X-306200Y1087700D01*
X-306100Y1086500D01*
X-305800Y1085433D01*
X-305400Y1084633D01*
X-304800Y1083967D01*
X-304000Y1083700D01*
X-303200Y1083967D01*
X-302600Y1084633D01*
X-302200Y1085433D01*
X-301900Y1086500D01*
X-301800Y1087700D01*
X-301900Y1088900D01*
X-302200Y1089967D01*
X-302600Y1090767D01*
X-303200Y1091433D01*
X-304000Y1091700D01*
G01X-298600Y1083700D02*
Y1091700D01*
X-296000Y1085033D01*
X-293400Y1091700D01*
Y1083700D01*
G01X-289200Y1091700D02*
X-286800D01*
G01X-288000D02*
Y1083700D01*
G01X-289200D02*
X-286800D01*
G01X-282000Y1091700D02*
Y1083700D01*
X-278000D01*
G01X-274100Y1084766D02*
X-273300Y1084100D01*
X-272400Y1083700D01*
X-271600D01*
X-270800Y1084100D01*
X-270200Y1084766D01*
X-269900Y1085700D01*
X-270100Y1086633D01*
X-270600Y1087433D01*
X-271500Y1087967D01*
X-272700Y1088233D01*
X-273400Y1088767D01*
X-273700Y1089700D01*
X-273500Y1090633D01*
X-273000Y1091300D01*
X-272300Y1091700D01*
X-271600D01*
X-270900Y1091433D01*
X-270300Y1090767D01*
G01X-258500Y1091700D02*
X-256000Y1083700D01*
X-253500Y1091700D01*
G01X-249200D02*
X-246800D01*
G01X-248000D02*
Y1083700D01*
G01X-249200D02*
X-246800D01*
G01X-242500D02*
X-240000Y1091700D01*
X-237500Y1083700D01*
G01X-238400Y1086500D02*
X-241600D01*
G01X-234100Y1084766D02*
X-233300Y1084100D01*
X-232400Y1083700D01*
X-231600D01*
X-230800Y1084100D01*
X-230200Y1084766D01*
X-229900Y1085700D01*
X-230100Y1086633D01*
X-230600Y1087433D01*
X-231500Y1087967D01*
X-232700Y1088233D01*
X-233400Y1088767D01*
X-233700Y1089700D01*
X-233500Y1090633D01*
X-233000Y1091300D01*
X-232300Y1091700D01*
X-231600D01*
X-230900Y1091433D01*
X-230300Y1090767D01*
G01X-218200Y1091700D02*
Y1085967D01*
X-217800Y1084766D01*
X-217000Y1083967D01*
X-216000Y1083700D01*
X-215000Y1083967D01*
X-214200Y1084766D01*
X-213800Y1085967D01*
Y1091700D01*
G01X-210100Y1084766D02*
X-209300Y1084100D01*
X-208400Y1083700D01*
X-207600D01*
X-206800Y1084100D01*
X-206200Y1084766D01*
X-205900Y1085700D01*
X-206100Y1086633D01*
X-206600Y1087433D01*
X-207500Y1087967D01*
X-208700Y1088233D01*
X-209400Y1088767D01*
X-209700Y1089700D01*
X-209500Y1090633D01*
X-209000Y1091300D01*
X-208300Y1091700D01*
X-207600D01*
X-206900Y1091433D01*
X-206300Y1090767D01*
G01X-198000Y1083700D02*
X-202000D01*
Y1091700D01*
X-198000D01*
G01X-199600Y1087833D02*
X-202000D01*
G01X-185700Y1084633D02*
X-185000Y1083967D01*
X-184200Y1083700D01*
X-183400Y1083967D01*
X-182700Y1084766D01*
X-182200Y1085967D01*
X-182000Y1087167D01*
Y1088633D01*
X-182200Y1089833D01*
X-182700Y1090900D01*
X-183300Y1091433D01*
X-184000Y1091700D01*
X-184800Y1091433D01*
X-185400Y1090900D01*
X-185800Y1090100D01*
X-186000Y1089033D01*
X-185800Y1088100D01*
X-185300Y1087167D01*
X-184700Y1086633D01*
X-184000Y1086500D01*
X-183200Y1086766D01*
X-182600Y1087433D01*
X-182000Y1088633D01*
G01X-176000Y1083433D02*
X-176200Y1083567D01*
Y1083833D01*
X-176000Y1083967D01*
X-175800Y1083833D01*
Y1083567D01*
X-176000Y1083433D01*
G01X-168000Y1083700D02*
X-167300Y1083833D01*
X-166500Y1084233D01*
X-166000Y1084900D01*
X-165800Y1085833D01*
X-166000Y1086766D01*
X-166600Y1087567D01*
X-167500Y1087967D01*
X-168500D01*
X-169100Y1088233D01*
X-169600Y1088900D01*
X-169800Y1089833D01*
X-169500Y1090767D01*
X-168800Y1091433D01*
X-168000Y1091700D01*
X-167200Y1091433D01*
X-166500Y1090767D01*
X-166200Y1089833D01*
X-166400Y1088900D01*
X-166900Y1088233D01*
X-167500Y1087967D01*
X-168500D01*
X-169400Y1087567D01*
X-170000Y1086766D01*
X-170200Y1085833D01*
X-170000Y1084900D01*
X-169500Y1084233D01*
X-168700Y1083833D01*
X-168000Y1083700D01*
G01X-162600D02*
Y1091700D01*
X-160000Y1085033D01*
X-157400Y1091700D01*
Y1083700D01*
G01X-153200Y1091700D02*
X-150800D01*
G01X-152000D02*
Y1083700D01*
G01X-153200D02*
X-150800D01*
G01X-146000Y1091700D02*
Y1083700D01*
X-142000D01*
G01X-138100Y1084766D02*
X-137300Y1084100D01*
X-136400Y1083700D01*
X-135600D01*
X-134800Y1084100D01*
X-134200Y1084766D01*
X-133900Y1085700D01*
X-134100Y1086633D01*
X-134600Y1087433D01*
X-135500Y1087967D01*
X-136700Y1088233D01*
X-137400Y1088767D01*
X-137700Y1089700D01*
X-137500Y1090633D01*
X-137000Y1091300D01*
X-136300Y1091700D01*
X-135600D01*
X-134900Y1091433D01*
X-134300Y1090767D01*
G01X-122200Y1083700D02*
Y1091700D01*
X-120200D01*
X-119400Y1091300D01*
X-118800Y1090767D01*
X-118300Y1089967D01*
X-117900Y1089033D01*
X-117800Y1087700D01*
X-117900Y1086367D01*
X-118300Y1085433D01*
X-118800Y1084633D01*
X-119400Y1084100D01*
X-120200Y1083700D01*
X-122200D01*
G01X-114000D02*
Y1091700D01*
X-111500D01*
X-110700Y1091300D01*
X-110200Y1090767D01*
X-110000Y1089700D01*
X-110200Y1088633D01*
X-110800Y1087967D01*
X-111500Y1087567D01*
X-114000D01*
G01X-111500D02*
X-110000Y1083700D01*
G01X-105200Y1091700D02*
X-102800D01*
G01X-104000D02*
Y1083700D01*
G01X-105200D02*
X-102800D01*
G01X-98000Y1091700D02*
Y1083700D01*
X-94000D01*
G01X-90000Y1091700D02*
Y1083700D01*
X-86000D01*
G01X-71200Y1087967D02*
X-70800Y1088367D01*
X-70500Y1089033D01*
X-70300Y1089967D01*
X-70500Y1090767D01*
X-70900Y1091300D01*
X-71600Y1091700D01*
X-74300D01*
Y1083700D01*
X-71000D01*
X-70300Y1084233D01*
X-69900Y1085033D01*
X-69700Y1085967D01*
X-69900Y1086900D01*
X-70500Y1087700D01*
X-71200Y1087967D01*
X-74300D01*
G01X-65200Y1091700D02*
X-62800D01*
G01X-64000D02*
Y1083700D01*
G01X-65200D02*
X-62800D01*
G01X-56000Y1091700D02*
Y1083700D01*
G01X-58300Y1091700D02*
X-53700D01*
G01X-48000Y1083433D02*
X-48200Y1083567D01*
Y1083833D01*
X-48000Y1083967D01*
X-47800Y1083833D01*
Y1083567D01*
X-48000Y1083433D01*
G01X-33900Y1083700D02*
Y1091700D01*
X-30100D01*
G01X-31500Y1087833D02*
X-33900D01*
G01X-24000Y1083700D02*
X-24800Y1083833D01*
X-25500Y1084367D01*
X-26100Y1085167D01*
X-26500Y1086100D01*
X-26700Y1087167D01*
Y1088233D01*
X-26500Y1089300D01*
X-26100Y1090233D01*
X-25500Y1091033D01*
X-24800Y1091567D01*
X-24000Y1091700D01*
X-23200Y1091567D01*
X-22500Y1091033D01*
X-21900Y1090233D01*
X-21500Y1089300D01*
X-21300Y1088233D01*
Y1087167D01*
X-21500Y1086100D01*
X-21900Y1085167D01*
X-22500Y1084367D01*
X-23200Y1083833D01*
X-24000Y1083700D01*
G01X-18000D02*
Y1091700D01*
X-15500D01*
X-14700Y1091300D01*
X-14200Y1090767D01*
X-14000Y1089700D01*
X-14200Y1088633D01*
X-14800Y1087967D01*
X-15500Y1087567D01*
X-18000D01*
G01X-15500D02*
X-14000Y1083700D01*
G01X0D02*
X700Y1083833D01*
X1500Y1084233D01*
X2000Y1084900D01*
X2200Y1085833D01*
X2000Y1086766D01*
X1400Y1087567D01*
X500Y1087967D01*
X-500D01*
X-1100Y1088233D01*
X-1600Y1088900D01*
X-1800Y1089833D01*
X-1500Y1090767D01*
X-800Y1091433D01*
X0Y1091700D01*
X800Y1091433D01*
X1500Y1090767D01*
X1800Y1089833D01*
X1600Y1088900D01*
X1100Y1088233D01*
X500Y1087967D01*
X-500D01*
X-1400Y1087567D01*
X-2000Y1086766D01*
X-2200Y1085833D01*
X-2000Y1084900D01*
X-1500Y1084233D01*
X-700Y1083833D01*
X0Y1083700D01*
G01X5400D02*
Y1091700D01*
X8000Y1085033D01*
X10600Y1091700D01*
Y1083700D01*
G01X14800Y1091700D02*
X17200D01*
G01X16000D02*
Y1083700D01*
G01X14800D02*
X17200D01*
G01X22000Y1091700D02*
Y1083700D01*
X26000D01*
G01X29900Y1084766D02*
X30700Y1084100D01*
X31600Y1083700D01*
X32400D01*
X33200Y1084100D01*
X33800Y1084766D01*
X34100Y1085700D01*
X33900Y1086633D01*
X33400Y1087433D01*
X32500Y1087967D01*
X31300Y1088233D01*
X30600Y1088767D01*
X30300Y1089700D01*
X30500Y1090633D01*
X31000Y1091300D01*
X31700Y1091700D01*
X32400D01*
X33100Y1091433D01*
X33700Y1090767D01*
G01X45500Y1091700D02*
X48000Y1083700D01*
X50500Y1091700D01*
G01X54800D02*
X57200D01*
G01X56000D02*
Y1083700D01*
G01X54800D02*
X57200D01*
G01X61500D02*
X64000Y1091700D01*
X66500Y1083700D01*
G01X65600Y1086500D02*
X62400D01*
G01X69900Y1084766D02*
X70700Y1084100D01*
X71600Y1083700D01*
X72400D01*
X73200Y1084100D01*
X73800Y1084766D01*
X74100Y1085700D01*
X73900Y1086633D01*
X73400Y1087433D01*
X72500Y1087967D01*
X71300Y1088233D01*
X70600Y1088767D01*
X70300Y1089700D01*
X70500Y1090633D01*
X71000Y1091300D01*
X71700Y1091700D01*
X72400D01*
X73100Y1091433D01*
X73700Y1090767D01*
G01X85800Y1091700D02*
Y1085967D01*
X86200Y1084766D01*
X87000Y1083967D01*
X88000Y1083700D01*
X89000Y1083967D01*
X89800Y1084766D01*
X90200Y1085967D01*
Y1091700D01*
G01X93900Y1084766D02*
X94700Y1084100D01*
X95600Y1083700D01*
X96400D01*
X97200Y1084100D01*
X97800Y1084766D01*
X98100Y1085700D01*
X97900Y1086633D01*
X97400Y1087433D01*
X96500Y1087967D01*
X95300Y1088233D01*
X94600Y1088767D01*
X94300Y1089700D01*
X94500Y1090633D01*
X95000Y1091300D01*
X95700Y1091700D01*
X96400D01*
X97100Y1091433D01*
X97700Y1090767D01*
G01X106000Y1083700D02*
X102000D01*
Y1091700D01*
X106000D01*
G01X104400Y1087833D02*
X102000D01*
G01X119800Y1083700D02*
X120000Y1085433D01*
X120300Y1086900D01*
X120700Y1088233D01*
X121200Y1089700D01*
X122000Y1091700D01*
X118000D01*
G01X128000Y1083433D02*
X127800Y1083567D01*
Y1083833D01*
X128000Y1083967D01*
X128200Y1083833D01*
Y1083567D01*
X128000Y1083433D01*
G01X134300Y1084633D02*
X135000Y1083967D01*
X135800Y1083700D01*
X136600Y1083967D01*
X137300Y1084766D01*
X137800Y1085967D01*
X138000Y1087167D01*
Y1088633D01*
X137800Y1089833D01*
X137300Y1090900D01*
X136700Y1091433D01*
X136000Y1091700D01*
X135200Y1091433D01*
X134600Y1090900D01*
X134200Y1090100D01*
X134000Y1089033D01*
X134200Y1088100D01*
X134700Y1087167D01*
X135300Y1086633D01*
X136000Y1086500D01*
X136800Y1086766D01*
X137400Y1087433D01*
X138000Y1088633D01*
G01X141400Y1083700D02*
Y1091700D01*
X144000Y1085033D01*
X146600Y1091700D01*
Y1083700D01*
G01X150800Y1091700D02*
X153200D01*
G01X152000D02*
Y1083700D01*
G01X150800D02*
X153200D01*
G01X158000Y1091700D02*
Y1083700D01*
X162000D01*
G01X165900Y1084766D02*
X166700Y1084100D01*
X167600Y1083700D01*
X168400D01*
X169200Y1084100D01*
X169800Y1084766D01*
X170100Y1085700D01*
X169900Y1086633D01*
X169400Y1087433D01*
X168500Y1087967D01*
X167300Y1088233D01*
X166600Y1088767D01*
X166300Y1089700D01*
X166500Y1090633D01*
X167000Y1091300D01*
X167700Y1091700D01*
X168400D01*
X169100Y1091433D01*
X169700Y1090767D01*
G01X181800Y1083700D02*
Y1091700D01*
X183800D01*
X184600Y1091300D01*
X185200Y1090767D01*
X185700Y1089967D01*
X186100Y1089033D01*
X186200Y1087700D01*
X186100Y1086367D01*
X185700Y1085433D01*
X185200Y1084633D01*
X184600Y1084100D01*
X183800Y1083700D01*
X181800D01*
G01X190000D02*
Y1091700D01*
X192500D01*
X193300Y1091300D01*
X193800Y1090767D01*
X194000Y1089700D01*
X193800Y1088633D01*
X193200Y1087967D01*
X192500Y1087567D01*
X190000D01*
G01X192500D02*
X194000Y1083700D01*
G01X198800Y1091700D02*
X201200D01*
G01X200000D02*
Y1083700D01*
G01X198800D02*
X201200D01*
G01X206000Y1091700D02*
Y1083700D01*
X210000D01*
G01X214000Y1091700D02*
Y1083700D01*
X218000D01*
G01X232800Y1087967D02*
X233200Y1088367D01*
X233500Y1089033D01*
X233700Y1089967D01*
X233500Y1090767D01*
X233100Y1091300D01*
X232400Y1091700D01*
X229700D01*
Y1083700D01*
X233000D01*
X233700Y1084233D01*
X234100Y1085033D01*
X234300Y1085967D01*
X234100Y1086900D01*
X233500Y1087700D01*
X232800Y1087967D01*
X229700D01*
G01X238800Y1091700D02*
X241200D01*
G01X240000D02*
Y1083700D01*
G01X238800D02*
X241200D01*
G01X248000Y1091700D02*
Y1083700D01*
G01X245700Y1091700D02*
X250300D01*
G01X256000Y1083433D02*
X255800Y1083567D01*
Y1083833D01*
X256000Y1083967D01*
X256200Y1083833D01*
Y1083567D01*
X256000Y1083433D01*
G01X262100Y1083700D02*
Y1091700D01*
X265900D01*
G01X264500Y1087833D02*
X262100D01*
G01X272000Y1083700D02*
X271200Y1083833D01*
X270500Y1084367D01*
X269900Y1085167D01*
X269500Y1086100D01*
X269300Y1087167D01*
Y1088233D01*
X269500Y1089300D01*
X269900Y1090233D01*
X270500Y1091033D01*
X271200Y1091567D01*
X272000Y1091700D01*
X272800Y1091567D01*
X273500Y1091033D01*
X274100Y1090233D01*
X274500Y1089300D01*
X274700Y1088233D01*
Y1087167D01*
X274500Y1086100D01*
X274100Y1085167D01*
X273500Y1084367D01*
X272800Y1083833D01*
X272000Y1083700D01*
G01X278000D02*
Y1091700D01*
X280500D01*
X281300Y1091300D01*
X281800Y1090767D01*
X282000Y1089700D01*
X281800Y1088633D01*
X281200Y1087967D01*
X280500Y1087567D01*
X278000D01*
G01X280500D02*
X282000Y1083700D01*
G01X294100Y1090367D02*
X294700Y1091167D01*
X295400Y1091567D01*
X296200Y1091700D01*
X297200Y1091433D01*
X297900Y1090767D01*
X298100Y1089967D01*
X298000Y1089166D01*
X297600Y1088500D01*
X295600Y1087167D01*
X294700Y1086233D01*
X294100Y1084900D01*
X293900Y1083700D01*
X298100D01*
G01X304000Y1091700D02*
X303200Y1091433D01*
X302600Y1090767D01*
X302200Y1089967D01*
X301900Y1088900D01*
X301800Y1087700D01*
X301900Y1086500D01*
X302200Y1085433D01*
X302600Y1084633D01*
X303200Y1083967D01*
X304000Y1083700D01*
X304800Y1083967D01*
X305400Y1084633D01*
X305800Y1085433D01*
X306100Y1086500D01*
X306200Y1087700D01*
X306100Y1088900D01*
X305800Y1089967D01*
X305400Y1090767D01*
X304800Y1091433D01*
X304000Y1091700D01*
G01X309400Y1083700D02*
Y1091700D01*
X312000Y1085033D01*
X314600Y1091700D01*
Y1083700D01*
G01X318800Y1091700D02*
X321200D01*
G01X320000D02*
Y1083700D01*
G01X318800D02*
X321200D01*
G01X326000Y1091700D02*
Y1083700D01*
X330000D01*
G01X333900Y1084766D02*
X334700Y1084100D01*
X335600Y1083700D01*
X336400D01*
X337200Y1084100D01*
X337800Y1084766D01*
X338100Y1085700D01*
X337900Y1086633D01*
X337400Y1087433D01*
X336500Y1087967D01*
X335300Y1088233D01*
X334600Y1088767D01*
X334300Y1089700D01*
X334500Y1090633D01*
X335000Y1091300D01*
X335700Y1091700D01*
X336400D01*
X337100Y1091433D01*
X337700Y1090767D01*
G01X349500Y1091700D02*
X352000Y1083700D01*
X354500Y1091700D01*
G01X358800D02*
X361200D01*
G01X360000D02*
Y1083700D01*
G01X358800D02*
X361200D01*
G01X365500D02*
X368000Y1091700D01*
X370500Y1083700D01*
G01X369600Y1086500D02*
X366400D01*
G01X373900Y1084766D02*
X374700Y1084100D01*
X375600Y1083700D01*
X376400D01*
X377200Y1084100D01*
X377800Y1084766D01*
X378100Y1085700D01*
X377900Y1086633D01*
X377400Y1087433D01*
X376500Y1087967D01*
X375300Y1088233D01*
X374600Y1088767D01*
X374300Y1089700D01*
X374500Y1090633D01*
X375000Y1091300D01*
X375700Y1091700D01*
X376400D01*
X377100Y1091433D01*
X377700Y1090767D01*
G01X389800Y1091700D02*
Y1085967D01*
X390200Y1084766D01*
X391000Y1083967D01*
X392000Y1083700D01*
X393000Y1083967D01*
X393800Y1084766D01*
X394200Y1085967D01*
Y1091700D01*
G01X397900Y1084766D02*
X398700Y1084100D01*
X399600Y1083700D01*
X400400D01*
X401200Y1084100D01*
X401800Y1084766D01*
X402100Y1085700D01*
X401900Y1086633D01*
X401400Y1087433D01*
X400500Y1087967D01*
X399300Y1088233D01*
X398600Y1088767D01*
X398300Y1089700D01*
X398500Y1090633D01*
X399000Y1091300D01*
X399700Y1091700D01*
X400400D01*
X401100Y1091433D01*
X401700Y1090767D01*
G01X410000Y1083700D02*
X406000D01*
Y1091700D01*
X410000D01*
G01X408400Y1087833D02*
X406000D01*
G01X424000Y1083700D02*
Y1091700D01*
X422800Y1090100D01*
G01Y1083700D02*
X425200D01*
G01X430300Y1084633D02*
X431000Y1083967D01*
X431800Y1083700D01*
X432600Y1083967D01*
X433300Y1084766D01*
X433800Y1085967D01*
X434000Y1087167D01*
Y1088633D01*
X433800Y1089833D01*
X433300Y1090900D01*
X432700Y1091433D01*
X432000Y1091700D01*
X431200Y1091433D01*
X430600Y1090900D01*
X430200Y1090100D01*
X430000Y1089033D01*
X430200Y1088100D01*
X430700Y1087167D01*
X431300Y1086633D01*
X432000Y1086500D01*
X432800Y1086766D01*
X433400Y1087433D01*
X434000Y1088633D01*
G01X440000Y1083433D02*
X439800Y1083567D01*
Y1083833D01*
X440000Y1083967D01*
X440200Y1083833D01*
Y1083567D01*
X440000Y1083433D01*
G01X447800Y1083700D02*
X448000Y1085433D01*
X448300Y1086900D01*
X448700Y1088233D01*
X449200Y1089700D01*
X450000Y1091700D01*
X446000D01*
G01X453400Y1083700D02*
Y1091700D01*
X456000Y1085033D01*
X458600Y1091700D01*
Y1083700D01*
G01X462800Y1091700D02*
X465200D01*
G01X464000D02*
Y1083700D01*
G01X462800D02*
X465200D01*
G01X470000Y1091700D02*
Y1083700D01*
X474000D01*
G01X477900Y1084766D02*
X478700Y1084100D01*
X479600Y1083700D01*
X480400D01*
X481200Y1084100D01*
X481800Y1084766D01*
X482100Y1085700D01*
X481900Y1086633D01*
X481400Y1087433D01*
X480500Y1087967D01*
X479300Y1088233D01*
X478600Y1088767D01*
X478300Y1089700D01*
X478500Y1090633D01*
X479000Y1091300D01*
X479700Y1091700D01*
X480400D01*
X481100Y1091433D01*
X481700Y1090767D01*
G01X493800Y1083700D02*
Y1091700D01*
X495800D01*
X496600Y1091300D01*
X497200Y1090767D01*
X497700Y1089967D01*
X498100Y1089033D01*
X498200Y1087700D01*
X498100Y1086367D01*
X497700Y1085433D01*
X497200Y1084633D01*
X496600Y1084100D01*
X495800Y1083700D01*
X493800D01*
G01X502000D02*
Y1091700D01*
X504500D01*
X505300Y1091300D01*
X505800Y1090767D01*
X506000Y1089700D01*
X505800Y1088633D01*
X505200Y1087967D01*
X504500Y1087567D01*
X502000D01*
G01X504500D02*
X506000Y1083700D01*
G01X510800Y1091700D02*
X513200D01*
G01X512000D02*
Y1083700D01*
G01X510800D02*
X513200D01*
G01X518000Y1091700D02*
Y1083700D01*
X522000D01*
G01X526000Y1091700D02*
Y1083700D01*
X530000D01*
G01X544800Y1087967D02*
X545200Y1088367D01*
X545500Y1089033D01*
X545700Y1089967D01*
X545500Y1090767D01*
X545100Y1091300D01*
X544400Y1091700D01*
X541700D01*
Y1083700D01*
X545000D01*
X545700Y1084233D01*
X546100Y1085033D01*
X546300Y1085967D01*
X546100Y1086900D01*
X545500Y1087700D01*
X544800Y1087967D01*
X541700D01*
G01X550800Y1091700D02*
X553200D01*
G01X552000D02*
Y1083700D01*
G01X550800D02*
X553200D01*
G01X560000Y1091700D02*
Y1083700D01*
G01X557700Y1091700D02*
X562300D01*
G01X568000Y1083433D02*
X567800Y1083567D01*
Y1083833D01*
X568000Y1083967D01*
X568200Y1083833D01*
Y1083567D01*
X568000Y1083433D01*
G01X-361900Y1102033D02*
X-361200Y1102967D01*
X-360600Y1103500D01*
X-359800Y1103767D01*
X-359100Y1103500D01*
X-358600Y1102967D01*
X-358200Y1102167D01*
X-358100Y1101233D01*
X-358200Y1100433D01*
X-358600Y1099633D01*
X-359200Y1098967D01*
X-359900Y1098700D01*
X-360700Y1098967D01*
X-361400Y1099766D01*
X-361800Y1100967D01*
X-361900Y1102300D01*
X-361700Y1104033D01*
X-361400Y1104967D01*
X-360900Y1105900D01*
X-360200Y1106567D01*
X-359500Y1106700D01*
X-358800Y1106433D01*
X-358300Y1105767D01*
G01X-352000Y1098433D02*
X-352200Y1098567D01*
Y1098833D01*
X-352000Y1098967D01*
X-351800Y1098833D01*
Y1098567D01*
X-352000Y1098433D01*
G01X-345900Y1105367D02*
X-345300Y1106167D01*
X-344600Y1106567D01*
X-343800Y1106700D01*
X-342800Y1106433D01*
X-342100Y1105767D01*
X-341900Y1104967D01*
X-342000Y1104166D01*
X-342400Y1103500D01*
X-344400Y1102167D01*
X-345300Y1101233D01*
X-345900Y1099900D01*
X-346100Y1098700D01*
X-341900D01*
G01X-328000D02*
X-328800Y1098833D01*
X-329500Y1099367D01*
X-330100Y1100167D01*
X-330500Y1101100D01*
X-330700Y1102167D01*
Y1103233D01*
X-330500Y1104300D01*
X-330100Y1105233D01*
X-329500Y1106033D01*
X-328800Y1106567D01*
X-328000Y1106700D01*
X-327200Y1106567D01*
X-326500Y1106033D01*
X-325900Y1105233D01*
X-325500Y1104300D01*
X-325300Y1103233D01*
Y1102167D01*
X-325500Y1101100D01*
X-325900Y1100167D01*
X-326500Y1099367D01*
X-327200Y1098833D01*
X-328000Y1098700D01*
G01X-322200Y1106700D02*
Y1100967D01*
X-321800Y1099766D01*
X-321000Y1098967D01*
X-320000Y1098700D01*
X-319000Y1098967D01*
X-318200Y1099766D01*
X-317800Y1100967D01*
Y1106700D01*
G01X-312000D02*
Y1098700D01*
G01X-314300Y1106700D02*
X-309700D01*
G01X-306100Y1099766D02*
X-305300Y1099100D01*
X-304400Y1098700D01*
X-303600D01*
X-302800Y1099100D01*
X-302200Y1099766D01*
X-301900Y1100700D01*
X-302100Y1101633D01*
X-302600Y1102433D01*
X-303500Y1102967D01*
X-304700Y1103233D01*
X-305400Y1103767D01*
X-305700Y1104700D01*
X-305500Y1105633D01*
X-305000Y1106300D01*
X-304300Y1106700D01*
X-303600D01*
X-302900Y1106433D01*
X-302300Y1105767D01*
G01X-297200Y1106700D02*
X-294800D01*
G01X-296000D02*
Y1098700D01*
G01X-297200D02*
X-294800D01*
G01X-290200D02*
Y1106700D01*
X-288200D01*
X-287400Y1106300D01*
X-286800Y1105767D01*
X-286300Y1104967D01*
X-285900Y1104033D01*
X-285800Y1102700D01*
X-285900Y1101367D01*
X-286300Y1100433D01*
X-286800Y1099633D01*
X-287400Y1099100D01*
X-288200Y1098700D01*
X-290200D01*
G01X-278000D02*
X-282000D01*
Y1106700D01*
X-278000D01*
G01X-279600Y1102833D02*
X-282000D01*
G01X-263200Y1102967D02*
X-262800Y1103367D01*
X-262500Y1104033D01*
X-262300Y1104967D01*
X-262500Y1105767D01*
X-262900Y1106300D01*
X-263600Y1106700D01*
X-266300D01*
Y1098700D01*
X-263000D01*
X-262300Y1099233D01*
X-261900Y1100033D01*
X-261700Y1100967D01*
X-261900Y1101900D01*
X-262500Y1102700D01*
X-263200Y1102967D01*
X-266300D01*
G01X-256000Y1098700D02*
X-256800Y1098833D01*
X-257500Y1099367D01*
X-258100Y1100167D01*
X-258500Y1101100D01*
X-258700Y1102167D01*
Y1103233D01*
X-258500Y1104300D01*
X-258100Y1105233D01*
X-257500Y1106033D01*
X-256800Y1106567D01*
X-256000Y1106700D01*
X-255200Y1106567D01*
X-254500Y1106033D01*
X-253900Y1105233D01*
X-253500Y1104300D01*
X-253300Y1103233D01*
Y1102167D01*
X-253500Y1101100D01*
X-253900Y1100167D01*
X-254500Y1099367D01*
X-255200Y1098833D01*
X-256000Y1098700D01*
G01X-250500D02*
X-248000Y1106700D01*
X-245500Y1098700D01*
G01X-246400Y1101500D02*
X-249600D01*
G01X-242000Y1098700D02*
Y1106700D01*
X-239500D01*
X-238700Y1106300D01*
X-238200Y1105767D01*
X-238000Y1104700D01*
X-238200Y1103633D01*
X-238800Y1102967D01*
X-239500Y1102567D01*
X-242000D01*
G01X-239500D02*
X-238000Y1098700D01*
G01X-234200D02*
Y1106700D01*
X-232200D01*
X-231400Y1106300D01*
X-230800Y1105767D01*
X-230300Y1104967D01*
X-229900Y1104033D01*
X-229800Y1102700D01*
X-229900Y1101367D01*
X-230300Y1100433D01*
X-230800Y1099633D01*
X-231400Y1099100D01*
X-232200Y1098700D01*
X-234200D01*
G01X-216000D02*
X-216800Y1098833D01*
X-217500Y1099367D01*
X-218100Y1100167D01*
X-218500Y1101100D01*
X-218700Y1102167D01*
Y1103233D01*
X-218500Y1104300D01*
X-218100Y1105233D01*
X-217500Y1106033D01*
X-216800Y1106567D01*
X-216000Y1106700D01*
X-215200Y1106567D01*
X-214500Y1106033D01*
X-213900Y1105233D01*
X-213500Y1104300D01*
X-213300Y1103233D01*
Y1102167D01*
X-213500Y1101100D01*
X-213900Y1100167D01*
X-214500Y1099367D01*
X-215200Y1098833D01*
X-216000Y1098700D01*
G01X-210200Y1106700D02*
Y1100967D01*
X-209800Y1099766D01*
X-209000Y1098967D01*
X-208000Y1098700D01*
X-207000Y1098967D01*
X-206200Y1099766D01*
X-205800Y1100967D01*
Y1106700D01*
G01X-200000D02*
Y1098700D01*
G01X-202300Y1106700D02*
X-197700D01*
G01X-194000D02*
Y1098700D01*
X-190000D01*
G01X-185200Y1106700D02*
X-182800D01*
G01X-184000D02*
Y1098700D01*
G01X-185200D02*
X-182800D01*
G01X-178300D02*
Y1106700D01*
X-173700Y1098700D01*
Y1106700D01*
G01X-166000Y1098700D02*
X-170000D01*
Y1106700D01*
X-166000D01*
G01X-167600Y1102833D02*
X-170000D01*
G01X-153900Y1098700D02*
Y1106700D01*
X-150100D01*
G01X-151500Y1102833D02*
X-153900D01*
G01X-144000Y1098700D02*
X-144800Y1098833D01*
X-145500Y1099367D01*
X-146100Y1100167D01*
X-146500Y1101100D01*
X-146700Y1102167D01*
Y1103233D01*
X-146500Y1104300D01*
X-146100Y1105233D01*
X-145500Y1106033D01*
X-144800Y1106567D01*
X-144000Y1106700D01*
X-143200Y1106567D01*
X-142500Y1106033D01*
X-141900Y1105233D01*
X-141500Y1104300D01*
X-141300Y1103233D01*
Y1102167D01*
X-141500Y1101100D01*
X-141900Y1100167D01*
X-142500Y1099367D01*
X-143200Y1098833D01*
X-144000Y1098700D01*
G01X-138000Y1106700D02*
Y1098700D01*
X-134000D01*
G01X-130000Y1106700D02*
Y1098700D01*
X-126000D01*
G01X-120000D02*
X-120800Y1098833D01*
X-121500Y1099367D01*
X-122100Y1100167D01*
X-122500Y1101100D01*
X-122700Y1102167D01*
Y1103233D01*
X-122500Y1104300D01*
X-122100Y1105233D01*
X-121500Y1106033D01*
X-120800Y1106567D01*
X-120000Y1106700D01*
X-119200Y1106567D01*
X-118500Y1106033D01*
X-117900Y1105233D01*
X-117500Y1104300D01*
X-117300Y1103233D01*
Y1102167D01*
X-117500Y1101100D01*
X-117900Y1100167D01*
X-118500Y1099367D01*
X-119200Y1098833D01*
X-120000Y1098700D01*
G01X-115000Y1106700D02*
X-113600Y1098700D01*
X-112000Y1106700D01*
X-110400Y1098700D01*
X-109000Y1106700D01*
G01X-98000Y1098700D02*
Y1106700D01*
X-95600D01*
X-94800Y1106300D01*
X-94200Y1105367D01*
X-94000Y1104300D01*
X-94200Y1103233D01*
X-94700Y1102433D01*
X-95600Y1102033D01*
X-98000D01*
G01X-85800Y1106033D02*
X-86400Y1106433D01*
X-87100Y1106700D01*
X-87900D01*
X-88800Y1106300D01*
X-89500Y1105633D01*
X-90000Y1104833D01*
X-90400Y1103500D01*
X-90500Y1102300D01*
X-90300Y1101100D01*
X-90000Y1100300D01*
X-89400Y1099500D01*
X-88700Y1098967D01*
X-88000Y1098700D01*
X-87300D01*
X-86600Y1098967D01*
X-86000Y1099367D01*
X-85500Y1099900D01*
G01X-79200Y1102967D02*
X-78800Y1103367D01*
X-78500Y1104033D01*
X-78300Y1104967D01*
X-78500Y1105767D01*
X-78900Y1106300D01*
X-79600Y1106700D01*
X-82300D01*
Y1098700D01*
X-79000D01*
X-78300Y1099233D01*
X-77900Y1100033D01*
X-77700Y1100967D01*
X-77900Y1101900D01*
X-78500Y1102700D01*
X-79200Y1102967D01*
X-82300D01*
G01X-66100Y1099766D02*
X-65300Y1099100D01*
X-64400Y1098700D01*
X-63600D01*
X-62800Y1099100D01*
X-62200Y1099766D01*
X-61900Y1100700D01*
X-62100Y1101633D01*
X-62600Y1102433D01*
X-63500Y1102967D01*
X-64700Y1103233D01*
X-65400Y1103767D01*
X-65700Y1104700D01*
X-65500Y1105633D01*
X-65000Y1106300D01*
X-64300Y1106700D01*
X-63600D01*
X-62900Y1106433D01*
X-62300Y1105767D01*
G01X-58100Y1098700D02*
Y1106700D01*
G01X-53900D02*
Y1098700D01*
G01Y1102700D02*
X-58100D01*
G01X-48000Y1098700D02*
X-48800Y1098833D01*
X-49500Y1099367D01*
X-50100Y1100167D01*
X-50500Y1101100D01*
X-50700Y1102167D01*
Y1103233D01*
X-50500Y1104300D01*
X-50100Y1105233D01*
X-49500Y1106033D01*
X-48800Y1106567D01*
X-48000Y1106700D01*
X-47200Y1106567D01*
X-46500Y1106033D01*
X-45900Y1105233D01*
X-45500Y1104300D01*
X-45300Y1103233D01*
Y1102167D01*
X-45500Y1101100D01*
X-45900Y1100167D01*
X-46500Y1099367D01*
X-47200Y1098833D01*
X-48000Y1098700D01*
G01X-42000D02*
Y1106700D01*
X-39600D01*
X-38800Y1106300D01*
X-38200Y1105367D01*
X-38000Y1104300D01*
X-38200Y1103233D01*
X-38700Y1102433D01*
X-39600Y1102033D01*
X-42000D01*
G01X-26000Y1098700D02*
Y1106700D01*
X-23600D01*
X-22800Y1106300D01*
X-22200Y1105367D01*
X-22000Y1104300D01*
X-22200Y1103233D01*
X-22700Y1102433D01*
X-23600Y1102033D01*
X-26000D01*
G01X-18000Y1098700D02*
Y1106700D01*
X-15500D01*
X-14700Y1106300D01*
X-14200Y1105767D01*
X-14000Y1104700D01*
X-14200Y1103633D01*
X-14800Y1102967D01*
X-15500Y1102567D01*
X-18000D01*
G01X-15500D02*
X-14000Y1098700D01*
G01X-6000D02*
X-10000D01*
Y1106700D01*
X-6000D01*
G01X-7600Y1102833D02*
X-10000D01*
G01X-1900Y1098700D02*
Y1106700D01*
X1900D01*
G01X500Y1102833D02*
X-1900D01*
G01X10000Y1098700D02*
X6000D01*
Y1106700D01*
X10000D01*
G01X8400Y1102833D02*
X6000D01*
G01X14000Y1098700D02*
Y1106700D01*
X16500D01*
X17300Y1106300D01*
X17800Y1105767D01*
X18000Y1104700D01*
X17800Y1103633D01*
X17200Y1102967D01*
X16500Y1102567D01*
X14000D01*
G01X16500D02*
X18000Y1098700D01*
G01X26000D02*
X22000D01*
Y1106700D01*
X26000D01*
G01X24400Y1102833D02*
X22000D01*
G01X29700Y1098700D02*
Y1106700D01*
X34300Y1098700D01*
Y1106700D01*
G01X42200Y1106033D02*
X41600Y1106433D01*
X40900Y1106700D01*
X40100D01*
X39200Y1106300D01*
X38500Y1105633D01*
X38000Y1104833D01*
X37600Y1103500D01*
X37500Y1102300D01*
X37700Y1101100D01*
X38000Y1100300D01*
X38600Y1099500D01*
X39300Y1098967D01*
X40000Y1098700D01*
X40700D01*
X41400Y1098967D01*
X42000Y1099367D01*
X42500Y1099900D01*
G01X50000Y1098700D02*
X46000D01*
Y1106700D01*
X50000D01*
G01X48400Y1102833D02*
X46000D01*
G01X64800Y1102967D02*
X65200Y1103367D01*
X65500Y1104033D01*
X65700Y1104967D01*
X65500Y1105767D01*
X65100Y1106300D01*
X64400Y1106700D01*
X61700D01*
Y1098700D01*
X65000D01*
X65700Y1099233D01*
X66100Y1100033D01*
X66300Y1100967D01*
X66100Y1101900D01*
X65500Y1102700D01*
X64800Y1102967D01*
X61700D01*
G01X69800Y1106700D02*
Y1100967D01*
X70200Y1099766D01*
X71000Y1098967D01*
X72000Y1098700D01*
X73000Y1098967D01*
X73800Y1099766D01*
X74200Y1100967D01*
Y1106700D01*
G01X80000D02*
Y1098700D01*
G01X77700Y1106700D02*
X82300D01*
G01X98200Y1106033D02*
X97600Y1106433D01*
X96900Y1106700D01*
X96100D01*
X95200Y1106300D01*
X94500Y1105633D01*
X94000Y1104833D01*
X93600Y1103500D01*
X93500Y1102300D01*
X93700Y1101100D01*
X94000Y1100300D01*
X94600Y1099500D01*
X95300Y1098967D01*
X96000Y1098700D01*
X96700D01*
X97400Y1098967D01*
X98000Y1099367D01*
X98500Y1099900D01*
G01X104000Y1098700D02*
X103200Y1098833D01*
X102500Y1099367D01*
X101900Y1100167D01*
X101500Y1101100D01*
X101300Y1102167D01*
Y1103233D01*
X101500Y1104300D01*
X101900Y1105233D01*
X102500Y1106033D01*
X103200Y1106567D01*
X104000Y1106700D01*
X104800Y1106567D01*
X105500Y1106033D01*
X106100Y1105233D01*
X106500Y1104300D01*
X106700Y1103233D01*
Y1102167D01*
X106500Y1101100D01*
X106100Y1100167D01*
X105500Y1099367D01*
X104800Y1098833D01*
X104000Y1098700D01*
G01X109800Y1106700D02*
Y1100967D01*
X110200Y1099766D01*
X111000Y1098967D01*
X112000Y1098700D01*
X113000Y1098967D01*
X113800Y1099766D01*
X114200Y1100967D01*
Y1106700D01*
G01X118000Y1098700D02*
Y1106700D01*
X120400D01*
X121200Y1106300D01*
X121800Y1105367D01*
X122000Y1104300D01*
X121800Y1103233D01*
X121300Y1102433D01*
X120400Y1102033D01*
X118000D01*
G01X128000Y1098700D02*
X127200Y1098833D01*
X126500Y1099367D01*
X125900Y1100167D01*
X125500Y1101100D01*
X125300Y1102167D01*
Y1103233D01*
X125500Y1104300D01*
X125900Y1105233D01*
X126500Y1106033D01*
X127200Y1106567D01*
X128000Y1106700D01*
X128800Y1106567D01*
X129500Y1106033D01*
X130100Y1105233D01*
X130500Y1104300D01*
X130700Y1103233D01*
Y1102167D01*
X130500Y1101100D01*
X130100Y1100167D01*
X129500Y1099367D01*
X128800Y1098833D01*
X128000Y1098700D01*
G01X133700D02*
Y1106700D01*
X138300Y1098700D01*
Y1106700D01*
G01X142200Y1098433D02*
X145800Y1106700D01*
G01X150100Y1098700D02*
Y1106700D01*
X153900D01*
G01X152500Y1102833D02*
X150100D01*
G01X158800Y1106700D02*
X161200D01*
G01X160000D02*
Y1098700D01*
G01X158800D02*
X161200D01*
G01X165800D02*
Y1106700D01*
X167800D01*
X168600Y1106300D01*
X169200Y1105767D01*
X169700Y1104967D01*
X170100Y1104033D01*
X170200Y1102700D01*
X170100Y1101367D01*
X169700Y1100433D01*
X169200Y1099633D01*
X168600Y1099100D01*
X167800Y1098700D01*
X165800D01*
G01X173800Y1106700D02*
Y1100967D01*
X174200Y1099766D01*
X175000Y1098967D01*
X176000Y1098700D01*
X177000Y1098967D01*
X177800Y1099766D01*
X178200Y1100967D01*
Y1106700D01*
G01X186200Y1106033D02*
X185600Y1106433D01*
X184900Y1106700D01*
X184100D01*
X183200Y1106300D01*
X182500Y1105633D01*
X182000Y1104833D01*
X181600Y1103500D01*
X181500Y1102300D01*
X181700Y1101100D01*
X182000Y1100300D01*
X182600Y1099500D01*
X183300Y1098967D01*
X184000Y1098700D01*
X184700D01*
X185400Y1098967D01*
X186000Y1099367D01*
X186500Y1099900D01*
G01X190800Y1106700D02*
X193200D01*
G01X192000D02*
Y1098700D01*
G01X190800D02*
X193200D01*
G01X197500D02*
X200000Y1106700D01*
X202500Y1098700D01*
G01X201600Y1101500D02*
X198400D01*
G01X206000Y1106700D02*
Y1098700D01*
X210000D01*
G01X221400D02*
Y1106700D01*
X224000Y1100033D01*
X226600Y1106700D01*
Y1098700D01*
G01X229500D02*
X232000Y1106700D01*
X234500Y1098700D01*
G01X233600Y1101500D02*
X230400D01*
G01X238000Y1098700D02*
Y1106700D01*
X240500D01*
X241300Y1106300D01*
X241800Y1105767D01*
X242000Y1104700D01*
X241800Y1103633D01*
X241200Y1102967D01*
X240500Y1102567D01*
X238000D01*
G01X240500D02*
X242000Y1098700D01*
G01X245800D02*
Y1106700D01*
G01X249600D02*
X245800Y1101766D01*
G01X250200Y1098700D02*
X247500Y1104033D01*
G01X254200Y1098433D02*
X257800Y1106700D01*
G01X264000D02*
Y1098700D01*
G01X261700Y1106700D02*
X266300D01*
G01X272000Y1098700D02*
X271200Y1098833D01*
X270500Y1099367D01*
X269900Y1100167D01*
X269500Y1101100D01*
X269300Y1102167D01*
Y1103233D01*
X269500Y1104300D01*
X269900Y1105233D01*
X270500Y1106033D01*
X271200Y1106567D01*
X272000Y1106700D01*
X272800Y1106567D01*
X273500Y1106033D01*
X274100Y1105233D01*
X274500Y1104300D01*
X274700Y1103233D01*
Y1102167D01*
X274500Y1101100D01*
X274100Y1100167D01*
X273500Y1099367D01*
X272800Y1098833D01*
X272000Y1098700D01*
G01X280000D02*
X279200Y1098833D01*
X278500Y1099367D01*
X277900Y1100167D01*
X277500Y1101100D01*
X277300Y1102167D01*
Y1103233D01*
X277500Y1104300D01*
X277900Y1105233D01*
X278500Y1106033D01*
X279200Y1106567D01*
X280000Y1106700D01*
X280800Y1106567D01*
X281500Y1106033D01*
X282100Y1105233D01*
X282500Y1104300D01*
X282700Y1103233D01*
Y1102167D01*
X282500Y1101100D01*
X282100Y1100167D01*
X281500Y1099367D01*
X280800Y1098833D01*
X280000Y1098700D01*
G01X286000Y1106700D02*
Y1098700D01*
X290000D01*
G01X294800Y1106700D02*
X297200D01*
G01X296000D02*
Y1098700D01*
G01X294800D02*
X297200D01*
G01X301700D02*
Y1106700D01*
X306300Y1098700D01*
Y1106700D01*
G01X312600Y1102700D02*
X314600D01*
Y1100300D01*
X314000Y1099500D01*
X313300Y1098967D01*
X312300Y1098700D01*
X311300Y1098967D01*
X310600Y1099500D01*
X310000Y1100300D01*
X309600Y1101233D01*
X309400Y1102300D01*
Y1103233D01*
X309600Y1104033D01*
X310000Y1104967D01*
X310600Y1105767D01*
X311200Y1106300D01*
X312000Y1106700D01*
X312700D01*
X313500Y1106433D01*
X314100Y1105900D01*
G01X325900Y1098700D02*
Y1106700D01*
G01X330100D02*
Y1098700D01*
G01Y1102700D02*
X325900D01*
G01X336000Y1098700D02*
X335200Y1098833D01*
X334500Y1099367D01*
X333900Y1100167D01*
X333500Y1101100D01*
X333300Y1102167D01*
Y1103233D01*
X333500Y1104300D01*
X333900Y1105233D01*
X334500Y1106033D01*
X335200Y1106567D01*
X336000Y1106700D01*
X336800Y1106567D01*
X337500Y1106033D01*
X338100Y1105233D01*
X338500Y1104300D01*
X338700Y1103233D01*
Y1102167D01*
X338500Y1101100D01*
X338100Y1100167D01*
X337500Y1099367D01*
X336800Y1098833D01*
X336000Y1098700D01*
G01X342000Y1106700D02*
Y1098700D01*
X346000D01*
G01X354000D02*
X350000D01*
Y1106700D01*
X354000D01*
G01X352400Y1102833D02*
X350000D01*
G01X365900Y1099766D02*
X366700Y1099100D01*
X367600Y1098700D01*
X368400D01*
X369200Y1099100D01*
X369800Y1099766D01*
X370100Y1100700D01*
X369900Y1101633D01*
X369400Y1102433D01*
X368500Y1102967D01*
X367300Y1103233D01*
X366600Y1103767D01*
X366300Y1104700D01*
X366500Y1105633D01*
X367000Y1106300D01*
X367700Y1106700D01*
X368400D01*
X369100Y1106433D01*
X369700Y1105767D01*
G01X374000Y1098700D02*
Y1106700D01*
X376400D01*
X377200Y1106300D01*
X377800Y1105367D01*
X378000Y1104300D01*
X377800Y1103233D01*
X377300Y1102433D01*
X376400Y1102033D01*
X374000D01*
G01X381500Y1098700D02*
X384000Y1106700D01*
X386500Y1098700D01*
G01X385600Y1101500D02*
X382400D01*
G01X394200Y1106033D02*
X393600Y1106433D01*
X392900Y1106700D01*
X392100D01*
X391200Y1106300D01*
X390500Y1105633D01*
X390000Y1104833D01*
X389600Y1103500D01*
X389500Y1102300D01*
X389700Y1101100D01*
X390000Y1100300D01*
X390600Y1099500D01*
X391300Y1098967D01*
X392000Y1098700D01*
X392700D01*
X393400Y1098967D01*
X394000Y1099367D01*
X394500Y1099900D01*
G01X398800Y1106700D02*
X401200D01*
G01X400000D02*
Y1098700D01*
G01X398800D02*
X401200D01*
G01X405700D02*
Y1106700D01*
X410300Y1098700D01*
Y1106700D01*
G01X416600Y1102700D02*
X418600D01*
Y1100300D01*
X418000Y1099500D01*
X417300Y1098967D01*
X416300Y1098700D01*
X415300Y1098967D01*
X414600Y1099500D01*
X414000Y1100300D01*
X413600Y1101233D01*
X413400Y1102300D01*
Y1103233D01*
X413600Y1104033D01*
X414000Y1104967D01*
X414600Y1105767D01*
X415200Y1106300D01*
X416000Y1106700D01*
X416700D01*
X417500Y1106433D01*
X418100Y1105900D01*
G01X429500Y1098700D02*
X432000Y1106700D01*
X434500Y1098700D01*
G01X433600Y1101500D02*
X430400D01*
G01X438000Y1106700D02*
Y1098700D01*
X442000D01*
G01X446000Y1106700D02*
Y1098700D01*
X450000D01*
G01X461800Y1106700D02*
Y1100967D01*
X462200Y1099766D01*
X463000Y1098967D01*
X464000Y1098700D01*
X465000Y1098967D01*
X465800Y1099766D01*
X466200Y1100967D01*
Y1106700D01*
G01X469900Y1099766D02*
X470700Y1099100D01*
X471600Y1098700D01*
X472400D01*
X473200Y1099100D01*
X473800Y1099766D01*
X474100Y1100700D01*
X473900Y1101633D01*
X473400Y1102433D01*
X472500Y1102967D01*
X471300Y1103233D01*
X470600Y1103767D01*
X470300Y1104700D01*
X470500Y1105633D01*
X471000Y1106300D01*
X471700Y1106700D01*
X472400D01*
X473100Y1106433D01*
X473700Y1105767D01*
G01X478800Y1106700D02*
X481200D01*
G01X480000D02*
Y1098700D01*
G01X478800D02*
X481200D01*
G01X485700D02*
Y1106700D01*
X490300Y1098700D01*
Y1106700D01*
G01X496600Y1102700D02*
X498600D01*
Y1100300D01*
X498000Y1099500D01*
X497300Y1098967D01*
X496300Y1098700D01*
X495300Y1098967D01*
X494600Y1099500D01*
X494000Y1100300D01*
X493600Y1101233D01*
X493400Y1102300D01*
Y1103233D01*
X493600Y1104033D01*
X494000Y1104967D01*
X494600Y1105767D01*
X495200Y1106300D01*
X496000Y1106700D01*
X496700D01*
X497500Y1106433D01*
X498100Y1105900D01*
G01X509800Y1099900D02*
X510400Y1099233D01*
X511100Y1098833D01*
X512000Y1098700D01*
X512900Y1098967D01*
X513600Y1099500D01*
X514100Y1100433D01*
X514200Y1101500D01*
X514000Y1102567D01*
X513500Y1103233D01*
X512800Y1103767D01*
X512100Y1103900D01*
X511400Y1103767D01*
X510500Y1103233D01*
X510800Y1106700D01*
X513500D01*
G01X520000D02*
X519200Y1106433D01*
X518600Y1105767D01*
X518200Y1104967D01*
X517900Y1103900D01*
X517800Y1102700D01*
X517900Y1101500D01*
X518200Y1100433D01*
X518600Y1099633D01*
X519200Y1098967D01*
X520000Y1098700D01*
X520800Y1098967D01*
X521400Y1099633D01*
X521800Y1100433D01*
X522100Y1101500D01*
X522200Y1102700D01*
X522100Y1103900D01*
X521800Y1104967D01*
X521400Y1105767D01*
X520800Y1106433D01*
X520000Y1106700D01*
G01X525400Y1098700D02*
Y1106700D01*
X528000Y1100033D01*
X530600Y1106700D01*
Y1098700D01*
G01X534800Y1106700D02*
X537200D01*
G01X536000D02*
Y1098700D01*
G01X534800D02*
X537200D01*
G01X542000Y1106700D02*
Y1098700D01*
X546000D01*
G01X549900Y1099766D02*
X550700Y1099100D01*
X551600Y1098700D01*
X552400D01*
X553200Y1099100D01*
X553800Y1099766D01*
X554100Y1100700D01*
X553900Y1101633D01*
X553400Y1102433D01*
X552500Y1102967D01*
X551300Y1103233D01*
X550600Y1103767D01*
X550300Y1104700D01*
X550500Y1105633D01*
X551000Y1106300D01*
X551700Y1106700D01*
X552400D01*
X553100Y1106433D01*
X553700Y1105767D01*
G01X560000Y1098433D02*
X559800Y1098567D01*
Y1098833D01*
X560000Y1098967D01*
X560200Y1098833D01*
Y1098567D01*
X560000Y1098433D01*
G01X-361900Y1117033D02*
X-361200Y1117967D01*
X-360600Y1118500D01*
X-359800Y1118767D01*
X-359100Y1118500D01*
X-358600Y1117967D01*
X-358200Y1117167D01*
X-358100Y1116233D01*
X-358200Y1115433D01*
X-358600Y1114633D01*
X-359200Y1113967D01*
X-359900Y1113700D01*
X-360700Y1113967D01*
X-361400Y1114766D01*
X-361800Y1115967D01*
X-361900Y1117300D01*
X-361700Y1119033D01*
X-361400Y1119967D01*
X-360900Y1120900D01*
X-360200Y1121567D01*
X-359500Y1121700D01*
X-358800Y1121433D01*
X-358300Y1120767D01*
G01X-352000Y1113433D02*
X-352200Y1113567D01*
Y1113833D01*
X-352000Y1113967D01*
X-351800Y1113833D01*
Y1113567D01*
X-352000Y1113433D01*
G01X-344000Y1113700D02*
Y1121700D01*
X-345200Y1120100D01*
G01Y1113700D02*
X-342800D01*
G01X-329200Y1121700D02*
X-326800D01*
G01X-328000D02*
Y1113700D01*
G01X-329200D02*
X-326800D01*
G01X-322300D02*
Y1121700D01*
X-317700Y1113700D01*
Y1121700D01*
G01X-314100Y1114766D02*
X-313300Y1114100D01*
X-312400Y1113700D01*
X-311600D01*
X-310800Y1114100D01*
X-310200Y1114766D01*
X-309900Y1115700D01*
X-310100Y1116633D01*
X-310600Y1117433D01*
X-311500Y1117967D01*
X-312700Y1118233D01*
X-313400Y1118767D01*
X-313700Y1119700D01*
X-313500Y1120633D01*
X-313000Y1121300D01*
X-312300Y1121700D01*
X-311600D01*
X-310900Y1121433D01*
X-310300Y1120767D01*
G01X-305200Y1121700D02*
X-302800D01*
G01X-304000D02*
Y1113700D01*
G01X-305200D02*
X-302800D01*
G01X-298200D02*
Y1121700D01*
X-296200D01*
X-295400Y1121300D01*
X-294800Y1120767D01*
X-294300Y1119967D01*
X-293900Y1119033D01*
X-293800Y1117700D01*
X-293900Y1116367D01*
X-294300Y1115433D01*
X-294800Y1114633D01*
X-295400Y1114100D01*
X-296200Y1113700D01*
X-298200D01*
G01X-286000D02*
X-290000D01*
Y1121700D01*
X-286000D01*
G01X-287600Y1117833D02*
X-290000D01*
G01X-271200Y1117967D02*
X-270800Y1118367D01*
X-270500Y1119033D01*
X-270300Y1119967D01*
X-270500Y1120767D01*
X-270900Y1121300D01*
X-271600Y1121700D01*
X-274300D01*
Y1113700D01*
X-271000D01*
X-270300Y1114233D01*
X-269900Y1115033D01*
X-269700Y1115967D01*
X-269900Y1116900D01*
X-270500Y1117700D01*
X-271200Y1117967D01*
X-274300D01*
G01X-264000Y1113700D02*
X-264800Y1113833D01*
X-265500Y1114367D01*
X-266100Y1115167D01*
X-266500Y1116100D01*
X-266700Y1117167D01*
Y1118233D01*
X-266500Y1119300D01*
X-266100Y1120233D01*
X-265500Y1121033D01*
X-264800Y1121567D01*
X-264000Y1121700D01*
X-263200Y1121567D01*
X-262500Y1121033D01*
X-261900Y1120233D01*
X-261500Y1119300D01*
X-261300Y1118233D01*
Y1117167D01*
X-261500Y1116100D01*
X-261900Y1115167D01*
X-262500Y1114367D01*
X-263200Y1113833D01*
X-264000Y1113700D01*
G01X-258500D02*
X-256000Y1121700D01*
X-253500Y1113700D01*
G01X-254400Y1116500D02*
X-257600D01*
G01X-250000Y1113700D02*
Y1121700D01*
X-247500D01*
X-246700Y1121300D01*
X-246200Y1120767D01*
X-246000Y1119700D01*
X-246200Y1118633D01*
X-246800Y1117967D01*
X-247500Y1117567D01*
X-250000D01*
G01X-247500D02*
X-246000Y1113700D01*
G01X-242200D02*
Y1121700D01*
X-240200D01*
X-239400Y1121300D01*
X-238800Y1120767D01*
X-238300Y1119967D01*
X-237900Y1119033D01*
X-237800Y1117700D01*
X-237900Y1116367D01*
X-238300Y1115433D01*
X-238800Y1114633D01*
X-239400Y1114100D01*
X-240200Y1113700D01*
X-242200D01*
G01X-224000D02*
X-224800Y1113833D01*
X-225500Y1114367D01*
X-226100Y1115167D01*
X-226500Y1116100D01*
X-226700Y1117167D01*
Y1118233D01*
X-226500Y1119300D01*
X-226100Y1120233D01*
X-225500Y1121033D01*
X-224800Y1121567D01*
X-224000Y1121700D01*
X-223200Y1121567D01*
X-222500Y1121033D01*
X-221900Y1120233D01*
X-221500Y1119300D01*
X-221300Y1118233D01*
Y1117167D01*
X-221500Y1116100D01*
X-221900Y1115167D01*
X-222500Y1114367D01*
X-223200Y1113833D01*
X-224000Y1113700D01*
G01X-218200Y1121700D02*
Y1115967D01*
X-217800Y1114766D01*
X-217000Y1113967D01*
X-216000Y1113700D01*
X-215000Y1113967D01*
X-214200Y1114766D01*
X-213800Y1115967D01*
Y1121700D01*
G01X-208000D02*
Y1113700D01*
G01X-210300Y1121700D02*
X-205700D01*
G01X-202000D02*
Y1113700D01*
X-198000D01*
G01X-193200Y1121700D02*
X-190800D01*
G01X-192000D02*
Y1113700D01*
G01X-193200D02*
X-190800D01*
G01X-186300D02*
Y1121700D01*
X-181700Y1113700D01*
Y1121700D01*
G01X-174000Y1113700D02*
X-178000D01*
Y1121700D01*
X-174000D01*
G01X-175600Y1117833D02*
X-178000D01*
G01X-162200Y1113700D02*
Y1121700D01*
X-160200D01*
X-159400Y1121300D01*
X-158800Y1120767D01*
X-158300Y1119967D01*
X-157900Y1119033D01*
X-157800Y1117700D01*
X-157900Y1116367D01*
X-158300Y1115433D01*
X-158800Y1114633D01*
X-159400Y1114100D01*
X-160200Y1113700D01*
X-162200D01*
G01X-154200Y1121700D02*
Y1115967D01*
X-153800Y1114766D01*
X-153000Y1113967D01*
X-152000Y1113700D01*
X-151000Y1113967D01*
X-150200Y1114766D01*
X-149800Y1115967D01*
Y1121700D01*
G01X-146600Y1113700D02*
Y1121700D01*
X-144000Y1115033D01*
X-141400Y1121700D01*
Y1113700D01*
G01X-138600D02*
Y1121700D01*
X-136000Y1115033D01*
X-133400Y1121700D01*
Y1113700D01*
G01X-128000D02*
Y1117300D01*
X-130000Y1121700D01*
G01X-126000D02*
X-128000Y1117300D01*
G01X-114000Y1113700D02*
Y1121700D01*
X-111600D01*
X-110800Y1121300D01*
X-110200Y1120367D01*
X-110000Y1119300D01*
X-110200Y1118233D01*
X-110700Y1117433D01*
X-111600Y1117033D01*
X-114000D01*
G01X-106500Y1113700D02*
X-104000Y1121700D01*
X-101500Y1113700D01*
G01X-102400Y1116500D02*
X-105600D01*
G01X-98200Y1113700D02*
Y1121700D01*
X-96200D01*
X-95400Y1121300D01*
X-94800Y1120767D01*
X-94300Y1119967D01*
X-93900Y1119033D01*
X-93800Y1117700D01*
X-93900Y1116367D01*
X-94300Y1115433D01*
X-94800Y1114633D01*
X-95400Y1114100D01*
X-96200Y1113700D01*
X-98200D01*
G01X-82200D02*
Y1121700D01*
X-80200D01*
X-79400Y1121300D01*
X-78800Y1120767D01*
X-78300Y1119967D01*
X-77900Y1119033D01*
X-77800Y1117700D01*
X-77900Y1116367D01*
X-78300Y1115433D01*
X-78800Y1114633D01*
X-79400Y1114100D01*
X-80200Y1113700D01*
X-82200D01*
G01X-70000D02*
X-74000D01*
Y1121700D01*
X-70000D01*
G01X-71600Y1117833D02*
X-74000D01*
G01X-66100Y1114766D02*
X-65300Y1114100D01*
X-64400Y1113700D01*
X-63600D01*
X-62800Y1114100D01*
X-62200Y1114766D01*
X-61900Y1115700D01*
X-62100Y1116633D01*
X-62600Y1117433D01*
X-63500Y1117967D01*
X-64700Y1118233D01*
X-65400Y1118767D01*
X-65700Y1119700D01*
X-65500Y1120633D01*
X-65000Y1121300D01*
X-64300Y1121700D01*
X-63600D01*
X-62900Y1121433D01*
X-62300Y1120767D01*
G01X-57200Y1121700D02*
X-54800D01*
G01X-56000D02*
Y1113700D01*
G01X-57200D02*
X-54800D01*
G01X-47400Y1117700D02*
X-45400D01*
Y1115300D01*
X-46000Y1114500D01*
X-46700Y1113967D01*
X-47700Y1113700D01*
X-48700Y1113967D01*
X-49400Y1114500D01*
X-50000Y1115300D01*
X-50400Y1116233D01*
X-50600Y1117300D01*
Y1118233D01*
X-50400Y1119033D01*
X-50000Y1119967D01*
X-49400Y1120767D01*
X-48800Y1121300D01*
X-48000Y1121700D01*
X-47300D01*
X-46500Y1121433D01*
X-45900Y1120900D01*
G01X-42300Y1113700D02*
Y1121700D01*
X-37700Y1113700D01*
Y1121700D01*
G01X-25200D02*
X-22800D01*
G01X-24000D02*
Y1113700D01*
G01X-25200D02*
X-22800D01*
G01X-18300D02*
Y1121700D01*
X-13700Y1113700D01*
Y1121700D01*
G01X-2100Y1114766D02*
X-1300Y1114100D01*
X-400Y1113700D01*
X400D01*
X1200Y1114100D01*
X1800Y1114766D01*
X2100Y1115700D01*
X1900Y1116633D01*
X1400Y1117433D01*
X500Y1117967D01*
X-700Y1118233D01*
X-1400Y1118767D01*
X-1700Y1119700D01*
X-1500Y1120633D01*
X-1000Y1121300D01*
X-300Y1121700D01*
X400D01*
X1100Y1121433D01*
X1700Y1120767D01*
G01X8000Y1113700D02*
X7200Y1113833D01*
X6500Y1114367D01*
X5900Y1115167D01*
X5500Y1116100D01*
X5300Y1117167D01*
Y1118233D01*
X5500Y1119300D01*
X5900Y1120233D01*
X6500Y1121033D01*
X7200Y1121567D01*
X8000Y1121700D01*
X8800Y1121567D01*
X9500Y1121033D01*
X10100Y1120233D01*
X10500Y1119300D01*
X10700Y1118233D01*
Y1117167D01*
X10500Y1116100D01*
X10100Y1115167D01*
X9500Y1114367D01*
X8800Y1113833D01*
X8000Y1113700D01*
G01X8800Y1115833D02*
X10000Y1113700D01*
G01X13800Y1121700D02*
Y1115967D01*
X14200Y1114766D01*
X15000Y1113967D01*
X16000Y1113700D01*
X17000Y1113967D01*
X17800Y1114766D01*
X18200Y1115967D01*
Y1121700D01*
G01X21500Y1113700D02*
X24000Y1121700D01*
X26500Y1113700D01*
G01X25600Y1116500D02*
X22400D01*
G01X30000Y1113700D02*
Y1121700D01*
X32500D01*
X33300Y1121300D01*
X33800Y1120767D01*
X34000Y1119700D01*
X33800Y1118633D01*
X33200Y1117967D01*
X32500Y1117567D01*
X30000D01*
G01X32500D02*
X34000Y1113700D01*
G01X42000D02*
X38000D01*
Y1121700D01*
X42000D01*
G01X40400Y1117833D02*
X38000D01*
G01X53900Y1114766D02*
X54700Y1114100D01*
X55600Y1113700D01*
X56400D01*
X57200Y1114100D01*
X57800Y1114766D01*
X58100Y1115700D01*
X57900Y1116633D01*
X57400Y1117433D01*
X56500Y1117967D01*
X55300Y1118233D01*
X54600Y1118767D01*
X54300Y1119700D01*
X54500Y1120633D01*
X55000Y1121300D01*
X55700Y1121700D01*
X56400D01*
X57100Y1121433D01*
X57700Y1120767D01*
G01X61900Y1113700D02*
Y1121700D01*
G01X66100D02*
Y1113700D01*
G01Y1117700D02*
X61900D01*
G01X69500Y1113700D02*
X72000Y1121700D01*
X74500Y1113700D01*
G01X73600Y1116500D02*
X70400D01*
G01X78000Y1113700D02*
Y1121700D01*
X80400D01*
X81200Y1121300D01*
X81800Y1120367D01*
X82000Y1119300D01*
X81800Y1118233D01*
X81300Y1117433D01*
X80400Y1117033D01*
X78000D01*
G01X90000Y1113700D02*
X86000D01*
Y1121700D01*
X90000D01*
G01X88400Y1117833D02*
X86000D01*
G01X94700Y1116367D02*
X97300D01*
G01X109900Y1114766D02*
X110700Y1114100D01*
X111600Y1113700D01*
X112400D01*
X113200Y1114100D01*
X113800Y1114766D01*
X114100Y1115700D01*
X113900Y1116633D01*
X113400Y1117433D01*
X112500Y1117967D01*
X111300Y1118233D01*
X110600Y1118767D01*
X110300Y1119700D01*
X110500Y1120633D01*
X111000Y1121300D01*
X111700Y1121700D01*
X112400D01*
X113100Y1121433D01*
X113700Y1120767D01*
G01X117900Y1113700D02*
Y1121700D01*
G01X122100D02*
Y1113700D01*
G01Y1117700D02*
X117900D01*
G01X125500Y1113700D02*
X128000Y1121700D01*
X130500Y1113700D01*
G01X129600Y1116500D02*
X126400D01*
G01X134000Y1113700D02*
Y1121700D01*
X136400D01*
X137200Y1121300D01*
X137800Y1120367D01*
X138000Y1119300D01*
X137800Y1118233D01*
X137300Y1117433D01*
X136400Y1117033D01*
X134000D01*
G01X146000Y1113700D02*
X142000D01*
Y1121700D01*
X146000D01*
G01X144400Y1117833D02*
X142000D01*
G01X157900Y1114766D02*
X158700Y1114100D01*
X159600Y1113700D01*
X160400D01*
X161200Y1114100D01*
X161800Y1114766D01*
X162100Y1115700D01*
X161900Y1116633D01*
X161400Y1117433D01*
X160500Y1117967D01*
X159300Y1118233D01*
X158600Y1118767D01*
X158300Y1119700D01*
X158500Y1120633D01*
X159000Y1121300D01*
X159700Y1121700D01*
X160400D01*
X161100Y1121433D01*
X161700Y1120767D01*
G01X166800Y1121700D02*
X169200D01*
G01X168000D02*
Y1113700D01*
G01X166800D02*
X169200D01*
G01X174100Y1121700D02*
X177900D01*
X174100Y1113700D01*
X177900D01*
G01X186000D02*
X182000D01*
Y1121700D01*
X186000D01*
G01X184400Y1117833D02*
X182000D01*
G01X197800Y1114900D02*
X198400Y1114233D01*
X199100Y1113833D01*
X200000Y1113700D01*
X200900Y1113967D01*
X201600Y1114500D01*
X202100Y1115433D01*
X202200Y1116500D01*
X202000Y1117567D01*
X201500Y1118233D01*
X200800Y1118767D01*
X200100Y1118900D01*
X199400Y1118767D01*
X198500Y1118233D01*
X198800Y1121700D01*
X201500D01*
G01X208000D02*
X207200Y1121433D01*
X206600Y1120767D01*
X206200Y1119967D01*
X205900Y1118900D01*
X205800Y1117700D01*
X205900Y1116500D01*
X206200Y1115433D01*
X206600Y1114633D01*
X207200Y1113967D01*
X208000Y1113700D01*
X208800Y1113967D01*
X209400Y1114633D01*
X209800Y1115433D01*
X210100Y1116500D01*
X210200Y1117700D01*
X210100Y1118900D01*
X209800Y1119967D01*
X209400Y1120767D01*
X208800Y1121433D01*
X208000Y1121700D01*
G01X213400Y1113700D02*
Y1121700D01*
X216000Y1115033D01*
X218600Y1121700D01*
Y1113700D01*
G01X222800Y1121700D02*
X225200D01*
G01X224000D02*
Y1113700D01*
G01X222800D02*
X225200D01*
G01X230000Y1121700D02*
Y1113700D01*
X234000D01*
G01X237900Y1114766D02*
X238700Y1114100D01*
X239600Y1113700D01*
X240400D01*
X241200Y1114100D01*
X241800Y1114766D01*
X242100Y1115700D01*
X241900Y1116633D01*
X241400Y1117433D01*
X240500Y1117967D01*
X239300Y1118233D01*
X238600Y1118767D01*
X238300Y1119700D01*
X238500Y1120633D01*
X239000Y1121300D01*
X239700Y1121700D01*
X240400D01*
X241100Y1121433D01*
X241700Y1120767D01*
G01X247800Y1112233D02*
X248200Y1113967D01*
G01X262000Y1113700D02*
Y1121700D01*
X264400D01*
X265200Y1121300D01*
X265800Y1120367D01*
X266000Y1119300D01*
X265800Y1118233D01*
X265300Y1117433D01*
X264400Y1117033D01*
X262000D01*
G01X270800Y1121700D02*
X273200D01*
G01X272000D02*
Y1113700D01*
G01X270800D02*
X273200D01*
G01X280000Y1121700D02*
Y1113700D01*
G01X277700Y1121700D02*
X282300D01*
G01X290200Y1121033D02*
X289600Y1121433D01*
X288900Y1121700D01*
X288100D01*
X287200Y1121300D01*
X286500Y1120633D01*
X286000Y1119833D01*
X285600Y1118500D01*
X285500Y1117300D01*
X285700Y1116100D01*
X286000Y1115300D01*
X286600Y1114500D01*
X287300Y1113967D01*
X288000Y1113700D01*
X288700D01*
X289400Y1113967D01*
X290000Y1114367D01*
X290500Y1114900D01*
G01X293900Y1113700D02*
Y1121700D01*
G01X298100D02*
Y1113700D01*
G01Y1117700D02*
X293900D01*
G01X311500Y1111033D02*
X310500Y1112367D01*
X310000Y1113700D01*
Y1119033D01*
X310500Y1120367D01*
X311500Y1121700D01*
G01X317900Y1114766D02*
X318700Y1114100D01*
X319600Y1113700D01*
X320400D01*
X321200Y1114100D01*
X321800Y1114766D01*
X322100Y1115700D01*
X321900Y1116633D01*
X321400Y1117433D01*
X320500Y1117967D01*
X319300Y1118233D01*
X318600Y1118767D01*
X318300Y1119700D01*
X318500Y1120633D01*
X319000Y1121300D01*
X319700Y1121700D01*
X320400D01*
X321100Y1121433D01*
X321700Y1120767D01*
G01X325900Y1113700D02*
Y1121700D01*
G01X330100D02*
Y1113700D01*
G01Y1117700D02*
X325900D01*
G01X333500Y1113700D02*
X336000Y1121700D01*
X338500Y1113700D01*
G01X337600Y1116500D02*
X334400D01*
G01X342000Y1113700D02*
Y1121700D01*
X344400D01*
X345200Y1121300D01*
X345800Y1120367D01*
X346000Y1119300D01*
X345800Y1118233D01*
X345300Y1117433D01*
X344400Y1117033D01*
X342000D01*
G01X354000Y1113700D02*
X350000D01*
Y1121700D01*
X354000D01*
G01X352400Y1117833D02*
X350000D01*
G01X370200Y1121033D02*
X369600Y1121433D01*
X368900Y1121700D01*
X368100D01*
X367200Y1121300D01*
X366500Y1120633D01*
X366000Y1119833D01*
X365600Y1118500D01*
X365500Y1117300D01*
X365700Y1116100D01*
X366000Y1115300D01*
X366600Y1114500D01*
X367300Y1113967D01*
X368000Y1113700D01*
X368700D01*
X369400Y1113967D01*
X370000Y1114367D01*
X370500Y1114900D01*
G01X378000Y1113700D02*
X374000D01*
Y1121700D01*
X378000D01*
G01X376400Y1117833D02*
X374000D01*
G01X381700Y1113700D02*
Y1121700D01*
X386300Y1113700D01*
Y1121700D01*
G01X392000D02*
Y1113700D01*
G01X389700Y1121700D02*
X394300D01*
G01X402000Y1113700D02*
X398000D01*
Y1121700D01*
X402000D01*
G01X400400Y1117833D02*
X398000D01*
G01X406000Y1113700D02*
Y1121700D01*
X408500D01*
X409300Y1121300D01*
X409800Y1120767D01*
X410000Y1119700D01*
X409800Y1118633D01*
X409200Y1117967D01*
X408500Y1117567D01*
X406000D01*
G01X408500D02*
X410000Y1113700D01*
G01X424000Y1121700D02*
Y1113700D01*
G01X421700Y1121700D02*
X426300D01*
G01X432000Y1113700D02*
X431200Y1113833D01*
X430500Y1114367D01*
X429900Y1115167D01*
X429500Y1116100D01*
X429300Y1117167D01*
Y1118233D01*
X429500Y1119300D01*
X429900Y1120233D01*
X430500Y1121033D01*
X431200Y1121567D01*
X432000Y1121700D01*
X432800Y1121567D01*
X433500Y1121033D01*
X434100Y1120233D01*
X434500Y1119300D01*
X434700Y1118233D01*
Y1117167D01*
X434500Y1116100D01*
X434100Y1115167D01*
X433500Y1114367D01*
X432800Y1113833D01*
X432000Y1113700D01*
G01X450200Y1121033D02*
X449600Y1121433D01*
X448900Y1121700D01*
X448100D01*
X447200Y1121300D01*
X446500Y1120633D01*
X446000Y1119833D01*
X445600Y1118500D01*
X445500Y1117300D01*
X445700Y1116100D01*
X446000Y1115300D01*
X446600Y1114500D01*
X447300Y1113967D01*
X448000Y1113700D01*
X448700D01*
X449400Y1113967D01*
X450000Y1114367D01*
X450500Y1114900D01*
G01X458000Y1113700D02*
X454000D01*
Y1121700D01*
X458000D01*
G01X456400Y1117833D02*
X454000D01*
G01X461700Y1113700D02*
Y1121700D01*
X466300Y1113700D01*
Y1121700D01*
G01X472000D02*
Y1113700D01*
G01X469700Y1121700D02*
X474300D01*
G01X482000Y1113700D02*
X478000D01*
Y1121700D01*
X482000D01*
G01X480400Y1117833D02*
X478000D01*
G01X486000Y1113700D02*
Y1121700D01*
X488500D01*
X489300Y1121300D01*
X489800Y1120767D01*
X490000Y1119700D01*
X489800Y1118633D01*
X489200Y1117967D01*
X488500Y1117567D01*
X486000D01*
G01X488500D02*
X490000Y1113700D01*
G01X496500Y1111033D02*
X497500Y1112367D01*
X498000Y1113700D01*
Y1119033D01*
X497500Y1120367D01*
X496500Y1121700D01*
G01X504000Y1113433D02*
X503800Y1113567D01*
Y1113833D01*
X504000Y1113967D01*
X504200Y1113833D01*
Y1113567D01*
X504000Y1113433D01*
G01Y1117033D02*
X503800Y1117167D01*
Y1117433D01*
X504000Y1117567D01*
X504200Y1117433D01*
Y1117167D01*
X504000Y1117033D01*
G01X520000Y1113700D02*
Y1121700D01*
X518800Y1120100D01*
G01Y1113700D02*
X521200D01*
G01X528000Y1121700D02*
X527200Y1121433D01*
X526600Y1120767D01*
X526200Y1119967D01*
X525900Y1118900D01*
X525800Y1117700D01*
X525900Y1116500D01*
X526200Y1115433D01*
X526600Y1114633D01*
X527200Y1113967D01*
X528000Y1113700D01*
X528800Y1113967D01*
X529400Y1114633D01*
X529800Y1115433D01*
X530100Y1116500D01*
X530200Y1117700D01*
X530100Y1118900D01*
X529800Y1119967D01*
X529400Y1120767D01*
X528800Y1121433D01*
X528000Y1121700D01*
G01X536000D02*
X535200Y1121433D01*
X534600Y1120767D01*
X534200Y1119967D01*
X533900Y1118900D01*
X533800Y1117700D01*
X533900Y1116500D01*
X534200Y1115433D01*
X534600Y1114633D01*
X535200Y1113967D01*
X536000Y1113700D01*
X536800Y1113967D01*
X537400Y1114633D01*
X537800Y1115433D01*
X538100Y1116500D01*
X538200Y1117700D01*
X538100Y1118900D01*
X537800Y1119967D01*
X537400Y1120767D01*
X536800Y1121433D01*
X536000Y1121700D01*
G01X541400Y1113700D02*
Y1121700D01*
X544000Y1115033D01*
X546600Y1121700D01*
Y1113700D01*
G01X550800Y1121700D02*
X553200D01*
G01X552000D02*
Y1113700D01*
G01X550800D02*
X553200D01*
G01X558000Y1121700D02*
Y1113700D01*
X562000D01*
G01X565900Y1114766D02*
X566700Y1114100D01*
X567600Y1113700D01*
X568400D01*
X569200Y1114100D01*
X569800Y1114766D01*
X570100Y1115700D01*
X569900Y1116633D01*
X569400Y1117433D01*
X568500Y1117967D01*
X567300Y1118233D01*
X566600Y1118767D01*
X566300Y1119700D01*
X566500Y1120633D01*
X567000Y1121300D01*
X567700Y1121700D01*
X568400D01*
X569100Y1121433D01*
X569700Y1120767D01*
G01X576000Y1113433D02*
X575800Y1113567D01*
Y1113833D01*
X576000Y1113967D01*
X576200Y1113833D01*
Y1113567D01*
X576000Y1113433D01*
G01X589800Y1113700D02*
Y1121700D01*
X591800D01*
X592600Y1121300D01*
X593200Y1120767D01*
X593700Y1119967D01*
X594100Y1119033D01*
X594200Y1117700D01*
X594100Y1116367D01*
X593700Y1115433D01*
X593200Y1114633D01*
X592600Y1114100D01*
X591800Y1113700D01*
X589800D01*
G01X598000D02*
Y1121700D01*
X600500D01*
X601300Y1121300D01*
X601800Y1120767D01*
X602000Y1119700D01*
X601800Y1118633D01*
X601200Y1117967D01*
X600500Y1117567D01*
X598000D01*
G01X600500D02*
X602000Y1113700D01*
G01X606800Y1121700D02*
X609200D01*
G01X608000D02*
Y1113700D01*
G01X606800D02*
X609200D01*
G01X614000Y1121700D02*
Y1113700D01*
X618000D01*
G01X622000Y1121700D02*
Y1113700D01*
X626000D01*
G01X630200Y1113433D02*
X633800Y1121700D01*
G01X638100Y1113700D02*
Y1121700D01*
X641900D01*
G01X640500Y1117833D02*
X638100D01*
G01X650000Y1113700D02*
X646000D01*
Y1121700D01*
X650000D01*
G01X648400Y1117833D02*
X646000D01*
G01X653500Y1113700D02*
X656000Y1121700D01*
X658500Y1113700D01*
G01X657600Y1116500D02*
X654400D01*
G01X664000Y1121700D02*
Y1113700D01*
G01X661700Y1121700D02*
X666300D01*
G01X669800D02*
Y1115967D01*
X670200Y1114766D01*
X671000Y1113967D01*
X672000Y1113700D01*
X673000Y1113967D01*
X673800Y1114766D01*
X674200Y1115967D01*
Y1121700D01*
G01X678000Y1113700D02*
Y1121700D01*
X680500D01*
X681300Y1121300D01*
X681800Y1120767D01*
X682000Y1119700D01*
X681800Y1118633D01*
X681200Y1117967D01*
X680500Y1117567D01*
X678000D01*
G01X680500D02*
X682000Y1113700D01*
G01X690000D02*
X686000D01*
Y1121700D01*
X690000D01*
G01X688400Y1117833D02*
X686000D01*
G01X694200Y1113433D02*
X697800Y1121700D01*
G01X702000Y1113700D02*
Y1121700D01*
X704500D01*
X705300Y1121300D01*
X705800Y1120767D01*
X706000Y1119700D01*
X705800Y1118633D01*
X705200Y1117967D01*
X704500Y1117567D01*
X702000D01*
G01X704500D02*
X706000Y1113700D01*
G01X712000D02*
X711200Y1113833D01*
X710500Y1114367D01*
X709900Y1115167D01*
X709500Y1116100D01*
X709300Y1117167D01*
Y1118233D01*
X709500Y1119300D01*
X709900Y1120233D01*
X710500Y1121033D01*
X711200Y1121567D01*
X712000Y1121700D01*
X712800Y1121567D01*
X713500Y1121033D01*
X714100Y1120233D01*
X714500Y1119300D01*
X714700Y1118233D01*
Y1117167D01*
X714500Y1116100D01*
X714100Y1115167D01*
X713500Y1114367D01*
X712800Y1113833D01*
X712000Y1113700D01*
G01X717800Y1121700D02*
Y1115967D01*
X718200Y1114766D01*
X719000Y1113967D01*
X720000Y1113700D01*
X721000Y1113967D01*
X721800Y1114766D01*
X722200Y1115967D01*
Y1121700D01*
G01X728000D02*
Y1113700D01*
G01X725700Y1121700D02*
X730300D01*
G01X738000Y1113700D02*
X734000D01*
Y1121700D01*
X738000D01*
G01X736400Y1117833D02*
X734000D01*
G01X742200Y1113433D02*
X745800Y1121700D01*
G01X750000Y1113700D02*
Y1121700D01*
X752400D01*
X753200Y1121300D01*
X753800Y1120367D01*
X754000Y1119300D01*
X753800Y1118233D01*
X753300Y1117433D01*
X752400Y1117033D01*
X750000D01*
G01X758000Y1113700D02*
Y1121700D01*
X760500D01*
X761300Y1121300D01*
X761800Y1120767D01*
X762000Y1119700D01*
X761800Y1118633D01*
X761200Y1117967D01*
X760500Y1117567D01*
X758000D01*
G01X760500D02*
X762000Y1113700D01*
G01X768000D02*
X767200Y1113833D01*
X766500Y1114367D01*
X765900Y1115167D01*
X765500Y1116100D01*
X765300Y1117167D01*
Y1118233D01*
X765500Y1119300D01*
X765900Y1120233D01*
X766500Y1121033D01*
X767200Y1121567D01*
X768000Y1121700D01*
X768800Y1121567D01*
X769500Y1121033D01*
X770100Y1120233D01*
X770500Y1119300D01*
X770700Y1118233D01*
Y1117167D01*
X770500Y1116100D01*
X770100Y1115167D01*
X769500Y1114367D01*
X768800Y1113833D01*
X768000Y1113700D01*
G01X774100D02*
Y1121700D01*
X777900D01*
G01X776500Y1117833D02*
X774100D01*
G01X782800Y1121700D02*
X785200D01*
G01X784000D02*
Y1113700D01*
G01X782800D02*
X785200D01*
G01X790000Y1121700D02*
Y1113700D01*
X794000D01*
G01X802000D02*
X798000D01*
Y1121700D01*
X802000D01*
G01X800400Y1117833D02*
X798000D01*
G01X813900Y1114766D02*
X814700Y1114100D01*
X815600Y1113700D01*
X816400D01*
X817200Y1114100D01*
X817800Y1114766D01*
X818100Y1115700D01*
X817900Y1116633D01*
X817400Y1117433D01*
X816500Y1117967D01*
X815300Y1118233D01*
X814600Y1118767D01*
X814300Y1119700D01*
X814500Y1120633D01*
X815000Y1121300D01*
X815700Y1121700D01*
X816400D01*
X817100Y1121433D01*
X817700Y1120767D01*
G01X822000Y1113700D02*
Y1121700D01*
X824400D01*
X825200Y1121300D01*
X825800Y1120367D01*
X826000Y1119300D01*
X825800Y1118233D01*
X825300Y1117433D01*
X824400Y1117033D01*
X822000D01*
G01X829500Y1113700D02*
X832000Y1121700D01*
X834500Y1113700D01*
G01X833600Y1116500D02*
X830400D01*
G01X842200Y1121033D02*
X841600Y1121433D01*
X840900Y1121700D01*
X840100D01*
X839200Y1121300D01*
X838500Y1120633D01*
X838000Y1119833D01*
X837600Y1118500D01*
X837500Y1117300D01*
X837700Y1116100D01*
X838000Y1115300D01*
X838600Y1114500D01*
X839300Y1113967D01*
X840000Y1113700D01*
X840700D01*
X841400Y1113967D01*
X842000Y1114367D01*
X842500Y1114900D01*
G01X846800Y1121700D02*
X849200D01*
G01X848000D02*
Y1113700D01*
G01X846800D02*
X849200D01*
G01X853700D02*
Y1121700D01*
X858300Y1113700D01*
Y1121700D01*
G01X864600Y1117700D02*
X866600D01*
Y1115300D01*
X866000Y1114500D01*
X865300Y1113967D01*
X864300Y1113700D01*
X863300Y1113967D01*
X862600Y1114500D01*
X862000Y1115300D01*
X861600Y1116233D01*
X861400Y1117300D01*
Y1118233D01*
X861600Y1119033D01*
X862000Y1119967D01*
X862600Y1120767D01*
X863200Y1121300D01*
X864000Y1121700D01*
X864700D01*
X865500Y1121433D01*
X866100Y1120900D01*
G01X877500Y1113700D02*
X880000Y1121700D01*
X882500Y1113700D01*
G01X881600Y1116500D02*
X878400D01*
G01X886000Y1121700D02*
Y1113700D01*
X890000D01*
G01X894000Y1121700D02*
Y1113700D01*
X898000D01*
G01X909800Y1121700D02*
Y1115967D01*
X910200Y1114766D01*
X911000Y1113967D01*
X912000Y1113700D01*
X913000Y1113967D01*
X913800Y1114766D01*
X914200Y1115967D01*
Y1121700D01*
G01X917900Y1114766D02*
X918700Y1114100D01*
X919600Y1113700D01*
X920400D01*
X921200Y1114100D01*
X921800Y1114766D01*
X922100Y1115700D01*
X921900Y1116633D01*
X921400Y1117433D01*
X920500Y1117967D01*
X919300Y1118233D01*
X918600Y1118767D01*
X918300Y1119700D01*
X918500Y1120633D01*
X919000Y1121300D01*
X919700Y1121700D01*
X920400D01*
X921100Y1121433D01*
X921700Y1120767D01*
G01X926800Y1121700D02*
X929200D01*
G01X928000D02*
Y1113700D01*
G01X926800D02*
X929200D01*
G01X933700D02*
Y1121700D01*
X938300Y1113700D01*
Y1121700D01*
G01X944600Y1117700D02*
X946600D01*
Y1115300D01*
X946000Y1114500D01*
X945300Y1113967D01*
X944300Y1113700D01*
X943300Y1113967D01*
X942600Y1114500D01*
X942000Y1115300D01*
X941600Y1116233D01*
X941400Y1117300D01*
Y1118233D01*
X941600Y1119033D01*
X942000Y1119967D01*
X942600Y1120767D01*
X943200Y1121300D01*
X944000Y1121700D01*
X944700D01*
X945500Y1121433D01*
X946100Y1120900D01*
G01X960000Y1113700D02*
Y1121700D01*
X958800Y1120100D01*
G01Y1113700D02*
X961200D01*
G01X968000Y1121700D02*
X967200Y1121433D01*
X966600Y1120767D01*
X966200Y1119967D01*
X965900Y1118900D01*
X965800Y1117700D01*
X965900Y1116500D01*
X966200Y1115433D01*
X966600Y1114633D01*
X967200Y1113967D01*
X968000Y1113700D01*
X968800Y1113967D01*
X969400Y1114633D01*
X969800Y1115433D01*
X970100Y1116500D01*
X970200Y1117700D01*
X970100Y1118900D01*
X969800Y1119967D01*
X969400Y1120767D01*
X968800Y1121433D01*
X968000Y1121700D01*
G01X976000D02*
X975200Y1121433D01*
X974600Y1120767D01*
X974200Y1119967D01*
X973900Y1118900D01*
X973800Y1117700D01*
X973900Y1116500D01*
X974200Y1115433D01*
X974600Y1114633D01*
X975200Y1113967D01*
X976000Y1113700D01*
X976800Y1113967D01*
X977400Y1114633D01*
X977800Y1115433D01*
X978100Y1116500D01*
X978200Y1117700D01*
X978100Y1118900D01*
X977800Y1119967D01*
X977400Y1120767D01*
X976800Y1121433D01*
X976000Y1121700D01*
G01X981400Y1113700D02*
Y1121700D01*
X984000Y1115033D01*
X986600Y1121700D01*
Y1113700D01*
G01X990800Y1121700D02*
X993200D01*
G01X992000D02*
Y1113700D01*
G01X990800D02*
X993200D01*
G01X998000Y1121700D02*
Y1113700D01*
X1002000D01*
G01X1005900Y1114766D02*
X1006700Y1114100D01*
X1007600Y1113700D01*
X1008400D01*
X1009200Y1114100D01*
X1009800Y1114766D01*
X1010100Y1115700D01*
X1009900Y1116633D01*
X1009400Y1117433D01*
X1008500Y1117967D01*
X1007300Y1118233D01*
X1006600Y1118767D01*
X1006300Y1119700D01*
X1006500Y1120633D01*
X1007000Y1121300D01*
X1007700Y1121700D01*
X1008400D01*
X1009100Y1121433D01*
X1009700Y1120767D01*
G01X1016000Y1113433D02*
X1015800Y1113567D01*
Y1113833D01*
X1016000Y1113967D01*
X1016200Y1113833D01*
Y1113567D01*
X1016000Y1113433D01*
G01X1038000Y1121700D02*
Y1113700D01*
X1042000D01*
G01X1045500D02*
X1048000Y1121700D01*
X1050500Y1113700D01*
G01X1049600Y1116500D02*
X1046400D01*
G01X1056800Y1117967D02*
X1057200Y1118367D01*
X1057500Y1119033D01*
X1057700Y1119967D01*
X1057500Y1120767D01*
X1057100Y1121300D01*
X1056400Y1121700D01*
X1053700D01*
Y1113700D01*
X1057000D01*
X1057700Y1114233D01*
X1058100Y1115033D01*
X1058300Y1115967D01*
X1058100Y1116900D01*
X1057500Y1117700D01*
X1056800Y1117967D01*
X1053700D01*
G01X1066000Y1113700D02*
X1062000D01*
Y1121700D01*
X1066000D01*
G01X1064400Y1117833D02*
X1062000D01*
G01X1070000Y1121700D02*
Y1113700D01*
X1074000D01*
G01X1085500D02*
X1088000Y1121700D01*
X1090500Y1113700D01*
G01X1089600Y1116500D02*
X1086400D01*
G01X1094000Y1113700D02*
Y1121700D01*
X1096500D01*
X1097300Y1121300D01*
X1097800Y1120767D01*
X1098000Y1119700D01*
X1097800Y1118633D01*
X1097200Y1117967D01*
X1096500Y1117567D01*
X1094000D01*
G01X1096500D02*
X1098000Y1113700D01*
G01X1106000D02*
X1102000D01*
Y1121700D01*
X1106000D01*
G01X1104400Y1117833D02*
X1102000D01*
G01X1109500Y1113700D02*
X1112000Y1121700D01*
X1114500Y1113700D01*
G01X1113600Y1116500D02*
X1110400D01*
G01X1125700Y1113700D02*
Y1121700D01*
X1130300Y1113700D01*
Y1121700D01*
G01X1136000Y1113700D02*
X1135200Y1113833D01*
X1134500Y1114367D01*
X1133900Y1115167D01*
X1133500Y1116100D01*
X1133300Y1117167D01*
Y1118233D01*
X1133500Y1119300D01*
X1133900Y1120233D01*
X1134500Y1121033D01*
X1135200Y1121567D01*
X1136000Y1121700D01*
X1136800Y1121567D01*
X1137500Y1121033D01*
X1138100Y1120233D01*
X1138500Y1119300D01*
X1138700Y1118233D01*
Y1117167D01*
X1138500Y1116100D01*
X1138100Y1115167D01*
X1137500Y1114367D01*
X1136800Y1113833D01*
X1136000Y1113700D01*
G01X1149500D02*
X1152000Y1121700D01*
X1154500Y1113700D01*
G01X1153600Y1116500D02*
X1150400D01*
G01X1157800Y1113700D02*
Y1121700D01*
X1159800D01*
X1160600Y1121300D01*
X1161200Y1120767D01*
X1161700Y1119967D01*
X1162100Y1119033D01*
X1162200Y1117700D01*
X1162100Y1116367D01*
X1161700Y1115433D01*
X1161200Y1114633D01*
X1160600Y1114100D01*
X1159800Y1113700D01*
X1157800D01*
G01X1165800D02*
Y1121700D01*
X1167800D01*
X1168600Y1121300D01*
X1169200Y1120767D01*
X1169700Y1119967D01*
X1170100Y1119033D01*
X1170200Y1117700D01*
X1170100Y1116367D01*
X1169700Y1115433D01*
X1169200Y1114633D01*
X1168600Y1114100D01*
X1167800Y1113700D01*
X1165800D01*
G01X1181800D02*
Y1121700D01*
X1183800D01*
X1184600Y1121300D01*
X1185200Y1120767D01*
X1185700Y1119967D01*
X1186100Y1119033D01*
X1186200Y1117700D01*
X1186100Y1116367D01*
X1185700Y1115433D01*
X1185200Y1114633D01*
X1184600Y1114100D01*
X1183800Y1113700D01*
X1181800D01*
G01X1189800Y1121700D02*
Y1115967D01*
X1190200Y1114766D01*
X1191000Y1113967D01*
X1192000Y1113700D01*
X1193000Y1113967D01*
X1193800Y1114766D01*
X1194200Y1115967D01*
Y1121700D01*
G01X1197400Y1113700D02*
Y1121700D01*
X1200000Y1115033D01*
X1202600Y1121700D01*
Y1113700D01*
G01X1205400D02*
Y1121700D01*
X1208000Y1115033D01*
X1210600Y1121700D01*
Y1113700D01*
G01X1216000D02*
Y1117300D01*
X1214000Y1121700D01*
G01X1218000D02*
X1216000Y1117300D01*
G01X1230000Y1113700D02*
Y1121700D01*
X1232400D01*
X1233200Y1121300D01*
X1233800Y1120367D01*
X1234000Y1119300D01*
X1233800Y1118233D01*
X1233300Y1117433D01*
X1232400Y1117033D01*
X1230000D01*
G01X1237500Y1113700D02*
X1240000Y1121700D01*
X1242500Y1113700D01*
G01X1241600Y1116500D02*
X1238400D01*
G01X1245800Y1113700D02*
Y1121700D01*
X1247800D01*
X1248600Y1121300D01*
X1249200Y1120767D01*
X1249700Y1119967D01*
X1250100Y1119033D01*
X1250200Y1117700D01*
X1250100Y1116367D01*
X1249700Y1115433D01*
X1249200Y1114633D01*
X1248600Y1114100D01*
X1247800Y1113700D01*
X1245800D01*
G01X1256000Y1113433D02*
X1255800Y1113567D01*
Y1113833D01*
X1256000Y1113967D01*
X1256200Y1113833D01*
Y1113567D01*
X1256000Y1113433D01*
G01X-362200Y1174900D02*
X-361600Y1174233D01*
X-360900Y1173833D01*
X-360000Y1173700D01*
X-359100Y1173967D01*
X-358400Y1174500D01*
X-357900Y1175433D01*
X-357800Y1176500D01*
X-358000Y1177567D01*
X-358500Y1178233D01*
X-359200Y1178767D01*
X-359900Y1178900D01*
X-360600Y1178767D01*
X-361500Y1178233D01*
X-361200Y1181700D01*
X-358500D01*
G01X-352000Y1173433D02*
X-352200Y1173567D01*
Y1173833D01*
X-352000Y1173967D01*
X-351800Y1173833D01*
Y1173567D01*
X-352000Y1173433D01*
G01X-346000Y1173700D02*
Y1181700D01*
X-343600D01*
X-342800Y1181300D01*
X-342200Y1180367D01*
X-342000Y1179300D01*
X-342200Y1178233D01*
X-342700Y1177433D01*
X-343600Y1177033D01*
X-346000D01*
G01X-334000Y1173700D02*
X-338000D01*
Y1181700D01*
X-334000D01*
G01X-335600Y1177833D02*
X-338000D01*
G01X-326000Y1173700D02*
X-330000D01*
Y1181700D01*
X-326000D01*
G01X-327600Y1177833D02*
X-330000D01*
G01X-322000Y1181700D02*
Y1173700D01*
X-318000D01*
G01X-313200Y1181700D02*
X-310800D01*
G01X-312000D02*
Y1173700D01*
G01X-313200D02*
X-310800D01*
G01X-306300D02*
Y1181700D01*
X-301700Y1173700D01*
Y1181700D01*
G01X-295400Y1177700D02*
X-293400D01*
Y1175300D01*
X-294000Y1174500D01*
X-294700Y1173967D01*
X-295700Y1173700D01*
X-296700Y1173967D01*
X-297400Y1174500D01*
X-298000Y1175300D01*
X-298400Y1176233D01*
X-298600Y1177300D01*
Y1178233D01*
X-298400Y1179033D01*
X-298000Y1179967D01*
X-297400Y1180767D01*
X-296800Y1181300D01*
X-296000Y1181700D01*
X-295300D01*
X-294500Y1181433D01*
X-293900Y1180900D01*
G01X-282100Y1174766D02*
X-281300Y1174100D01*
X-280400Y1173700D01*
X-279600D01*
X-278800Y1174100D01*
X-278200Y1174766D01*
X-277900Y1175700D01*
X-278100Y1176633D01*
X-278600Y1177433D01*
X-279500Y1177967D01*
X-280700Y1178233D01*
X-281400Y1178767D01*
X-281700Y1179700D01*
X-281500Y1180633D01*
X-281000Y1181300D01*
X-280300Y1181700D01*
X-279600D01*
X-278900Y1181433D01*
X-278300Y1180767D01*
G01X-272000Y1181700D02*
Y1173700D01*
G01X-274300Y1181700D02*
X-269700D01*
G01X-266000Y1173700D02*
Y1181700D01*
X-263500D01*
X-262700Y1181300D01*
X-262200Y1180767D01*
X-262000Y1179700D01*
X-262200Y1178633D01*
X-262800Y1177967D01*
X-263500Y1177567D01*
X-266000D01*
G01X-263500D02*
X-262000Y1173700D01*
G01X-254000D02*
X-258000D01*
Y1181700D01*
X-254000D01*
G01X-255600Y1177833D02*
X-258000D01*
G01X-250300Y1173700D02*
Y1181700D01*
X-245700Y1173700D01*
Y1181700D01*
G01X-239400Y1177700D02*
X-237400D01*
Y1175300D01*
X-238000Y1174500D01*
X-238700Y1173967D01*
X-239700Y1173700D01*
X-240700Y1173967D01*
X-241400Y1174500D01*
X-242000Y1175300D01*
X-242400Y1176233D01*
X-242600Y1177300D01*
Y1178233D01*
X-242400Y1179033D01*
X-242000Y1179967D01*
X-241400Y1180767D01*
X-240800Y1181300D01*
X-240000Y1181700D01*
X-239300D01*
X-238500Y1181433D01*
X-237900Y1180900D01*
G01X-232000Y1181700D02*
Y1173700D01*
G01X-234300Y1181700D02*
X-229700D01*
G01X-226100Y1173700D02*
Y1181700D01*
G01X-221900D02*
Y1173700D01*
G01Y1177700D02*
X-226100D01*
G01X-210500Y1173700D02*
X-208000Y1181700D01*
X-205500Y1173700D01*
G01X-206400Y1176500D02*
X-209600D01*
G01X-202300Y1173700D02*
Y1181700D01*
X-197700Y1173700D01*
Y1181700D01*
G01X-194200Y1173700D02*
Y1181700D01*
X-192200D01*
X-191400Y1181300D01*
X-190800Y1180767D01*
X-190300Y1179967D01*
X-189900Y1179033D01*
X-189800Y1177700D01*
X-189900Y1176367D01*
X-190300Y1175433D01*
X-190800Y1174633D01*
X-191400Y1174100D01*
X-192200Y1173700D01*
X-194200D01*
G01X-175200Y1177967D02*
X-174800Y1178367D01*
X-174500Y1179033D01*
X-174300Y1179967D01*
X-174500Y1180767D01*
X-174900Y1181300D01*
X-175600Y1181700D01*
X-178300D01*
Y1173700D01*
X-175000D01*
X-174300Y1174233D01*
X-173900Y1175033D01*
X-173700Y1175967D01*
X-173900Y1176900D01*
X-174500Y1177700D01*
X-175200Y1177967D01*
X-178300D01*
G01X-167400Y1177700D02*
X-165400D01*
Y1175300D01*
X-166000Y1174500D01*
X-166700Y1173967D01*
X-167700Y1173700D01*
X-168700Y1173967D01*
X-169400Y1174500D01*
X-170000Y1175300D01*
X-170400Y1176233D01*
X-170600Y1177300D01*
Y1178233D01*
X-170400Y1179033D01*
X-170000Y1179967D01*
X-169400Y1180767D01*
X-168800Y1181300D01*
X-168000Y1181700D01*
X-167300D01*
X-166500Y1181433D01*
X-165900Y1180900D01*
G01X-162500Y1173700D02*
X-160000Y1181700D01*
X-157500Y1173700D01*
G01X-158400Y1176500D02*
X-161600D01*
G01X-146000Y1173700D02*
Y1181700D01*
X-143600D01*
X-142800Y1181300D01*
X-142200Y1180367D01*
X-142000Y1179300D01*
X-142200Y1178233D01*
X-142700Y1177433D01*
X-143600Y1177033D01*
X-146000D01*
G01X-138500Y1173700D02*
X-136000Y1181700D01*
X-133500Y1173700D01*
G01X-134400Y1176500D02*
X-137600D01*
G01X-130200Y1173700D02*
Y1181700D01*
X-128200D01*
X-127400Y1181300D01*
X-126800Y1180767D01*
X-126300Y1179967D01*
X-125900Y1179033D01*
X-125800Y1177700D01*
X-125900Y1176367D01*
X-126300Y1175433D01*
X-126800Y1174633D01*
X-127400Y1174100D01*
X-128200Y1173700D01*
X-130200D01*
G01X-122100Y1174766D02*
X-121300Y1174100D01*
X-120400Y1173700D01*
X-119600D01*
X-118800Y1174100D01*
X-118200Y1174766D01*
X-117900Y1175700D01*
X-118100Y1176633D01*
X-118600Y1177433D01*
X-119500Y1177967D01*
X-120700Y1178233D01*
X-121400Y1178767D01*
X-121700Y1179700D01*
X-121500Y1180633D01*
X-121000Y1181300D01*
X-120300Y1181700D01*
X-119600D01*
X-118900Y1181433D01*
X-118300Y1180767D01*
G01X-106500Y1173700D02*
X-104000Y1181700D01*
X-101500Y1173700D01*
G01X-102400Y1176500D02*
X-105600D01*
G01X-98200Y1173700D02*
Y1181700D01*
X-96200D01*
X-95400Y1181300D01*
X-94800Y1180767D01*
X-94300Y1179967D01*
X-93900Y1179033D01*
X-93800Y1177700D01*
X-93900Y1176367D01*
X-94300Y1175433D01*
X-94800Y1174633D01*
X-95400Y1174100D01*
X-96200Y1173700D01*
X-98200D01*
G01X-90100D02*
Y1181700D01*
G01X-85900D02*
Y1173700D01*
G01Y1177700D02*
X-90100D01*
G01X-78000Y1173700D02*
X-82000D01*
Y1181700D01*
X-78000D01*
G01X-79600Y1177833D02*
X-82000D01*
G01X-74100Y1174766D02*
X-73300Y1174100D01*
X-72400Y1173700D01*
X-71600D01*
X-70800Y1174100D01*
X-70200Y1174766D01*
X-69900Y1175700D01*
X-70100Y1176633D01*
X-70600Y1177433D01*
X-71500Y1177967D01*
X-72700Y1178233D01*
X-73400Y1178767D01*
X-73700Y1179700D01*
X-73500Y1180633D01*
X-73000Y1181300D01*
X-72300Y1181700D01*
X-71600D01*
X-70900Y1181433D01*
X-70300Y1180767D01*
G01X-65200Y1181700D02*
X-62800D01*
G01X-64000D02*
Y1173700D01*
G01X-65200D02*
X-62800D01*
G01X-56000D02*
X-56800Y1173833D01*
X-57500Y1174367D01*
X-58100Y1175167D01*
X-58500Y1176100D01*
X-58700Y1177167D01*
Y1178233D01*
X-58500Y1179300D01*
X-58100Y1180233D01*
X-57500Y1181033D01*
X-56800Y1181567D01*
X-56000Y1181700D01*
X-55200Y1181567D01*
X-54500Y1181033D01*
X-53900Y1180233D01*
X-53500Y1179300D01*
X-53300Y1178233D01*
Y1177167D01*
X-53500Y1176100D01*
X-53900Y1175167D01*
X-54500Y1174367D01*
X-55200Y1173833D01*
X-56000Y1173700D01*
G01X-50300D02*
Y1181700D01*
X-45700Y1173700D01*
Y1181700D01*
G01X-32000D02*
Y1173700D01*
G01X-34300Y1181700D02*
X-29700D01*
G01X-22000Y1173700D02*
X-26000D01*
Y1181700D01*
X-22000D01*
G01X-23600Y1177833D02*
X-26000D01*
G01X-18100Y1174766D02*
X-17300Y1174100D01*
X-16400Y1173700D01*
X-15600D01*
X-14800Y1174100D01*
X-14200Y1174766D01*
X-13900Y1175700D01*
X-14100Y1176633D01*
X-14600Y1177433D01*
X-15500Y1177967D01*
X-16700Y1178233D01*
X-17400Y1178767D01*
X-17700Y1179700D01*
X-17500Y1180633D01*
X-17000Y1181300D01*
X-16300Y1181700D01*
X-15600D01*
X-14900Y1181433D01*
X-14300Y1180767D01*
G01X-8000Y1181700D02*
Y1173700D01*
G01X-10300Y1181700D02*
X-5700D01*
G01X6000Y1173700D02*
Y1181700D01*
X8400D01*
X9200Y1181300D01*
X9800Y1180367D01*
X10000Y1179300D01*
X9800Y1178233D01*
X9300Y1177433D01*
X8400Y1177033D01*
X6000D01*
G01X13500Y1173700D02*
X16000Y1181700D01*
X18500Y1173700D01*
G01X17600Y1176500D02*
X14400D01*
G01X24000Y1181700D02*
Y1173700D01*
G01X21700Y1181700D02*
X26300D01*
G01X32000D02*
Y1173700D01*
G01X29700Y1181700D02*
X34300D01*
G01X42000Y1173700D02*
X38000D01*
Y1181700D01*
X42000D01*
G01X40400Y1177833D02*
X38000D01*
G01X46000Y1173700D02*
Y1181700D01*
X48500D01*
X49300Y1181300D01*
X49800Y1180767D01*
X50000Y1179700D01*
X49800Y1178633D01*
X49200Y1177967D01*
X48500Y1177567D01*
X46000D01*
G01X48500D02*
X50000Y1173700D01*
G01X53700D02*
Y1181700D01*
X58300Y1173700D01*
Y1181700D01*
G01X61900Y1174766D02*
X62700Y1174100D01*
X63600Y1173700D01*
X64400D01*
X65200Y1174100D01*
X65800Y1174766D01*
X66100Y1175700D01*
X65900Y1176633D01*
X65400Y1177433D01*
X64500Y1177967D01*
X63300Y1178233D01*
X62600Y1178767D01*
X62300Y1179700D01*
X62500Y1180633D01*
X63000Y1181300D01*
X63700Y1181700D01*
X64400D01*
X65100Y1181433D01*
X65700Y1180767D01*
G01X72000Y1173433D02*
X71800Y1173567D01*
Y1173833D01*
X72000Y1173967D01*
X72200Y1173833D01*
Y1173567D01*
X72000Y1173433D01*
G01X-358800Y1248700D02*
Y1256700D01*
X-362500Y1250967D01*
X-357500D01*
G01X-352000Y1248433D02*
X-352200Y1248567D01*
Y1248833D01*
X-352000Y1248967D01*
X-351800Y1248833D01*
Y1248567D01*
X-352000Y1248433D01*
G01X-341800Y1256033D02*
X-342400Y1256433D01*
X-343100Y1256700D01*
X-343900D01*
X-344800Y1256300D01*
X-345500Y1255633D01*
X-346000Y1254833D01*
X-346400Y1253500D01*
X-346500Y1252300D01*
X-346300Y1251100D01*
X-346000Y1250300D01*
X-345400Y1249500D01*
X-344700Y1248967D01*
X-344000Y1248700D01*
X-343300D01*
X-342600Y1248967D01*
X-342000Y1249367D01*
X-341500Y1249900D01*
G01X-336000Y1248700D02*
X-336800Y1248833D01*
X-337500Y1249367D01*
X-338100Y1250167D01*
X-338500Y1251100D01*
X-338700Y1252167D01*
Y1253233D01*
X-338500Y1254300D01*
X-338100Y1255233D01*
X-337500Y1256033D01*
X-336800Y1256567D01*
X-336000Y1256700D01*
X-335200Y1256567D01*
X-334500Y1256033D01*
X-333900Y1255233D01*
X-333500Y1254300D01*
X-333300Y1253233D01*
Y1252167D01*
X-333500Y1251100D01*
X-333900Y1250167D01*
X-334500Y1249367D01*
X-335200Y1248833D01*
X-336000Y1248700D01*
G01X-330300D02*
Y1256700D01*
X-325700Y1248700D01*
Y1256700D01*
G01X-320000D02*
Y1248700D01*
G01X-322300Y1256700D02*
X-317700D01*
G01X-314000Y1248700D02*
Y1256700D01*
X-311500D01*
X-310700Y1256300D01*
X-310200Y1255767D01*
X-310000Y1254700D01*
X-310200Y1253633D01*
X-310800Y1252967D01*
X-311500Y1252567D01*
X-314000D01*
G01X-311500D02*
X-310000Y1248700D01*
G01X-304000D02*
X-304800Y1248833D01*
X-305500Y1249367D01*
X-306100Y1250167D01*
X-306500Y1251100D01*
X-306700Y1252167D01*
Y1253233D01*
X-306500Y1254300D01*
X-306100Y1255233D01*
X-305500Y1256033D01*
X-304800Y1256567D01*
X-304000Y1256700D01*
X-303200Y1256567D01*
X-302500Y1256033D01*
X-301900Y1255233D01*
X-301500Y1254300D01*
X-301300Y1253233D01*
Y1252167D01*
X-301500Y1251100D01*
X-301900Y1250167D01*
X-302500Y1249367D01*
X-303200Y1248833D01*
X-304000Y1248700D01*
G01X-298000Y1256700D02*
Y1248700D01*
X-294000D01*
G01X-290000Y1256700D02*
Y1248700D01*
X-286000D01*
G01X-278000D02*
X-282000D01*
Y1256700D01*
X-278000D01*
G01X-279600Y1252833D02*
X-282000D01*
G01X-274200Y1248700D02*
Y1256700D01*
X-272200D01*
X-271400Y1256300D01*
X-270800Y1255767D01*
X-270300Y1254967D01*
X-269900Y1254033D01*
X-269800Y1252700D01*
X-269900Y1251367D01*
X-270300Y1250433D01*
X-270800Y1249633D01*
X-271400Y1249100D01*
X-272200Y1248700D01*
X-274200D01*
G01X-257200Y1256700D02*
X-254800D01*
G01X-256000D02*
Y1248700D01*
G01X-257200D02*
X-254800D01*
G01X-250600D02*
Y1256700D01*
X-248000Y1250033D01*
X-245400Y1256700D01*
Y1248700D01*
G01X-242000D02*
Y1256700D01*
X-239600D01*
X-238800Y1256300D01*
X-238200Y1255367D01*
X-238000Y1254300D01*
X-238200Y1253233D01*
X-238700Y1252433D01*
X-239600Y1252033D01*
X-242000D01*
G01X-230000Y1248700D02*
X-234000D01*
Y1256700D01*
X-230000D01*
G01X-231600Y1252833D02*
X-234000D01*
G01X-226200Y1248700D02*
Y1256700D01*
X-224200D01*
X-223400Y1256300D01*
X-222800Y1255767D01*
X-222300Y1254967D01*
X-221900Y1254033D01*
X-221800Y1252700D01*
X-221900Y1251367D01*
X-222300Y1250433D01*
X-222800Y1249633D01*
X-223400Y1249100D01*
X-224200Y1248700D01*
X-226200D01*
G01X-218500D02*
X-216000Y1256700D01*
X-213500Y1248700D01*
G01X-214400Y1251500D02*
X-217600D01*
G01X-210300Y1248700D02*
Y1256700D01*
X-205700Y1248700D01*
Y1256700D01*
G01X-197800Y1256033D02*
X-198400Y1256433D01*
X-199100Y1256700D01*
X-199900D01*
X-200800Y1256300D01*
X-201500Y1255633D01*
X-202000Y1254833D01*
X-202400Y1253500D01*
X-202500Y1252300D01*
X-202300Y1251100D01*
X-202000Y1250300D01*
X-201400Y1249500D01*
X-200700Y1248967D01*
X-200000Y1248700D01*
X-199300D01*
X-198600Y1248967D01*
X-198000Y1249367D01*
X-197500Y1249900D01*
G01X-190000Y1248700D02*
X-194000D01*
Y1256700D01*
X-190000D01*
G01X-191600Y1252833D02*
X-194000D01*
G01X-175200Y1252967D02*
X-174800Y1253367D01*
X-174500Y1254033D01*
X-174300Y1254967D01*
X-174500Y1255767D01*
X-174900Y1256300D01*
X-175600Y1256700D01*
X-178300D01*
Y1248700D01*
X-175000D01*
X-174300Y1249233D01*
X-173900Y1250033D01*
X-173700Y1250967D01*
X-173900Y1251900D01*
X-174500Y1252700D01*
X-175200Y1252967D01*
X-178300D01*
G01X-168000Y1248700D02*
X-168800Y1248833D01*
X-169500Y1249367D01*
X-170100Y1250167D01*
X-170500Y1251100D01*
X-170700Y1252167D01*
Y1253233D01*
X-170500Y1254300D01*
X-170100Y1255233D01*
X-169500Y1256033D01*
X-168800Y1256567D01*
X-168000Y1256700D01*
X-167200Y1256567D01*
X-166500Y1256033D01*
X-165900Y1255233D01*
X-165500Y1254300D01*
X-165300Y1253233D01*
Y1252167D01*
X-165500Y1251100D01*
X-165900Y1250167D01*
X-166500Y1249367D01*
X-167200Y1248833D01*
X-168000Y1248700D01*
G01X-162500D02*
X-160000Y1256700D01*
X-157500Y1248700D01*
G01X-158400Y1251500D02*
X-161600D01*
G01X-154000Y1248700D02*
Y1256700D01*
X-151500D01*
X-150700Y1256300D01*
X-150200Y1255767D01*
X-150000Y1254700D01*
X-150200Y1253633D01*
X-150800Y1252967D01*
X-151500Y1252567D01*
X-154000D01*
G01X-151500D02*
X-150000Y1248700D01*
G01X-146200D02*
Y1256700D01*
X-144200D01*
X-143400Y1256300D01*
X-142800Y1255767D01*
X-142300Y1254967D01*
X-141900Y1254033D01*
X-141800Y1252700D01*
X-141900Y1251367D01*
X-142300Y1250433D01*
X-142800Y1249633D01*
X-143400Y1249100D01*
X-144200Y1248700D01*
X-146200D01*
G01X-136000Y1248433D02*
X-136200Y1248567D01*
Y1248833D01*
X-136000Y1248967D01*
X-135800Y1248833D01*
Y1248567D01*
X-136000Y1248433D01*
G01X-122100Y1249766D02*
X-121300Y1249100D01*
X-120400Y1248700D01*
X-119600D01*
X-118800Y1249100D01*
X-118200Y1249766D01*
X-117900Y1250700D01*
X-118100Y1251633D01*
X-118600Y1252433D01*
X-119500Y1252967D01*
X-120700Y1253233D01*
X-121400Y1253767D01*
X-121700Y1254700D01*
X-121500Y1255633D01*
X-121000Y1256300D01*
X-120300Y1256700D01*
X-119600D01*
X-118900Y1256433D01*
X-118300Y1255767D01*
G01X-110000Y1248700D02*
X-114000D01*
Y1256700D01*
X-110000D01*
G01X-111600Y1252833D02*
X-114000D01*
G01X-102000Y1248700D02*
X-106000D01*
Y1256700D01*
X-102000D01*
G01X-103600Y1252833D02*
X-106000D01*
G01X-90000Y1256700D02*
Y1248700D01*
X-86000D01*
G01X-82500D02*
X-80000Y1256700D01*
X-77500Y1248700D01*
G01X-78400Y1251500D02*
X-81600D01*
G01X-72000Y1248700D02*
Y1252300D01*
X-74000Y1256700D01*
G01X-70000D02*
X-72000Y1252300D01*
G01X-62000Y1248700D02*
X-66000D01*
Y1256700D01*
X-62000D01*
G01X-63600Y1252833D02*
X-66000D01*
G01X-58000Y1248700D02*
Y1256700D01*
X-55500D01*
X-54700Y1256300D01*
X-54200Y1255767D01*
X-54000Y1254700D01*
X-54200Y1253633D01*
X-54800Y1252967D01*
X-55500Y1252567D01*
X-58000D01*
G01X-55500D02*
X-54000Y1248700D01*
G01X-42100Y1249766D02*
X-41300Y1249100D01*
X-40400Y1248700D01*
X-39600D01*
X-38800Y1249100D01*
X-38200Y1249766D01*
X-37900Y1250700D01*
X-38100Y1251633D01*
X-38600Y1252433D01*
X-39500Y1252967D01*
X-40700Y1253233D01*
X-41400Y1253767D01*
X-41700Y1254700D01*
X-41500Y1255633D01*
X-41000Y1256300D01*
X-40300Y1256700D01*
X-39600D01*
X-38900Y1256433D01*
X-38300Y1255767D01*
G01X-32000Y1256700D02*
Y1248700D01*
G01X-34300Y1256700D02*
X-29700D01*
G01X-26500Y1248700D02*
X-24000Y1256700D01*
X-21500Y1248700D01*
G01X-22400Y1251500D02*
X-25600D01*
G01X-13800Y1256033D02*
X-14400Y1256433D01*
X-15100Y1256700D01*
X-15900D01*
X-16800Y1256300D01*
X-17500Y1255633D01*
X-18000Y1254833D01*
X-18400Y1253500D01*
X-18500Y1252300D01*
X-18300Y1251100D01*
X-18000Y1250300D01*
X-17400Y1249500D01*
X-16700Y1248967D01*
X-16000Y1248700D01*
X-15300D01*
X-14600Y1248967D01*
X-14000Y1249367D01*
X-13500Y1249900D01*
G01X-10200Y1248700D02*
Y1256700D01*
G01X-6400D02*
X-10200Y1251766D01*
G01X-5800Y1248700D02*
X-8500Y1254033D01*
G01X-2200Y1256700D02*
Y1250967D01*
X-1800Y1249766D01*
X-1000Y1248967D01*
X0Y1248700D01*
X1000Y1248967D01*
X1800Y1249766D01*
X2200Y1250967D01*
Y1256700D01*
G01X6000Y1248700D02*
Y1256700D01*
X8400D01*
X9200Y1256300D01*
X9800Y1255367D01*
X10000Y1254300D01*
X9800Y1253233D01*
X9300Y1252433D01*
X8400Y1252033D01*
X6000D01*
G01X21500Y1248700D02*
X24000Y1256700D01*
X26500Y1248700D01*
G01X25600Y1251500D02*
X22400D01*
G01X29700Y1248700D02*
Y1256700D01*
X34300Y1248700D01*
Y1256700D01*
G01X37800Y1248700D02*
Y1256700D01*
X39800D01*
X40600Y1256300D01*
X41200Y1255767D01*
X41700Y1254967D01*
X42100Y1254033D01*
X42200Y1252700D01*
X42100Y1251367D01*
X41700Y1250433D01*
X41200Y1249633D01*
X40600Y1249100D01*
X39800Y1248700D01*
X37800D01*
G01X54800Y1256700D02*
X57200D01*
G01X56000D02*
Y1248700D01*
G01X54800D02*
X57200D01*
G01X61400D02*
Y1256700D01*
X64000Y1250033D01*
X66600Y1256700D01*
Y1248700D01*
G01X70000D02*
Y1256700D01*
X72400D01*
X73200Y1256300D01*
X73800Y1255367D01*
X74000Y1254300D01*
X73800Y1253233D01*
X73300Y1252433D01*
X72400Y1252033D01*
X70000D01*
G01X82000Y1248700D02*
X78000D01*
Y1256700D01*
X82000D01*
G01X80400Y1252833D02*
X78000D01*
G01X85800Y1248700D02*
Y1256700D01*
X87800D01*
X88600Y1256300D01*
X89200Y1255767D01*
X89700Y1254967D01*
X90100Y1254033D01*
X90200Y1252700D01*
X90100Y1251367D01*
X89700Y1250433D01*
X89200Y1249633D01*
X88600Y1249100D01*
X87800Y1248700D01*
X85800D01*
G01X93500D02*
X96000Y1256700D01*
X98500Y1248700D01*
G01X97600Y1251500D02*
X94400D01*
G01X101700Y1248700D02*
Y1256700D01*
X106300Y1248700D01*
Y1256700D01*
G01X114200Y1256033D02*
X113600Y1256433D01*
X112900Y1256700D01*
X112100D01*
X111200Y1256300D01*
X110500Y1255633D01*
X110000Y1254833D01*
X109600Y1253500D01*
X109500Y1252300D01*
X109700Y1251100D01*
X110000Y1250300D01*
X110600Y1249500D01*
X111300Y1248967D01*
X112000Y1248700D01*
X112700D01*
X113400Y1248967D01*
X114000Y1249367D01*
X114500Y1249900D01*
G01X122000Y1248700D02*
X118000D01*
Y1256700D01*
X122000D01*
G01X120400Y1252833D02*
X118000D01*
G01X-362200Y1370300D02*
X-361600Y1369367D01*
X-360800Y1368833D01*
X-359900Y1368700D01*
X-359100Y1368833D01*
X-358300Y1369500D01*
X-357800Y1370300D01*
X-357700Y1371100D01*
X-357900Y1372033D01*
X-358600Y1372700D01*
X-359300Y1372967D01*
X-360200D01*
G01X-359300D02*
X-358700Y1373367D01*
X-358200Y1374033D01*
X-358000Y1374833D01*
X-358200Y1375633D01*
X-358700Y1376300D01*
X-359600Y1376700D01*
X-360500Y1376567D01*
X-361400Y1376033D01*
G01X-352000Y1368433D02*
X-352200Y1368567D01*
Y1368833D01*
X-352000Y1368967D01*
X-351800Y1368833D01*
Y1368567D01*
X-352000Y1368433D01*
G01X-346000Y1368700D02*
Y1376700D01*
X-343600D01*
X-342800Y1376300D01*
X-342200Y1375367D01*
X-342000Y1374300D01*
X-342200Y1373233D01*
X-342700Y1372433D01*
X-343600Y1372033D01*
X-346000D01*
G01X-333800Y1376033D02*
X-334400Y1376433D01*
X-335100Y1376700D01*
X-335900D01*
X-336800Y1376300D01*
X-337500Y1375633D01*
X-338000Y1374833D01*
X-338400Y1373500D01*
X-338500Y1372300D01*
X-338300Y1371100D01*
X-338000Y1370300D01*
X-337400Y1369500D01*
X-336700Y1368967D01*
X-336000Y1368700D01*
X-335300D01*
X-334600Y1368967D01*
X-334000Y1369367D01*
X-333500Y1369900D01*
G01X-327200Y1372967D02*
X-326800Y1373367D01*
X-326500Y1374033D01*
X-326300Y1374967D01*
X-326500Y1375767D01*
X-326900Y1376300D01*
X-327600Y1376700D01*
X-330300D01*
Y1368700D01*
X-327000D01*
X-326300Y1369233D01*
X-325900Y1370033D01*
X-325700Y1370967D01*
X-325900Y1371900D01*
X-326500Y1372700D01*
X-327200Y1372967D01*
X-330300D01*
G01X-314000Y1368700D02*
Y1376700D01*
X-311600D01*
X-310800Y1376300D01*
X-310200Y1375367D01*
X-310000Y1374300D01*
X-310200Y1373233D01*
X-310700Y1372433D01*
X-311600Y1372033D01*
X-314000D01*
G01X-306000Y1368700D02*
Y1376700D01*
X-303500D01*
X-302700Y1376300D01*
X-302200Y1375767D01*
X-302000Y1374700D01*
X-302200Y1373633D01*
X-302800Y1372967D01*
X-303500Y1372567D01*
X-306000D01*
G01X-303500D02*
X-302000Y1368700D01*
G01X-296000D02*
X-296800Y1368833D01*
X-297500Y1369367D01*
X-298100Y1370167D01*
X-298500Y1371100D01*
X-298700Y1372167D01*
Y1373233D01*
X-298500Y1374300D01*
X-298100Y1375233D01*
X-297500Y1376033D01*
X-296800Y1376567D01*
X-296000Y1376700D01*
X-295200Y1376567D01*
X-294500Y1376033D01*
X-293900Y1375233D01*
X-293500Y1374300D01*
X-293300Y1373233D01*
Y1372167D01*
X-293500Y1371100D01*
X-293900Y1370167D01*
X-294500Y1369367D01*
X-295200Y1368833D01*
X-296000Y1368700D01*
G01X-285800Y1376033D02*
X-286400Y1376433D01*
X-287100Y1376700D01*
X-287900D01*
X-288800Y1376300D01*
X-289500Y1375633D01*
X-290000Y1374833D01*
X-290400Y1373500D01*
X-290500Y1372300D01*
X-290300Y1371100D01*
X-290000Y1370300D01*
X-289400Y1369500D01*
X-288700Y1368967D01*
X-288000Y1368700D01*
X-287300D01*
X-286600Y1368967D01*
X-286000Y1369367D01*
X-285500Y1369900D01*
G01X-278000Y1368700D02*
X-282000D01*
Y1376700D01*
X-278000D01*
G01X-279600Y1372833D02*
X-282000D01*
G01X-274100Y1369766D02*
X-273300Y1369100D01*
X-272400Y1368700D01*
X-271600D01*
X-270800Y1369100D01*
X-270200Y1369766D01*
X-269900Y1370700D01*
X-270100Y1371633D01*
X-270600Y1372433D01*
X-271500Y1372967D01*
X-272700Y1373233D01*
X-273400Y1373767D01*
X-273700Y1374700D01*
X-273500Y1375633D01*
X-273000Y1376300D01*
X-272300Y1376700D01*
X-271600D01*
X-270900Y1376433D01*
X-270300Y1375767D01*
G01X-266100Y1369766D02*
X-265300Y1369100D01*
X-264400Y1368700D01*
X-263600D01*
X-262800Y1369100D01*
X-262200Y1369766D01*
X-261900Y1370700D01*
X-262100Y1371633D01*
X-262600Y1372433D01*
X-263500Y1372967D01*
X-264700Y1373233D01*
X-265400Y1373767D01*
X-265700Y1374700D01*
X-265500Y1375633D01*
X-265000Y1376300D01*
X-264300Y1376700D01*
X-263600D01*
X-262900Y1376433D01*
X-262300Y1375767D01*
G01X-256000Y1368433D02*
X-256200Y1368567D01*
Y1368833D01*
X-256000Y1368967D01*
X-255800Y1368833D01*
Y1368567D01*
X-256000Y1368433D01*
G01Y1372033D02*
X-256200Y1372167D01*
Y1372433D01*
X-256000Y1372567D01*
X-255800Y1372433D01*
Y1372167D01*
X-256000Y1372033D01*
G01X-361900Y1390367D02*
X-361300Y1391167D01*
X-360600Y1391567D01*
X-359800Y1391700D01*
X-358800Y1391433D01*
X-358100Y1390767D01*
X-357900Y1389967D01*
X-358000Y1389166D01*
X-358400Y1388500D01*
X-360400Y1387167D01*
X-361300Y1386233D01*
X-361900Y1384900D01*
X-362100Y1383700D01*
X-357900D01*
G01X-352000Y1383433D02*
X-352200Y1383567D01*
Y1383833D01*
X-352000Y1383967D01*
X-351800Y1383833D01*
Y1383567D01*
X-352000Y1383433D01*
G01X-345900Y1383700D02*
Y1391700D01*
X-342100D01*
G01X-343500Y1387833D02*
X-345900D01*
G01X-338500Y1383700D02*
X-336000Y1391700D01*
X-333500Y1383700D01*
G01X-334400Y1386500D02*
X-337600D01*
G01X-327200Y1387967D02*
X-326800Y1388367D01*
X-326500Y1389033D01*
X-326300Y1389967D01*
X-326500Y1390767D01*
X-326900Y1391300D01*
X-327600Y1391700D01*
X-330300D01*
Y1383700D01*
X-327000D01*
X-326300Y1384233D01*
X-325900Y1385033D01*
X-325700Y1385967D01*
X-325900Y1386900D01*
X-326500Y1387700D01*
X-327200Y1387967D01*
X-330300D01*
G01X-322000Y1383700D02*
Y1391700D01*
X-319500D01*
X-318700Y1391300D01*
X-318200Y1390767D01*
X-318000Y1389700D01*
X-318200Y1388633D01*
X-318800Y1387967D01*
X-319500Y1387567D01*
X-322000D01*
G01X-319500D02*
X-318000Y1383700D01*
G01X-313200Y1391700D02*
X-310800D01*
G01X-312000D02*
Y1383700D01*
G01X-313200D02*
X-310800D01*
G01X-301800Y1391033D02*
X-302400Y1391433D01*
X-303100Y1391700D01*
X-303900D01*
X-304800Y1391300D01*
X-305500Y1390633D01*
X-306000Y1389833D01*
X-306400Y1388500D01*
X-306500Y1387300D01*
X-306300Y1386100D01*
X-306000Y1385300D01*
X-305400Y1384500D01*
X-304700Y1383967D01*
X-304000Y1383700D01*
X-303300D01*
X-302600Y1383967D01*
X-302000Y1384367D01*
X-301500Y1384900D01*
G01X-298500Y1383700D02*
X-296000Y1391700D01*
X-293500Y1383700D01*
G01X-294400Y1386500D02*
X-297600D01*
G01X-288000Y1391700D02*
Y1383700D01*
G01X-290300Y1391700D02*
X-285700D01*
G01X-278000Y1383700D02*
X-282000D01*
Y1391700D01*
X-278000D01*
G01X-279600Y1387833D02*
X-282000D01*
G01X-266000Y1383700D02*
Y1391700D01*
X-263600D01*
X-262800Y1391300D01*
X-262200Y1390367D01*
X-262000Y1389300D01*
X-262200Y1388233D01*
X-262700Y1387433D01*
X-263600Y1387033D01*
X-266000D01*
G01X-254000Y1383700D02*
X-258000D01*
Y1391700D01*
X-254000D01*
G01X-255600Y1387833D02*
X-258000D01*
G01X-250000Y1383700D02*
Y1391700D01*
X-247500D01*
X-246700Y1391300D01*
X-246200Y1390767D01*
X-246000Y1389700D01*
X-246200Y1388633D01*
X-246800Y1387967D01*
X-247500Y1387567D01*
X-250000D01*
G01X-247500D02*
X-246000Y1383700D01*
G01X-232000D02*
X-232800Y1383833D01*
X-233500Y1384367D01*
X-234100Y1385167D01*
X-234500Y1386100D01*
X-234700Y1387167D01*
Y1388233D01*
X-234500Y1389300D01*
X-234100Y1390233D01*
X-233500Y1391033D01*
X-232800Y1391567D01*
X-232000Y1391700D01*
X-231200Y1391567D01*
X-230500Y1391033D01*
X-229900Y1390233D01*
X-229500Y1389300D01*
X-229300Y1388233D01*
Y1387167D01*
X-229500Y1386100D01*
X-229900Y1385167D01*
X-230500Y1384367D01*
X-231200Y1383833D01*
X-232000Y1383700D01*
G01X-231200Y1385833D02*
X-230000Y1383700D01*
G01X-226200Y1391700D02*
Y1385967D01*
X-225800Y1384766D01*
X-225000Y1383967D01*
X-224000Y1383700D01*
X-223000Y1383967D01*
X-222200Y1384766D01*
X-221800Y1385967D01*
Y1391700D01*
G01X-218500Y1383700D02*
X-216000Y1391700D01*
X-213500Y1383700D01*
G01X-214400Y1386500D02*
X-217600D01*
G01X-210300Y1383700D02*
Y1391700D01*
X-205700Y1383700D01*
Y1391700D01*
G01X-200000D02*
Y1383700D01*
G01X-202300Y1391700D02*
X-197700D01*
G01X-194500Y1383700D02*
X-192000Y1391700D01*
X-189500Y1383700D01*
G01X-190400Y1386500D02*
X-193600D01*
G01X-178000Y1383700D02*
Y1391700D01*
X-175600D01*
X-174800Y1391300D01*
X-174200Y1390367D01*
X-174000Y1389300D01*
X-174200Y1388233D01*
X-174700Y1387433D01*
X-175600Y1387033D01*
X-178000D01*
G01X-165800Y1391033D02*
X-166400Y1391433D01*
X-167100Y1391700D01*
X-167900D01*
X-168800Y1391300D01*
X-169500Y1390633D01*
X-170000Y1389833D01*
X-170400Y1388500D01*
X-170500Y1387300D01*
X-170300Y1386100D01*
X-170000Y1385300D01*
X-169400Y1384500D01*
X-168700Y1383967D01*
X-168000Y1383700D01*
X-167300D01*
X-166600Y1383967D01*
X-166000Y1384367D01*
X-165500Y1384900D01*
G01X-159200Y1387967D02*
X-158800Y1388367D01*
X-158500Y1389033D01*
X-158300Y1389967D01*
X-158500Y1390767D01*
X-158900Y1391300D01*
X-159600Y1391700D01*
X-162300D01*
Y1383700D01*
X-159000D01*
X-158300Y1384233D01*
X-157900Y1385033D01*
X-157700Y1385967D01*
X-157900Y1386900D01*
X-158500Y1387700D01*
X-159200Y1387967D01*
X-162300D01*
G01X-146100Y1384766D02*
X-145300Y1384100D01*
X-144400Y1383700D01*
X-143600D01*
X-142800Y1384100D01*
X-142200Y1384766D01*
X-141900Y1385700D01*
X-142100Y1386633D01*
X-142600Y1387433D01*
X-143500Y1387967D01*
X-144700Y1388233D01*
X-145400Y1388767D01*
X-145700Y1389700D01*
X-145500Y1390633D01*
X-145000Y1391300D01*
X-144300Y1391700D01*
X-143600D01*
X-142900Y1391433D01*
X-142300Y1390767D01*
G01X-138000Y1383700D02*
Y1391700D01*
X-135600D01*
X-134800Y1391300D01*
X-134200Y1390367D01*
X-134000Y1389300D01*
X-134200Y1388233D01*
X-134700Y1387433D01*
X-135600Y1387033D01*
X-138000D01*
G01X-126000Y1383700D02*
X-130000D01*
Y1391700D01*
X-126000D01*
G01X-127600Y1387833D02*
X-130000D01*
G01X-117800Y1391033D02*
X-118400Y1391433D01*
X-119100Y1391700D01*
X-119900D01*
X-120800Y1391300D01*
X-121500Y1390633D01*
X-122000Y1389833D01*
X-122400Y1388500D01*
X-122500Y1387300D01*
X-122300Y1386100D01*
X-122000Y1385300D01*
X-121400Y1384500D01*
X-120700Y1383967D01*
X-120000Y1383700D01*
X-119300D01*
X-118600Y1383967D01*
X-118000Y1384367D01*
X-117500Y1384900D01*
G01X-113200Y1391700D02*
X-110800D01*
G01X-112000D02*
Y1383700D01*
G01X-113200D02*
X-110800D01*
G01X-105900D02*
Y1391700D01*
X-102100D01*
G01X-103500Y1387833D02*
X-105900D01*
G01X-97200Y1391700D02*
X-94800D01*
G01X-96000D02*
Y1383700D01*
G01X-97200D02*
X-94800D01*
G01X-85800Y1391033D02*
X-86400Y1391433D01*
X-87100Y1391700D01*
X-87900D01*
X-88800Y1391300D01*
X-89500Y1390633D01*
X-90000Y1389833D01*
X-90400Y1388500D01*
X-90500Y1387300D01*
X-90300Y1386100D01*
X-90000Y1385300D01*
X-89400Y1384500D01*
X-88700Y1383967D01*
X-88000Y1383700D01*
X-87300D01*
X-86600Y1383967D01*
X-86000Y1384367D01*
X-85500Y1384900D01*
G01X-82500Y1383700D02*
X-80000Y1391700D01*
X-77500Y1383700D01*
G01X-78400Y1386500D02*
X-81600D01*
G01X-72000Y1391700D02*
Y1383700D01*
G01X-74300Y1391700D02*
X-69700D01*
G01X-65200D02*
X-62800D01*
G01X-64000D02*
Y1383700D01*
G01X-65200D02*
X-62800D01*
G01X-56000D02*
X-56800Y1383833D01*
X-57500Y1384367D01*
X-58100Y1385167D01*
X-58500Y1386100D01*
X-58700Y1387167D01*
Y1388233D01*
X-58500Y1389300D01*
X-58100Y1390233D01*
X-57500Y1391033D01*
X-56800Y1391567D01*
X-56000Y1391700D01*
X-55200Y1391567D01*
X-54500Y1391033D01*
X-53900Y1390233D01*
X-53500Y1389300D01*
X-53300Y1388233D01*
Y1387167D01*
X-53500Y1386100D01*
X-53900Y1385167D01*
X-54500Y1384367D01*
X-55200Y1383833D01*
X-56000Y1383700D01*
G01X-50300D02*
Y1391700D01*
X-45700Y1383700D01*
Y1391700D01*
G01X-29000Y1381033D02*
X-34000Y1389033D01*
Y1390367D01*
X-33000Y1391700D01*
X-32000D01*
X-31000Y1390367D01*
Y1389033D01*
X-32000Y1387700D01*
X-34000Y1386367D01*
X-35000Y1385033D01*
Y1382367D01*
X-34000Y1381033D01*
X-31000D01*
X-29000Y1383700D01*
G01X-16000D02*
X-16800Y1383833D01*
X-17500Y1384367D01*
X-18100Y1385167D01*
X-18500Y1386100D01*
X-18700Y1387167D01*
Y1388233D01*
X-18500Y1389300D01*
X-18100Y1390233D01*
X-17500Y1391033D01*
X-16800Y1391567D01*
X-16000Y1391700D01*
X-15200Y1391567D01*
X-14500Y1391033D01*
X-13900Y1390233D01*
X-13500Y1389300D01*
X-13300Y1388233D01*
Y1387167D01*
X-13500Y1386100D01*
X-13900Y1385167D01*
X-14500Y1384367D01*
X-15200Y1383833D01*
X-16000Y1383700D01*
G01X-15200Y1385833D02*
X-14000Y1383700D01*
G01X-5800Y1391033D02*
X-6400Y1391433D01*
X-7100Y1391700D01*
X-7900D01*
X-8800Y1391300D01*
X-9500Y1390633D01*
X-10000Y1389833D01*
X-10400Y1388500D01*
X-10500Y1387300D01*
X-10300Y1386100D01*
X-10000Y1385300D01*
X-9400Y1384500D01*
X-8700Y1383967D01*
X-8000Y1383700D01*
X-7300D01*
X-6600Y1383967D01*
X-6000Y1384367D01*
X-5500Y1384900D01*
G01X0Y1391700D02*
Y1383700D01*
G01X-2300Y1391700D02*
X2300D01*
G01X18000Y1383700D02*
X14000D01*
Y1391700D01*
X18000D01*
G01X16400Y1387833D02*
X14000D01*
G01X24000Y1383700D02*
X23200Y1383833D01*
X22500Y1384367D01*
X21900Y1385167D01*
X21500Y1386100D01*
X21300Y1387167D01*
Y1388233D01*
X21500Y1389300D01*
X21900Y1390233D01*
X22500Y1391033D01*
X23200Y1391567D01*
X24000Y1391700D01*
X24800Y1391567D01*
X25500Y1391033D01*
X26100Y1390233D01*
X26500Y1389300D01*
X26700Y1388233D01*
Y1387167D01*
X26500Y1386100D01*
X26100Y1385167D01*
X25500Y1384367D01*
X24800Y1383833D01*
X24000Y1383700D01*
G01X24800Y1385833D02*
X26000Y1383700D01*
G01X38100D02*
Y1391700D01*
X41900D01*
G01X40500Y1387833D02*
X38100D01*
G01X45500Y1383700D02*
X48000Y1391700D01*
X50500Y1383700D01*
G01X49600Y1386500D02*
X46400D01*
G01X56000Y1383700D02*
X55200Y1383833D01*
X54500Y1384367D01*
X53900Y1385167D01*
X53500Y1386100D01*
X53300Y1387167D01*
Y1388233D01*
X53500Y1389300D01*
X53900Y1390233D01*
X54500Y1391033D01*
X55200Y1391567D01*
X56000Y1391700D01*
X56800Y1391567D01*
X57500Y1391033D01*
X58100Y1390233D01*
X58500Y1389300D01*
X58700Y1388233D01*
Y1387167D01*
X58500Y1386100D01*
X58100Y1385167D01*
X57500Y1384367D01*
X56800Y1383833D01*
X56000Y1383700D01*
G01X56800Y1385833D02*
X58000Y1383700D01*
G01X64000Y1383433D02*
X63800Y1383567D01*
Y1383833D01*
X64000Y1383967D01*
X64200Y1383833D01*
Y1383567D01*
X64000Y1383433D01*
G01X-360000Y1398700D02*
Y1406700D01*
X-361200Y1405100D01*
G01Y1398700D02*
X-358800D01*
G01X-352000Y1398433D02*
X-352200Y1398567D01*
Y1398833D01*
X-352000Y1398967D01*
X-351800Y1398833D01*
Y1398567D01*
X-352000Y1398433D01*
G01X-346000Y1398700D02*
Y1406700D01*
X-343600D01*
X-342800Y1406300D01*
X-342200Y1405367D01*
X-342000Y1404300D01*
X-342200Y1403233D01*
X-342700Y1402433D01*
X-343600Y1402033D01*
X-346000D01*
G01X-333800Y1406033D02*
X-334400Y1406433D01*
X-335100Y1406700D01*
X-335900D01*
X-336800Y1406300D01*
X-337500Y1405633D01*
X-338000Y1404833D01*
X-338400Y1403500D01*
X-338500Y1402300D01*
X-338300Y1401100D01*
X-338000Y1400300D01*
X-337400Y1399500D01*
X-336700Y1398967D01*
X-336000Y1398700D01*
X-335300D01*
X-334600Y1398967D01*
X-334000Y1399367D01*
X-333500Y1399900D01*
G01X-327200Y1402967D02*
X-326800Y1403367D01*
X-326500Y1404033D01*
X-326300Y1404967D01*
X-326500Y1405767D01*
X-326900Y1406300D01*
X-327600Y1406700D01*
X-330300D01*
Y1398700D01*
X-327000D01*
X-326300Y1399233D01*
X-325900Y1400033D01*
X-325700Y1400967D01*
X-325900Y1401900D01*
X-326500Y1402700D01*
X-327200Y1402967D01*
X-330300D01*
G01X-314100Y1399766D02*
X-313300Y1399100D01*
X-312400Y1398700D01*
X-311600D01*
X-310800Y1399100D01*
X-310200Y1399766D01*
X-309900Y1400700D01*
X-310100Y1401633D01*
X-310600Y1402433D01*
X-311500Y1402967D01*
X-312700Y1403233D01*
X-313400Y1403767D01*
X-313700Y1404700D01*
X-313500Y1405633D01*
X-313000Y1406300D01*
X-312300Y1406700D01*
X-311600D01*
X-310900Y1406433D01*
X-310300Y1405767D01*
G01X-305200Y1406700D02*
X-302800D01*
G01X-304000D02*
Y1398700D01*
G01X-305200D02*
X-302800D01*
G01X-297900Y1406700D02*
X-294100D01*
X-297900Y1398700D01*
X-294100D01*
G01X-286000D02*
X-290000D01*
Y1406700D01*
X-286000D01*
G01X-287600Y1402833D02*
X-290000D01*
G01X-256000Y1398433D02*
X-256200Y1398567D01*
Y1398833D01*
X-256000Y1398967D01*
X-255800Y1398833D01*
Y1398567D01*
X-256000Y1398433D01*
G01Y1402033D02*
X-256200Y1402167D01*
Y1402433D01*
X-256000Y1402567D01*
X-255800Y1402433D01*
Y1402167D01*
X-256000Y1402033D01*
G01X-241900Y1398700D02*
Y1406700D01*
X-238100D01*
G01X-239500Y1402833D02*
X-241900D01*
G01X-232000Y1398700D02*
X-232800Y1398833D01*
X-233500Y1399367D01*
X-234100Y1400167D01*
X-234500Y1401100D01*
X-234700Y1402167D01*
Y1403233D01*
X-234500Y1404300D01*
X-234100Y1405233D01*
X-233500Y1406033D01*
X-232800Y1406567D01*
X-232000Y1406700D01*
X-231200Y1406567D01*
X-230500Y1406033D01*
X-229900Y1405233D01*
X-229500Y1404300D01*
X-229300Y1403233D01*
Y1402167D01*
X-229500Y1401100D01*
X-229900Y1400167D01*
X-230500Y1399367D01*
X-231200Y1398833D01*
X-232000Y1398700D01*
G01X-226000Y1406700D02*
Y1398700D01*
X-222000D01*
G01X-218000Y1406700D02*
Y1398700D01*
X-214000D01*
G01X-208000D02*
X-208800Y1398833D01*
X-209500Y1399367D01*
X-210100Y1400167D01*
X-210500Y1401100D01*
X-210700Y1402167D01*
Y1403233D01*
X-210500Y1404300D01*
X-210100Y1405233D01*
X-209500Y1406033D01*
X-208800Y1406567D01*
X-208000Y1406700D01*
X-207200Y1406567D01*
X-206500Y1406033D01*
X-205900Y1405233D01*
X-205500Y1404300D01*
X-205300Y1403233D01*
Y1402167D01*
X-205500Y1401100D01*
X-205900Y1400167D01*
X-206500Y1399367D01*
X-207200Y1398833D01*
X-208000Y1398700D01*
G01X-203000Y1406700D02*
X-201600Y1398700D01*
X-200000Y1406700D01*
X-198400Y1398700D01*
X-197000Y1406700D01*
G01X-183400Y1402700D02*
X-181400D01*
Y1400300D01*
X-182000Y1399500D01*
X-182700Y1398967D01*
X-183700Y1398700D01*
X-184700Y1398967D01*
X-185400Y1399500D01*
X-186000Y1400300D01*
X-186400Y1401233D01*
X-186600Y1402300D01*
Y1403233D01*
X-186400Y1404033D01*
X-186000Y1404967D01*
X-185400Y1405767D01*
X-184800Y1406300D01*
X-184000Y1406700D01*
X-183300D01*
X-182500Y1406433D01*
X-181900Y1405900D01*
G01X-174000Y1398700D02*
X-178000D01*
Y1406700D01*
X-174000D01*
G01X-175600Y1402833D02*
X-178000D01*
G01X-170000Y1398700D02*
Y1406700D01*
X-167500D01*
X-166700Y1406300D01*
X-166200Y1405767D01*
X-166000Y1404700D01*
X-166200Y1403633D01*
X-166800Y1402967D01*
X-167500Y1402567D01*
X-170000D01*
G01X-167500D02*
X-166000Y1398700D01*
G01X-159200Y1402967D02*
X-158800Y1403367D01*
X-158500Y1404033D01*
X-158300Y1404967D01*
X-158500Y1405767D01*
X-158900Y1406300D01*
X-159600Y1406700D01*
X-162300D01*
Y1398700D01*
X-159000D01*
X-158300Y1399233D01*
X-157900Y1400033D01*
X-157700Y1400967D01*
X-157900Y1401900D01*
X-158500Y1402700D01*
X-159200Y1402967D01*
X-162300D01*
G01X-150000Y1398700D02*
X-154000D01*
Y1406700D01*
X-150000D01*
G01X-151600Y1402833D02*
X-154000D01*
G01X-146000Y1398700D02*
Y1406700D01*
X-143500D01*
X-142700Y1406300D01*
X-142200Y1405767D01*
X-142000Y1404700D01*
X-142200Y1403633D01*
X-142800Y1402967D01*
X-143500Y1402567D01*
X-146000D01*
G01X-143500D02*
X-142000Y1398700D01*
G01X-129900D02*
Y1406700D01*
X-126100D01*
G01X-127500Y1402833D02*
X-129900D01*
G01X-121200Y1406700D02*
X-118800D01*
G01X-120000D02*
Y1398700D01*
G01X-121200D02*
X-118800D01*
G01X-114000Y1406700D02*
Y1398700D01*
X-110000D01*
G01X-102000D02*
X-106000D01*
Y1406700D01*
X-102000D01*
G01X-103600Y1402833D02*
X-106000D01*
G01X-96700Y1396300D02*
X-95300Y1398167D01*
Y1400033D01*
X-96700D01*
Y1398167D01*
X-95300D01*
G01Y1401367D02*
Y1403233D01*
X-96700D01*
Y1401367D01*
X-95300D01*
G01X-83000Y1406700D02*
X-81600Y1398700D01*
X-80000Y1406700D01*
X-78400Y1398700D01*
X-77000Y1406700D01*
G01X-73200D02*
X-70800D01*
G01X-72000D02*
Y1398700D01*
G01X-73200D02*
X-70800D01*
G01X-64000Y1406700D02*
Y1398700D01*
G01X-66300Y1406700D02*
X-61700D01*
G01X-58100Y1398700D02*
Y1406700D01*
G01X-53900D02*
Y1398700D01*
G01Y1402700D02*
X-58100D01*
G01X-40000Y1406700D02*
Y1398700D01*
G01X-42300Y1406700D02*
X-37700D01*
G01X-32000Y1398700D02*
X-32800Y1398833D01*
X-33500Y1399367D01*
X-34100Y1400167D01*
X-34500Y1401100D01*
X-34700Y1402167D01*
Y1403233D01*
X-34500Y1404300D01*
X-34100Y1405233D01*
X-33500Y1406033D01*
X-32800Y1406567D01*
X-32000Y1406700D01*
X-31200Y1406567D01*
X-30500Y1406033D01*
X-29900Y1405233D01*
X-29500Y1404300D01*
X-29300Y1403233D01*
Y1402167D01*
X-29500Y1401100D01*
X-29900Y1400167D01*
X-30500Y1399367D01*
X-31200Y1398833D01*
X-32000Y1398700D01*
G01X-26000Y1406700D02*
Y1398700D01*
X-22000D01*
G01X-14000D02*
X-18000D01*
Y1406700D01*
X-14000D01*
G01X-15600Y1402833D02*
X-18000D01*
G01X-10000Y1398700D02*
Y1406700D01*
X-7500D01*
X-6700Y1406300D01*
X-6200Y1405767D01*
X-6000Y1404700D01*
X-6200Y1403633D01*
X-6800Y1402967D01*
X-7500Y1402567D01*
X-10000D01*
G01X-7500D02*
X-6000Y1398700D01*
G01X-2500D02*
X0Y1406700D01*
X2500Y1398700D01*
G01X1600Y1401500D02*
X-1600D01*
G01X5700Y1398700D02*
Y1406700D01*
X10300Y1398700D01*
Y1406700D01*
G01X18200Y1406033D02*
X17600Y1406433D01*
X16900Y1406700D01*
X16100D01*
X15200Y1406300D01*
X14500Y1405633D01*
X14000Y1404833D01*
X13600Y1403500D01*
X13500Y1402300D01*
X13700Y1401100D01*
X14000Y1400300D01*
X14600Y1399500D01*
X15300Y1398967D01*
X16000Y1398700D01*
X16700D01*
X17400Y1398967D01*
X18000Y1399367D01*
X18500Y1399900D01*
G01X26000Y1398700D02*
X22000D01*
Y1406700D01*
X26000D01*
G01X24400Y1402833D02*
X22000D01*
G01X38700Y1400167D02*
X41300D01*
G01Y1402567D02*
X38700D01*
G01X46900Y1401367D02*
X49300D01*
G01X48000Y1403100D02*
Y1399633D01*
G01X54200Y1398433D02*
X57800Y1406700D01*
G01X62700Y1401367D02*
X65300D01*
G01X72000Y1406700D02*
X71200Y1406433D01*
X70600Y1405767D01*
X70200Y1404967D01*
X69900Y1403900D01*
X69800Y1402700D01*
X69900Y1401500D01*
X70200Y1400433D01*
X70600Y1399633D01*
X71200Y1398967D01*
X72000Y1398700D01*
X72800Y1398967D01*
X73400Y1399633D01*
X73800Y1400433D01*
X74100Y1401500D01*
X74200Y1402700D01*
X74100Y1403900D01*
X73800Y1404967D01*
X73400Y1405767D01*
X72800Y1406433D01*
X72000Y1406700D01*
G01X80000Y1398433D02*
X79800Y1398567D01*
Y1398833D01*
X80000Y1398967D01*
X80200Y1398833D01*
Y1398567D01*
X80000Y1398433D01*
G01X88000Y1398700D02*
Y1406700D01*
X86800Y1405100D01*
G01Y1398700D02*
X89200D01*
G01X93800Y1399900D02*
X94400Y1399233D01*
X95100Y1398833D01*
X96000Y1398700D01*
X96900Y1398967D01*
X97600Y1399500D01*
X98100Y1400433D01*
X98200Y1401500D01*
X98000Y1402567D01*
X97500Y1403233D01*
X96800Y1403767D01*
X96100Y1403900D01*
X95400Y1403767D01*
X94500Y1403233D01*
X94800Y1406700D01*
X97500D01*
G01X101400Y1398700D02*
Y1406700D01*
X104000Y1400033D01*
X106600Y1406700D01*
Y1398700D01*
G01X109400D02*
Y1406700D01*
X112000Y1400033D01*
X114600Y1406700D01*
Y1398700D01*
G01X-362300Y1413700D02*
Y1421700D01*
X-357700Y1413700D01*
Y1421700D01*
G01X-352000Y1413700D02*
X-352800Y1413833D01*
X-353500Y1414367D01*
X-354100Y1415167D01*
X-354500Y1416100D01*
X-354700Y1417167D01*
Y1418233D01*
X-354500Y1419300D01*
X-354100Y1420233D01*
X-353500Y1421033D01*
X-352800Y1421567D01*
X-352000Y1421700D01*
X-351200Y1421567D01*
X-350500Y1421033D01*
X-349900Y1420233D01*
X-349500Y1419300D01*
X-349300Y1418233D01*
Y1417167D01*
X-349500Y1416100D01*
X-349900Y1415167D01*
X-350500Y1414367D01*
X-351200Y1413833D01*
X-352000Y1413700D01*
G01X-344000Y1421700D02*
Y1413700D01*
G01X-346300Y1421700D02*
X-341700D01*
G01X-334000Y1413700D02*
X-338000D01*
Y1421700D01*
X-334000D01*
G01X-335600Y1417833D02*
X-338000D01*
G01X-330100Y1414766D02*
X-329300Y1414100D01*
X-328400Y1413700D01*
X-327600D01*
X-326800Y1414100D01*
X-326200Y1414766D01*
X-325900Y1415700D01*
X-326100Y1416633D01*
X-326600Y1417433D01*
X-327500Y1417967D01*
X-328700Y1418233D01*
X-329400Y1418767D01*
X-329700Y1419700D01*
X-329500Y1420633D01*
X-329000Y1421300D01*
X-328300Y1421700D01*
X-327600D01*
X-326900Y1421433D01*
X-326300Y1420767D01*
G01X-320000Y1413433D02*
X-320200Y1413567D01*
Y1413833D01*
X-320000Y1413967D01*
X-319800Y1413833D01*
Y1413567D01*
X-320000Y1413433D01*
G01Y1417033D02*
X-320200Y1417167D01*
Y1417433D01*
X-320000Y1417567D01*
X-319800Y1417433D01*
Y1417167D01*
X-320000Y1417033D01*
G01X-304500Y1411033D02*
X-305500Y1412367D01*
X-306000Y1413700D01*
Y1419033D01*
X-305500Y1420367D01*
X-304500Y1421700D01*
G01X-298200D02*
Y1415967D01*
X-297800Y1414766D01*
X-297000Y1413967D01*
X-296000Y1413700D01*
X-295000Y1413967D01*
X-294200Y1414766D01*
X-293800Y1415967D01*
Y1421700D01*
G01X-290300Y1413700D02*
Y1421700D01*
X-285700Y1413700D01*
Y1421700D01*
G01X-282000D02*
Y1413700D01*
X-278000D01*
G01X-270000D02*
X-274000D01*
Y1421700D01*
X-270000D01*
G01X-271600Y1417833D02*
X-274000D01*
G01X-266100Y1414766D02*
X-265300Y1414100D01*
X-264400Y1413700D01*
X-263600D01*
X-262800Y1414100D01*
X-262200Y1414766D01*
X-261900Y1415700D01*
X-262100Y1416633D01*
X-262600Y1417433D01*
X-263500Y1417967D01*
X-264700Y1418233D01*
X-265400Y1418767D01*
X-265700Y1419700D01*
X-265500Y1420633D01*
X-265000Y1421300D01*
X-264300Y1421700D01*
X-263600D01*
X-262900Y1421433D01*
X-262300Y1420767D01*
G01X-258100Y1414766D02*
X-257300Y1414100D01*
X-256400Y1413700D01*
X-255600D01*
X-254800Y1414100D01*
X-254200Y1414766D01*
X-253900Y1415700D01*
X-254100Y1416633D01*
X-254600Y1417433D01*
X-255500Y1417967D01*
X-256700Y1418233D01*
X-257400Y1418767D01*
X-257700Y1419700D01*
X-257500Y1420633D01*
X-257000Y1421300D01*
X-256300Y1421700D01*
X-255600D01*
X-254900Y1421433D01*
X-254300Y1420767D01*
G01X-240000Y1413700D02*
X-240800Y1413833D01*
X-241500Y1414367D01*
X-242100Y1415167D01*
X-242500Y1416100D01*
X-242700Y1417167D01*
Y1418233D01*
X-242500Y1419300D01*
X-242100Y1420233D01*
X-241500Y1421033D01*
X-240800Y1421567D01*
X-240000Y1421700D01*
X-239200Y1421567D01*
X-238500Y1421033D01*
X-237900Y1420233D01*
X-237500Y1419300D01*
X-237300Y1418233D01*
Y1417167D01*
X-237500Y1416100D01*
X-237900Y1415167D01*
X-238500Y1414367D01*
X-239200Y1413833D01*
X-240000Y1413700D01*
G01X-232000Y1421700D02*
Y1413700D01*
G01X-234300Y1421700D02*
X-229700D01*
G01X-226100Y1413700D02*
Y1421700D01*
G01X-221900D02*
Y1413700D01*
G01Y1417700D02*
X-226100D01*
G01X-214000Y1413700D02*
X-218000D01*
Y1421700D01*
X-214000D01*
G01X-215600Y1417833D02*
X-218000D01*
G01X-210000Y1413700D02*
Y1421700D01*
X-207500D01*
X-206700Y1421300D01*
X-206200Y1420767D01*
X-206000Y1419700D01*
X-206200Y1418633D01*
X-206800Y1417967D01*
X-207500Y1417567D01*
X-210000D01*
G01X-207500D02*
X-206000Y1413700D01*
G01X-203000Y1421700D02*
X-201600Y1413700D01*
X-200000Y1421700D01*
X-198400Y1413700D01*
X-197000Y1421700D01*
G01X-193200D02*
X-190800D01*
G01X-192000D02*
Y1413700D01*
G01X-193200D02*
X-190800D01*
G01X-186100Y1414766D02*
X-185300Y1414100D01*
X-184400Y1413700D01*
X-183600D01*
X-182800Y1414100D01*
X-182200Y1414766D01*
X-181900Y1415700D01*
X-182100Y1416633D01*
X-182600Y1417433D01*
X-183500Y1417967D01*
X-184700Y1418233D01*
X-185400Y1418767D01*
X-185700Y1419700D01*
X-185500Y1420633D01*
X-185000Y1421300D01*
X-184300Y1421700D01*
X-183600D01*
X-182900Y1421433D01*
X-182300Y1420767D01*
G01X-174000Y1413700D02*
X-178000D01*
Y1421700D01*
X-174000D01*
G01X-175600Y1417833D02*
X-178000D01*
G01X-162100Y1414766D02*
X-161300Y1414100D01*
X-160400Y1413700D01*
X-159600D01*
X-158800Y1414100D01*
X-158200Y1414766D01*
X-157900Y1415700D01*
X-158100Y1416633D01*
X-158600Y1417433D01*
X-159500Y1417967D01*
X-160700Y1418233D01*
X-161400Y1418767D01*
X-161700Y1419700D01*
X-161500Y1420633D01*
X-161000Y1421300D01*
X-160300Y1421700D01*
X-159600D01*
X-158900Y1421433D01*
X-158300Y1420767D01*
G01X-154000Y1413700D02*
Y1421700D01*
X-151600D01*
X-150800Y1421300D01*
X-150200Y1420367D01*
X-150000Y1419300D01*
X-150200Y1418233D01*
X-150700Y1417433D01*
X-151600Y1417033D01*
X-154000D01*
G01X-142000Y1413700D02*
X-146000D01*
Y1421700D01*
X-142000D01*
G01X-143600Y1417833D02*
X-146000D01*
G01X-133800Y1421033D02*
X-134400Y1421433D01*
X-135100Y1421700D01*
X-135900D01*
X-136800Y1421300D01*
X-137500Y1420633D01*
X-138000Y1419833D01*
X-138400Y1418500D01*
X-138500Y1417300D01*
X-138300Y1416100D01*
X-138000Y1415300D01*
X-137400Y1414500D01*
X-136700Y1413967D01*
X-136000Y1413700D01*
X-135300D01*
X-134600Y1413967D01*
X-134000Y1414367D01*
X-133500Y1414900D01*
G01X-129200Y1421700D02*
X-126800D01*
G01X-128000D02*
Y1413700D01*
G01X-129200D02*
X-126800D01*
G01X-121900D02*
Y1421700D01*
X-118100D01*
G01X-119500Y1417833D02*
X-121900D01*
G01X-113200Y1421700D02*
X-110800D01*
G01X-112000D02*
Y1413700D01*
G01X-113200D02*
X-110800D01*
G01X-102000D02*
X-106000D01*
Y1421700D01*
X-102000D01*
G01X-103600Y1417833D02*
X-106000D01*
G01X-98200Y1413700D02*
Y1421700D01*
X-96200D01*
X-95400Y1421300D01*
X-94800Y1420767D01*
X-94300Y1419967D01*
X-93900Y1419033D01*
X-93800Y1417700D01*
X-93900Y1416367D01*
X-94300Y1415433D01*
X-94800Y1414633D01*
X-95400Y1414100D01*
X-96200Y1413700D01*
X-98200D01*
G01X-81200Y1421700D02*
X-78800D01*
G01X-80000D02*
Y1413700D01*
G01X-81200D02*
X-78800D01*
G01X-74300D02*
Y1421700D01*
X-69700Y1413700D01*
Y1421700D01*
G01X-58000Y1413700D02*
Y1421700D01*
X-55600D01*
X-54800Y1421300D01*
X-54200Y1420367D01*
X-54000Y1419300D01*
X-54200Y1418233D01*
X-54700Y1417433D01*
X-55600Y1417033D01*
X-58000D01*
G01X-45800Y1421033D02*
X-46400Y1421433D01*
X-47100Y1421700D01*
X-47900D01*
X-48800Y1421300D01*
X-49500Y1420633D01*
X-50000Y1419833D01*
X-50400Y1418500D01*
X-50500Y1417300D01*
X-50300Y1416100D01*
X-50000Y1415300D01*
X-49400Y1414500D01*
X-48700Y1413967D01*
X-48000Y1413700D01*
X-47300D01*
X-46600Y1413967D01*
X-46000Y1414367D01*
X-45500Y1414900D01*
G01X-39200Y1417967D02*
X-38800Y1418367D01*
X-38500Y1419033D01*
X-38300Y1419967D01*
X-38500Y1420767D01*
X-38900Y1421300D01*
X-39600Y1421700D01*
X-42300D01*
Y1413700D01*
X-39000D01*
X-38300Y1414233D01*
X-37900Y1415033D01*
X-37700Y1415967D01*
X-37900Y1416900D01*
X-38500Y1417700D01*
X-39200Y1417967D01*
X-42300D01*
G01X-26100Y1414766D02*
X-25300Y1414100D01*
X-24400Y1413700D01*
X-23600D01*
X-22800Y1414100D01*
X-22200Y1414766D01*
X-21900Y1415700D01*
X-22100Y1416633D01*
X-22600Y1417433D01*
X-23500Y1417967D01*
X-24700Y1418233D01*
X-25400Y1418767D01*
X-25700Y1419700D01*
X-25500Y1420633D01*
X-25000Y1421300D01*
X-24300Y1421700D01*
X-23600D01*
X-22900Y1421433D01*
X-22300Y1420767D01*
G01X-18000Y1413700D02*
Y1421700D01*
X-15600D01*
X-14800Y1421300D01*
X-14200Y1420367D01*
X-14000Y1419300D01*
X-14200Y1418233D01*
X-14700Y1417433D01*
X-15600Y1417033D01*
X-18000D01*
G01X-6000Y1413700D02*
X-10000D01*
Y1421700D01*
X-6000D01*
G01X-7600Y1417833D02*
X-10000D01*
G01X2200Y1421033D02*
X1600Y1421433D01*
X900Y1421700D01*
X100D01*
X-800Y1421300D01*
X-1500Y1420633D01*
X-2000Y1419833D01*
X-2400Y1418500D01*
X-2500Y1417300D01*
X-2300Y1416100D01*
X-2000Y1415300D01*
X-1400Y1414500D01*
X-700Y1413967D01*
X0Y1413700D01*
X700D01*
X1400Y1413967D01*
X2000Y1414367D01*
X2500Y1414900D01*
G01X8500Y1411033D02*
X9500Y1412367D01*
X10000Y1413700D01*
Y1419033D01*
X9500Y1420367D01*
X8500Y1421700D01*
G01X-360000Y1428700D02*
X-360800Y1428833D01*
X-361500Y1429367D01*
X-362100Y1430167D01*
X-362500Y1431100D01*
X-362700Y1432167D01*
Y1433233D01*
X-362500Y1434300D01*
X-362100Y1435233D01*
X-361500Y1436033D01*
X-360800Y1436567D01*
X-360000Y1436700D01*
X-359200Y1436567D01*
X-358500Y1436033D01*
X-357900Y1435233D01*
X-357500Y1434300D01*
X-357300Y1433233D01*
Y1432167D01*
X-357500Y1431100D01*
X-357900Y1430167D01*
X-358500Y1429367D01*
X-359200Y1428833D01*
X-360000Y1428700D01*
G01X-359200Y1430833D02*
X-358000Y1428700D01*
G01X-353700Y1434033D02*
Y1430300D01*
X-353300Y1429367D01*
X-352700Y1428833D01*
X-352000Y1428700D01*
X-351300Y1428833D01*
X-350700Y1429367D01*
X-350300Y1430300D01*
G01Y1428700D02*
Y1434033D01*
G01X-342200Y1428700D02*
Y1434033D01*
G01Y1433100D02*
X-342600Y1433633D01*
X-343200Y1433900D01*
X-343900Y1434033D01*
X-344600Y1433767D01*
X-345200Y1433233D01*
X-345600Y1432433D01*
X-345800Y1431367D01*
X-345600Y1430300D01*
X-345200Y1429500D01*
X-344600Y1428967D01*
X-343900Y1428700D01*
X-343200Y1428833D01*
X-342600Y1429233D01*
X-342200Y1429766D01*
G01X-337700Y1428700D02*
Y1434033D01*
G01Y1432700D02*
X-337300Y1433367D01*
X-336700Y1433900D01*
X-335900Y1434033D01*
X-335200Y1433900D01*
X-334600Y1433367D01*
X-334300Y1432433D01*
Y1428700D01*
G01X-328000Y1436700D02*
Y1428700D01*
G01X-329400Y1434033D02*
X-326600D01*
G01X-318200Y1428700D02*
Y1434033D01*
G01Y1433100D02*
X-318600Y1433633D01*
X-319200Y1433900D01*
X-319900Y1434033D01*
X-320600Y1433767D01*
X-321200Y1433233D01*
X-321600Y1432433D01*
X-321800Y1431367D01*
X-321600Y1430300D01*
X-321200Y1429500D01*
X-320600Y1428967D01*
X-319900Y1428700D01*
X-319200Y1428833D01*
X-318600Y1429233D01*
X-318200Y1429766D01*
G01X-305900Y1428700D02*
Y1436700D01*
X-302100D01*
G01X-303500Y1432833D02*
X-305900D01*
G01X-298500Y1428700D02*
X-296000Y1436700D01*
X-293500Y1428700D01*
G01X-294400Y1431500D02*
X-297600D01*
G01X-287200Y1432967D02*
X-286800Y1433367D01*
X-286500Y1434033D01*
X-286300Y1434967D01*
X-286500Y1435767D01*
X-286900Y1436300D01*
X-287600Y1436700D01*
X-290300D01*
Y1428700D01*
X-287000D01*
X-286300Y1429233D01*
X-285900Y1430033D01*
X-285700Y1430967D01*
X-285900Y1431900D01*
X-286500Y1432700D01*
X-287200Y1432967D01*
X-290300D01*
G01X-274300Y1428700D02*
Y1436700D01*
X-269700Y1428700D01*
Y1436700D01*
G01X-264000Y1428700D02*
X-264800Y1428833D01*
X-265500Y1429367D01*
X-266100Y1430167D01*
X-266500Y1431100D01*
X-266700Y1432167D01*
Y1433233D01*
X-266500Y1434300D01*
X-266100Y1435233D01*
X-265500Y1436033D01*
X-264800Y1436567D01*
X-264000Y1436700D01*
X-263200Y1436567D01*
X-262500Y1436033D01*
X-261900Y1435233D01*
X-261500Y1434300D01*
X-261300Y1433233D01*
Y1432167D01*
X-261500Y1431100D01*
X-261900Y1430167D01*
X-262500Y1429367D01*
X-263200Y1428833D01*
X-264000Y1428700D01*
G01X-256000Y1436700D02*
Y1428700D01*
G01X-258300Y1436700D02*
X-253700D01*
G01X-246000Y1428700D02*
X-250000D01*
Y1436700D01*
X-246000D01*
G01X-247600Y1432833D02*
X-250000D01*
G01X-234000Y1428700D02*
Y1436700D01*
X-231500D01*
X-230700Y1436300D01*
X-230200Y1435767D01*
X-230000Y1434700D01*
X-230200Y1433633D01*
X-230800Y1432967D01*
X-231500Y1432567D01*
X-234000D01*
G01X-231500D02*
X-230000Y1428700D01*
G01X-222000D02*
X-226000D01*
Y1436700D01*
X-222000D01*
G01X-223600Y1432833D02*
X-226000D01*
G01X-218500Y1436700D02*
X-216000Y1428700D01*
X-213500Y1436700D01*
G01X-208000Y1428433D02*
X-208200Y1428567D01*
Y1428833D01*
X-208000Y1428967D01*
X-207800Y1428833D01*
Y1428567D01*
X-208000Y1428433D01*
G01Y1432033D02*
X-208200Y1432167D01*
Y1432433D01*
X-208000Y1432567D01*
X-207800Y1432433D01*
Y1432167D01*
X-208000Y1432033D01*
G01X-201900Y1428700D02*
Y1436700D01*
X-198100D01*
G01X-199500Y1432833D02*
X-201900D01*
G01X-349370Y788152D02*
Y756656D01*
G01D02*
Y807837D01*
G01Y859018D02*
Y807837D01*
G01Y827522D02*
Y859018D01*
G01X-344400Y1132700D02*
X-342400D01*
Y1130300D01*
X-343000Y1129500D01*
X-343700Y1128967D01*
X-344700Y1128700D01*
X-345700Y1128967D01*
X-346400Y1129500D01*
X-347000Y1130300D01*
X-347400Y1131233D01*
X-347600Y1132300D01*
Y1133233D01*
X-347400Y1134033D01*
X-347000Y1134967D01*
X-346400Y1135767D01*
X-345800Y1136300D01*
X-345000Y1136700D01*
X-344300D01*
X-343500Y1136433D01*
X-342900Y1135900D01*
G01X-339000Y1128700D02*
Y1136700D01*
X-336500D01*
X-335700Y1136300D01*
X-335200Y1135767D01*
X-335000Y1134700D01*
X-335200Y1133633D01*
X-335800Y1132967D01*
X-336500Y1132567D01*
X-339000D01*
G01X-336500D02*
X-335000Y1128700D01*
G01X-329000D02*
X-329800Y1128833D01*
X-330500Y1129367D01*
X-331100Y1130167D01*
X-331500Y1131100D01*
X-331700Y1132167D01*
Y1133233D01*
X-331500Y1134300D01*
X-331100Y1135233D01*
X-330500Y1136033D01*
X-329800Y1136567D01*
X-329000Y1136700D01*
X-328200Y1136567D01*
X-327500Y1136033D01*
X-326900Y1135233D01*
X-326500Y1134300D01*
X-326300Y1133233D01*
Y1132167D01*
X-326500Y1131100D01*
X-326900Y1130167D01*
X-327500Y1129367D01*
X-328200Y1128833D01*
X-329000Y1128700D01*
G01X-323200Y1136700D02*
Y1130967D01*
X-322800Y1129766D01*
X-322000Y1128967D01*
X-321000Y1128700D01*
X-320000Y1128967D01*
X-319200Y1129766D01*
X-318800Y1130967D01*
Y1136700D01*
G01X-315000Y1128700D02*
Y1136700D01*
X-312600D01*
X-311800Y1136300D01*
X-311200Y1135367D01*
X-311000Y1134300D01*
X-311200Y1133233D01*
X-311700Y1132433D01*
X-312600Y1132033D01*
X-315000D01*
G01X-307100Y1129766D02*
X-306300Y1129100D01*
X-305400Y1128700D01*
X-304600D01*
X-303800Y1129100D01*
X-303200Y1129766D01*
X-302900Y1130700D01*
X-303100Y1131633D01*
X-303600Y1132433D01*
X-304500Y1132967D01*
X-305700Y1133233D01*
X-306400Y1133767D01*
X-306700Y1134700D01*
X-306500Y1135633D01*
X-306000Y1136300D01*
X-305300Y1136700D01*
X-304600D01*
X-303900Y1136433D01*
X-303300Y1135767D01*
G01X-291500Y1128700D02*
X-289000Y1136700D01*
X-286500Y1128700D01*
G01X-287400Y1131500D02*
X-290600D01*
G01X-275500Y1128700D02*
X-273000Y1136700D01*
X-270500Y1128700D01*
G01X-271400Y1131500D02*
X-274600D01*
G01X-267300Y1128700D02*
Y1136700D01*
X-262700Y1128700D01*
Y1136700D01*
G01X-259200Y1128700D02*
Y1136700D01*
X-257200D01*
X-256400Y1136300D01*
X-255800Y1135767D01*
X-255300Y1134967D01*
X-254900Y1134033D01*
X-254800Y1132700D01*
X-254900Y1131367D01*
X-255300Y1130433D01*
X-255800Y1129633D01*
X-256400Y1129100D01*
X-257200Y1128700D01*
X-259200D01*
G01X-240200Y1132967D02*
X-239800Y1133367D01*
X-239500Y1134033D01*
X-239300Y1134967D01*
X-239500Y1135767D01*
X-239900Y1136300D01*
X-240600Y1136700D01*
X-243300D01*
Y1128700D01*
X-240000D01*
X-239300Y1129233D01*
X-238900Y1130033D01*
X-238700Y1130967D01*
X-238900Y1131900D01*
X-239500Y1132700D01*
X-240200Y1132967D01*
X-243300D01*
G01X-233200Y1127233D02*
X-232800Y1128967D01*
G01X-225000Y1136700D02*
Y1128700D01*
G01X-227300Y1136700D02*
X-222700D01*
G01X-219100Y1128700D02*
Y1136700D01*
G01X-214900D02*
Y1128700D01*
G01Y1132700D02*
X-219100D01*
G01X-207000Y1128700D02*
X-211000D01*
Y1136700D01*
X-207000D01*
G01X-208600Y1132833D02*
X-211000D01*
G01X-203300Y1128700D02*
Y1136700D01*
X-198700Y1128700D01*
Y1136700D01*
G01X-184400Y1132700D02*
X-182400D01*
Y1130300D01*
X-183000Y1129500D01*
X-183700Y1128967D01*
X-184700Y1128700D01*
X-185700Y1128967D01*
X-186400Y1129500D01*
X-187000Y1130300D01*
X-187400Y1131233D01*
X-187600Y1132300D01*
Y1133233D01*
X-187400Y1134033D01*
X-187000Y1134967D01*
X-186400Y1135767D01*
X-185800Y1136300D01*
X-185000Y1136700D01*
X-184300D01*
X-183500Y1136433D01*
X-182900Y1135900D01*
G01X-179000Y1128700D02*
Y1136700D01*
X-176500D01*
X-175700Y1136300D01*
X-175200Y1135767D01*
X-175000Y1134700D01*
X-175200Y1133633D01*
X-175800Y1132967D01*
X-176500Y1132567D01*
X-179000D01*
G01X-176500D02*
X-175000Y1128700D01*
G01X-169000D02*
X-169800Y1128833D01*
X-170500Y1129367D01*
X-171100Y1130167D01*
X-171500Y1131100D01*
X-171700Y1132167D01*
Y1133233D01*
X-171500Y1134300D01*
X-171100Y1135233D01*
X-170500Y1136033D01*
X-169800Y1136567D01*
X-169000Y1136700D01*
X-168200Y1136567D01*
X-167500Y1136033D01*
X-166900Y1135233D01*
X-166500Y1134300D01*
X-166300Y1133233D01*
Y1132167D01*
X-166500Y1131100D01*
X-166900Y1130167D01*
X-167500Y1129367D01*
X-168200Y1128833D01*
X-169000Y1128700D01*
G01X-163200Y1136700D02*
Y1130967D01*
X-162800Y1129766D01*
X-162000Y1128967D01*
X-161000Y1128700D01*
X-160000Y1128967D01*
X-159200Y1129766D01*
X-158800Y1130967D01*
Y1136700D01*
G01X-155000Y1128700D02*
Y1136700D01*
X-152600D01*
X-151800Y1136300D01*
X-151200Y1135367D01*
X-151000Y1134300D01*
X-151200Y1133233D01*
X-151700Y1132433D01*
X-152600Y1132033D01*
X-155000D01*
G01X-139500Y1128700D02*
X-137000Y1136700D01*
X-134500Y1128700D01*
G01X-135400Y1131500D02*
X-138600D01*
G01X-118800Y1136033D02*
X-119400Y1136433D01*
X-120100Y1136700D01*
X-120900D01*
X-121800Y1136300D01*
X-122500Y1135633D01*
X-123000Y1134833D01*
X-123400Y1133500D01*
X-123500Y1132300D01*
X-123300Y1131100D01*
X-123000Y1130300D01*
X-122400Y1129500D01*
X-121700Y1128967D01*
X-121000Y1128700D01*
X-120300D01*
X-119600Y1128967D01*
X-119000Y1129367D01*
X-118500Y1129900D01*
G01X-115500Y1128700D02*
X-113000Y1136700D01*
X-110500Y1128700D01*
G01X-111400Y1131500D02*
X-114600D01*
G01X-107300Y1128700D02*
Y1136700D01*
X-102700Y1128700D01*
Y1136700D01*
G01X-88200Y1132967D02*
X-87800Y1133367D01*
X-87500Y1134033D01*
X-87300Y1134967D01*
X-87500Y1135767D01*
X-87900Y1136300D01*
X-88600Y1136700D01*
X-91300D01*
Y1128700D01*
X-88000D01*
X-87300Y1129233D01*
X-86900Y1130033D01*
X-86700Y1130967D01*
X-86900Y1131900D01*
X-87500Y1132700D01*
X-88200Y1132967D01*
X-91300D01*
G01X-79000Y1128700D02*
X-83000D01*
Y1136700D01*
X-79000D01*
G01X-80600Y1132833D02*
X-83000D01*
G01X-67000Y1128700D02*
Y1136700D01*
X-64600D01*
X-63800Y1136300D01*
X-63200Y1135367D01*
X-63000Y1134300D01*
X-63200Y1133233D01*
X-63700Y1132433D01*
X-64600Y1132033D01*
X-67000D01*
G01X-59000Y1136700D02*
Y1128700D01*
X-55000D01*
G01X-51500D02*
X-49000Y1136700D01*
X-46500Y1128700D01*
G01X-47400Y1131500D02*
X-50600D01*
G01X-38800Y1136033D02*
X-39400Y1136433D01*
X-40100Y1136700D01*
X-40900D01*
X-41800Y1136300D01*
X-42500Y1135633D01*
X-43000Y1134833D01*
X-43400Y1133500D01*
X-43500Y1132300D01*
X-43300Y1131100D01*
X-43000Y1130300D01*
X-42400Y1129500D01*
X-41700Y1128967D01*
X-41000Y1128700D01*
X-40300D01*
X-39600Y1128967D01*
X-39000Y1129367D01*
X-38500Y1129900D01*
G01X-31000Y1128700D02*
X-35000D01*
Y1136700D01*
X-31000D01*
G01X-32600Y1132833D02*
X-35000D01*
G01X-27200Y1128700D02*
Y1136700D01*
X-25200D01*
X-24400Y1136300D01*
X-23800Y1135767D01*
X-23300Y1134967D01*
X-22900Y1134033D01*
X-22800Y1132700D01*
X-22900Y1131367D01*
X-23300Y1130433D01*
X-23800Y1129633D01*
X-24400Y1129100D01*
X-25200Y1128700D01*
X-27200D01*
G01X-11100Y1129766D02*
X-10300Y1129100D01*
X-9400Y1128700D01*
X-8600D01*
X-7800Y1129100D01*
X-7200Y1129766D01*
X-6900Y1130700D01*
X-7100Y1131633D01*
X-7600Y1132433D01*
X-8500Y1132967D01*
X-9700Y1133233D01*
X-10400Y1133767D01*
X-10700Y1134700D01*
X-10500Y1135633D01*
X-10000Y1136300D01*
X-9300Y1136700D01*
X-8600D01*
X-7900Y1136433D01*
X-7300Y1135767D01*
G01X1000Y1128700D02*
X-3000D01*
Y1136700D01*
X1000D01*
G01X-600Y1132833D02*
X-3000D01*
G01X5000Y1128700D02*
Y1136700D01*
X7400D01*
X8200Y1136300D01*
X8800Y1135367D01*
X9000Y1134300D01*
X8800Y1133233D01*
X8300Y1132433D01*
X7400Y1132033D01*
X5000D01*
G01X12500Y1128700D02*
X15000Y1136700D01*
X17500Y1128700D01*
G01X16600Y1131500D02*
X13400D01*
G01X21000Y1128700D02*
Y1136700D01*
X23500D01*
X24300Y1136300D01*
X24800Y1135767D01*
X25000Y1134700D01*
X24800Y1133633D01*
X24200Y1132967D01*
X23500Y1132567D01*
X21000D01*
G01X23500D02*
X25000Y1128700D01*
G01X28500D02*
X31000Y1136700D01*
X33500Y1128700D01*
G01X32600Y1131500D02*
X29400D01*
G01X39000Y1136700D02*
Y1128700D01*
G01X36700Y1136700D02*
X41300D01*
G01X49000Y1128700D02*
X45000D01*
Y1136700D01*
X49000D01*
G01X47400Y1132833D02*
X45000D01*
G01X53000Y1136700D02*
Y1128700D01*
X57000D01*
G01X63000D02*
Y1132300D01*
X61000Y1136700D01*
G01X65000D02*
X63000Y1132300D01*
G01X77100Y1128700D02*
Y1136700D01*
X80900D01*
G01X79500Y1132833D02*
X77100D01*
G01X85000Y1128700D02*
Y1136700D01*
X87500D01*
X88300Y1136300D01*
X88800Y1135767D01*
X89000Y1134700D01*
X88800Y1133633D01*
X88200Y1132967D01*
X87500Y1132567D01*
X85000D01*
G01X87500D02*
X89000Y1128700D01*
G01X95000D02*
X94200Y1128833D01*
X93500Y1129367D01*
X92900Y1130167D01*
X92500Y1131100D01*
X92300Y1132167D01*
Y1133233D01*
X92500Y1134300D01*
X92900Y1135233D01*
X93500Y1136033D01*
X94200Y1136567D01*
X95000Y1136700D01*
X95800Y1136567D01*
X96500Y1136033D01*
X97100Y1135233D01*
X97500Y1134300D01*
X97700Y1133233D01*
Y1132167D01*
X97500Y1131100D01*
X97100Y1130167D01*
X96500Y1129367D01*
X95800Y1128833D01*
X95000Y1128700D01*
G01X100400D02*
Y1136700D01*
X103000Y1130033D01*
X105600Y1136700D01*
Y1128700D01*
G01X119600Y1132700D02*
X121600D01*
Y1130300D01*
X121000Y1129500D01*
X120300Y1128967D01*
X119300Y1128700D01*
X118300Y1128967D01*
X117600Y1129500D01*
X117000Y1130300D01*
X116600Y1131233D01*
X116400Y1132300D01*
Y1133233D01*
X116600Y1134033D01*
X117000Y1134967D01*
X117600Y1135767D01*
X118200Y1136300D01*
X119000Y1136700D01*
X119700D01*
X120500Y1136433D01*
X121100Y1135900D01*
G01X125000Y1128700D02*
Y1136700D01*
X127500D01*
X128300Y1136300D01*
X128800Y1135767D01*
X129000Y1134700D01*
X128800Y1133633D01*
X128200Y1132967D01*
X127500Y1132567D01*
X125000D01*
G01X127500D02*
X129000Y1128700D01*
G01X135000D02*
X134200Y1128833D01*
X133500Y1129367D01*
X132900Y1130167D01*
X132500Y1131100D01*
X132300Y1132167D01*
Y1133233D01*
X132500Y1134300D01*
X132900Y1135233D01*
X133500Y1136033D01*
X134200Y1136567D01*
X135000Y1136700D01*
X135800Y1136567D01*
X136500Y1136033D01*
X137100Y1135233D01*
X137500Y1134300D01*
X137700Y1133233D01*
Y1132167D01*
X137500Y1131100D01*
X137100Y1130167D01*
X136500Y1129367D01*
X135800Y1128833D01*
X135000Y1128700D01*
G01X140800Y1136700D02*
Y1130967D01*
X141200Y1129766D01*
X142000Y1128967D01*
X143000Y1128700D01*
X144000Y1128967D01*
X144800Y1129766D01*
X145200Y1130967D01*
Y1136700D01*
G01X149000Y1128700D02*
Y1136700D01*
X151400D01*
X152200Y1136300D01*
X152800Y1135367D01*
X153000Y1134300D01*
X152800Y1133233D01*
X152300Y1132433D01*
X151400Y1132033D01*
X149000D01*
G01X167800Y1132967D02*
X168200Y1133367D01*
X168500Y1134033D01*
X168700Y1134967D01*
X168500Y1135767D01*
X168100Y1136300D01*
X167400Y1136700D01*
X164700D01*
Y1128700D01*
X168000D01*
X168700Y1129233D01*
X169100Y1130033D01*
X169300Y1130967D01*
X169100Y1131900D01*
X168500Y1132700D01*
X167800Y1132967D01*
X164700D01*
G01X175000Y1128433D02*
X174800Y1128567D01*
Y1128833D01*
X175000Y1128967D01*
X175200Y1128833D01*
Y1128567D01*
X175000Y1128433D01*
G01X-345000Y1151700D02*
Y1143700D01*
G01X-347300Y1151700D02*
X-342700D01*
G01X-337000Y1143700D02*
X-337800Y1143833D01*
X-338500Y1144367D01*
X-339100Y1145167D01*
X-339500Y1146100D01*
X-339700Y1147167D01*
Y1148233D01*
X-339500Y1149300D01*
X-339100Y1150233D01*
X-338500Y1151033D01*
X-337800Y1151567D01*
X-337000Y1151700D01*
X-336200Y1151567D01*
X-335500Y1151033D01*
X-334900Y1150233D01*
X-334500Y1149300D01*
X-334300Y1148233D01*
Y1147167D01*
X-334500Y1146100D01*
X-334900Y1145167D01*
X-335500Y1144367D01*
X-336200Y1143833D01*
X-337000Y1143700D01*
G01X-321000Y1151700D02*
Y1143700D01*
G01X-323300Y1151700D02*
X-318700D01*
G01X-315100Y1143700D02*
Y1151700D01*
G01X-310900D02*
Y1143700D01*
G01Y1147700D02*
X-315100D01*
G01X-303000Y1143700D02*
X-307000D01*
Y1151700D01*
X-303000D01*
G01X-304600Y1147833D02*
X-307000D01*
G01X-288200Y1147967D02*
X-287800Y1148367D01*
X-287500Y1149033D01*
X-287300Y1149967D01*
X-287500Y1150767D01*
X-287900Y1151300D01*
X-288600Y1151700D01*
X-291300D01*
Y1143700D01*
X-288000D01*
X-287300Y1144233D01*
X-286900Y1145033D01*
X-286700Y1145967D01*
X-286900Y1146900D01*
X-287500Y1147700D01*
X-288200Y1147967D01*
X-291300D01*
G01X-281000Y1143700D02*
X-281800Y1143833D01*
X-282500Y1144367D01*
X-283100Y1145167D01*
X-283500Y1146100D01*
X-283700Y1147167D01*
Y1148233D01*
X-283500Y1149300D01*
X-283100Y1150233D01*
X-282500Y1151033D01*
X-281800Y1151567D01*
X-281000Y1151700D01*
X-280200Y1151567D01*
X-279500Y1151033D01*
X-278900Y1150233D01*
X-278500Y1149300D01*
X-278300Y1148233D01*
Y1147167D01*
X-278500Y1146100D01*
X-278900Y1145167D01*
X-279500Y1144367D01*
X-280200Y1143833D01*
X-281000Y1143700D01*
G01X-275500D02*
X-273000Y1151700D01*
X-270500Y1143700D01*
G01X-271400Y1146500D02*
X-274600D01*
G01X-267000Y1143700D02*
Y1151700D01*
X-264500D01*
X-263700Y1151300D01*
X-263200Y1150767D01*
X-263000Y1149700D01*
X-263200Y1148633D01*
X-263800Y1147967D01*
X-264500Y1147567D01*
X-267000D01*
G01X-264500D02*
X-263000Y1143700D01*
G01X-259200D02*
Y1151700D01*
X-257200D01*
X-256400Y1151300D01*
X-255800Y1150767D01*
X-255300Y1149967D01*
X-254900Y1149033D01*
X-254800Y1147700D01*
X-254900Y1146367D01*
X-255300Y1145433D01*
X-255800Y1144633D01*
X-256400Y1144100D01*
X-257200Y1143700D01*
X-259200D01*
G01X-238800Y1151033D02*
X-239400Y1151433D01*
X-240100Y1151700D01*
X-240900D01*
X-241800Y1151300D01*
X-242500Y1150633D01*
X-243000Y1149833D01*
X-243400Y1148500D01*
X-243500Y1147300D01*
X-243300Y1146100D01*
X-243000Y1145300D01*
X-242400Y1144500D01*
X-241700Y1143967D01*
X-241000Y1143700D01*
X-240300D01*
X-239600Y1143967D01*
X-239000Y1144367D01*
X-238500Y1144900D01*
G01X-233000Y1143700D02*
X-233800Y1143833D01*
X-234500Y1144367D01*
X-235100Y1145167D01*
X-235500Y1146100D01*
X-235700Y1147167D01*
Y1148233D01*
X-235500Y1149300D01*
X-235100Y1150233D01*
X-234500Y1151033D01*
X-233800Y1151567D01*
X-233000Y1151700D01*
X-232200Y1151567D01*
X-231500Y1151033D01*
X-230900Y1150233D01*
X-230500Y1149300D01*
X-230300Y1148233D01*
Y1147167D01*
X-230500Y1146100D01*
X-230900Y1145167D01*
X-231500Y1144367D01*
X-232200Y1143833D01*
X-233000Y1143700D01*
G01X-227200Y1151700D02*
Y1145967D01*
X-226800Y1144766D01*
X-226000Y1143967D01*
X-225000Y1143700D01*
X-224000Y1143967D01*
X-223200Y1144766D01*
X-222800Y1145967D01*
Y1151700D01*
G01X-219000Y1143700D02*
Y1151700D01*
X-216600D01*
X-215800Y1151300D01*
X-215200Y1150367D01*
X-215000Y1149300D01*
X-215200Y1148233D01*
X-215700Y1147433D01*
X-216600Y1147033D01*
X-219000D01*
G01X-209000Y1143700D02*
X-209800Y1143833D01*
X-210500Y1144367D01*
X-211100Y1145167D01*
X-211500Y1146100D01*
X-211700Y1147167D01*
Y1148233D01*
X-211500Y1149300D01*
X-211100Y1150233D01*
X-210500Y1151033D01*
X-209800Y1151567D01*
X-209000Y1151700D01*
X-208200Y1151567D01*
X-207500Y1151033D01*
X-206900Y1150233D01*
X-206500Y1149300D01*
X-206300Y1148233D01*
Y1147167D01*
X-206500Y1146100D01*
X-206900Y1145167D01*
X-207500Y1144367D01*
X-208200Y1143833D01*
X-209000Y1143700D01*
G01X-203300D02*
Y1151700D01*
X-198700Y1143700D01*
Y1151700D01*
G01X-195100Y1144766D02*
X-194300Y1144100D01*
X-193400Y1143700D01*
X-192600D01*
X-191800Y1144100D01*
X-191200Y1144766D01*
X-190900Y1145700D01*
X-191100Y1146633D01*
X-191600Y1147433D01*
X-192500Y1147967D01*
X-193700Y1148233D01*
X-194400Y1148767D01*
X-194700Y1149700D01*
X-194500Y1150633D01*
X-194000Y1151300D01*
X-193300Y1151700D01*
X-192600D01*
X-191900Y1151433D01*
X-191300Y1150767D01*
G01X-185000Y1143433D02*
X-185200Y1143567D01*
Y1143833D01*
X-185000Y1143967D01*
X-184800Y1143833D01*
Y1143567D01*
X-185000Y1143433D01*
G01X-178200Y1151700D02*
X-175800D01*
G01X-177000D02*
Y1143700D01*
G01X-178200D02*
X-175800D01*
G01X-170900D02*
Y1151700D01*
X-167100D01*
G01X-168500Y1147833D02*
X-170900D01*
G01X-154200Y1151700D02*
X-151800D01*
G01X-153000D02*
Y1143700D01*
G01X-154200D02*
X-151800D01*
G01X-145000Y1151700D02*
Y1143700D01*
G01X-147300Y1151700D02*
X-142700D01*
G01X-130200D02*
X-127800D01*
G01X-129000D02*
Y1143700D01*
G01X-130200D02*
X-127800D01*
G01X-123100Y1144766D02*
X-122300Y1144100D01*
X-121400Y1143700D01*
X-120600D01*
X-119800Y1144100D01*
X-119200Y1144766D01*
X-118900Y1145700D01*
X-119100Y1146633D01*
X-119600Y1147433D01*
X-120500Y1147967D01*
X-121700Y1148233D01*
X-122400Y1148767D01*
X-122700Y1149700D01*
X-122500Y1150633D01*
X-122000Y1151300D01*
X-121300Y1151700D01*
X-120600D01*
X-119900Y1151433D01*
X-119300Y1150767D01*
G01X-107300Y1143700D02*
Y1151700D01*
X-102700Y1143700D01*
Y1151700D01*
G01X-97000Y1143700D02*
X-97800Y1143833D01*
X-98500Y1144367D01*
X-99100Y1145167D01*
X-99500Y1146100D01*
X-99700Y1147167D01*
Y1148233D01*
X-99500Y1149300D01*
X-99100Y1150233D01*
X-98500Y1151033D01*
X-97800Y1151567D01*
X-97000Y1151700D01*
X-96200Y1151567D01*
X-95500Y1151033D01*
X-94900Y1150233D01*
X-94500Y1149300D01*
X-94300Y1148233D01*
Y1147167D01*
X-94500Y1146100D01*
X-94900Y1145167D01*
X-95500Y1144367D01*
X-96200Y1143833D01*
X-97000Y1143700D01*
G01X-89000Y1151700D02*
Y1143700D01*
G01X-91300Y1151700D02*
X-86700D01*
G01X-75000Y1143700D02*
Y1151700D01*
X-72600D01*
X-71800Y1151300D01*
X-71200Y1150367D01*
X-71000Y1149300D01*
X-71200Y1148233D01*
X-71700Y1147433D01*
X-72600Y1147033D01*
X-75000D01*
G01X-65000Y1143700D02*
X-65800Y1143833D01*
X-66500Y1144367D01*
X-67100Y1145167D01*
X-67500Y1146100D01*
X-67700Y1147167D01*
Y1148233D01*
X-67500Y1149300D01*
X-67100Y1150233D01*
X-66500Y1151033D01*
X-65800Y1151567D01*
X-65000Y1151700D01*
X-64200Y1151567D01*
X-63500Y1151033D01*
X-62900Y1150233D01*
X-62500Y1149300D01*
X-62300Y1148233D01*
Y1147167D01*
X-62500Y1146100D01*
X-62900Y1145167D01*
X-63500Y1144367D01*
X-64200Y1143833D01*
X-65000Y1143700D01*
G01X-59100Y1144766D02*
X-58300Y1144100D01*
X-57400Y1143700D01*
X-56600D01*
X-55800Y1144100D01*
X-55200Y1144766D01*
X-54900Y1145700D01*
X-55100Y1146633D01*
X-55600Y1147433D01*
X-56500Y1147967D01*
X-57700Y1148233D01*
X-58400Y1148767D01*
X-58700Y1149700D01*
X-58500Y1150633D01*
X-58000Y1151300D01*
X-57300Y1151700D01*
X-56600D01*
X-55900Y1151433D01*
X-55300Y1150767D01*
G01X-51100Y1144766D02*
X-50300Y1144100D01*
X-49400Y1143700D01*
X-48600D01*
X-47800Y1144100D01*
X-47200Y1144766D01*
X-46900Y1145700D01*
X-47100Y1146633D01*
X-47600Y1147433D01*
X-48500Y1147967D01*
X-49700Y1148233D01*
X-50400Y1148767D01*
X-50700Y1149700D01*
X-50500Y1150633D01*
X-50000Y1151300D01*
X-49300Y1151700D01*
X-48600D01*
X-47900Y1151433D01*
X-47300Y1150767D01*
G01X-42200Y1151700D02*
X-39800D01*
G01X-41000D02*
Y1143700D01*
G01X-42200D02*
X-39800D01*
G01X-32200Y1147967D02*
X-31800Y1148367D01*
X-31500Y1149033D01*
X-31300Y1149967D01*
X-31500Y1150767D01*
X-31900Y1151300D01*
X-32600Y1151700D01*
X-35300D01*
Y1143700D01*
X-32000D01*
X-31300Y1144233D01*
X-30900Y1145033D01*
X-30700Y1145967D01*
X-30900Y1146900D01*
X-31500Y1147700D01*
X-32200Y1147967D01*
X-35300D01*
G01X-27000Y1151700D02*
Y1143700D01*
X-23000D01*
G01X-15000D02*
X-19000D01*
Y1151700D01*
X-15000D01*
G01X-16600Y1147833D02*
X-19000D01*
G01X-1000Y1151700D02*
Y1143700D01*
G01X-3300Y1151700D02*
X1300D01*
G01X7000Y1143700D02*
X6200Y1143833D01*
X5500Y1144367D01*
X4900Y1145167D01*
X4500Y1146100D01*
X4300Y1147167D01*
Y1148233D01*
X4500Y1149300D01*
X4900Y1150233D01*
X5500Y1151033D01*
X6200Y1151567D01*
X7000Y1151700D01*
X7800Y1151567D01*
X8500Y1151033D01*
X9100Y1150233D01*
X9500Y1149300D01*
X9700Y1148233D01*
Y1147167D01*
X9500Y1146100D01*
X9100Y1145167D01*
X8500Y1144367D01*
X7800Y1143833D01*
X7000Y1143700D01*
G01X21100D02*
Y1151700D01*
X24900D01*
G01X23500Y1147833D02*
X21100D01*
G01X29800Y1151700D02*
X32200D01*
G01X31000D02*
Y1143700D01*
G01X29800D02*
X32200D01*
G01X39000Y1151700D02*
Y1143700D01*
G01X36700Y1151700D02*
X41300D01*
G01X53800D02*
X56200D01*
G01X55000D02*
Y1143700D01*
G01X53800D02*
X56200D01*
G01X60700D02*
Y1151700D01*
X65300Y1143700D01*
Y1151700D01*
G01X79000D02*
Y1143700D01*
G01X76700Y1151700D02*
X81300D01*
G01X84900Y1143700D02*
Y1151700D01*
G01X89100D02*
Y1143700D01*
G01Y1147700D02*
X84900D01*
G01X97000Y1143700D02*
X93000D01*
Y1151700D01*
X97000D01*
G01X95400Y1147833D02*
X93000D01*
G01X109000Y1151700D02*
Y1143700D01*
X113000D01*
G01X119000D02*
X118200Y1143833D01*
X117500Y1144367D01*
X116900Y1145167D01*
X116500Y1146100D01*
X116300Y1147167D01*
Y1148233D01*
X116500Y1149300D01*
X116900Y1150233D01*
X117500Y1151033D01*
X118200Y1151567D01*
X119000Y1151700D01*
X119800Y1151567D01*
X120500Y1151033D01*
X121100Y1150233D01*
X121500Y1149300D01*
X121700Y1148233D01*
Y1147167D01*
X121500Y1146100D01*
X121100Y1145167D01*
X120500Y1144367D01*
X119800Y1143833D01*
X119000Y1143700D01*
G01X129200Y1151033D02*
X128600Y1151433D01*
X127900Y1151700D01*
X127100D01*
X126200Y1151300D01*
X125500Y1150633D01*
X125000Y1149833D01*
X124600Y1148500D01*
X124500Y1147300D01*
X124700Y1146100D01*
X125000Y1145300D01*
X125600Y1144500D01*
X126300Y1143967D01*
X127000Y1143700D01*
X127700D01*
X128400Y1143967D01*
X129000Y1144367D01*
X129500Y1144900D01*
G01X132500Y1143700D02*
X135000Y1151700D01*
X137500Y1143700D01*
G01X136600Y1146500D02*
X133400D01*
G01X143000Y1151700D02*
Y1143700D01*
G01X140700Y1151700D02*
X145300D01*
G01X149800D02*
X152200D01*
G01X151000D02*
Y1143700D01*
G01X149800D02*
X152200D01*
G01X159000D02*
X158200Y1143833D01*
X157500Y1144367D01*
X156900Y1145167D01*
X156500Y1146100D01*
X156300Y1147167D01*
Y1148233D01*
X156500Y1149300D01*
X156900Y1150233D01*
X157500Y1151033D01*
X158200Y1151567D01*
X159000Y1151700D01*
X159800Y1151567D01*
X160500Y1151033D01*
X161100Y1150233D01*
X161500Y1149300D01*
X161700Y1148233D01*
Y1147167D01*
X161500Y1146100D01*
X161100Y1145167D01*
X160500Y1144367D01*
X159800Y1143833D01*
X159000Y1143700D01*
G01X164700D02*
Y1151700D01*
X169300Y1143700D01*
Y1151700D01*
G01X172900Y1144766D02*
X173700Y1144100D01*
X174600Y1143700D01*
X175400D01*
X176200Y1144100D01*
X176800Y1144766D01*
X177100Y1145700D01*
X176900Y1146633D01*
X176400Y1147433D01*
X175500Y1147967D01*
X174300Y1148233D01*
X173600Y1148767D01*
X173300Y1149700D01*
X173500Y1150633D01*
X174000Y1151300D01*
X174700Y1151700D01*
X175400D01*
X176100Y1151433D01*
X176700Y1150767D01*
G01X189100Y1143700D02*
Y1151700D01*
X192900D01*
G01X191500Y1147833D02*
X189100D01*
G01X199000Y1143700D02*
X198200Y1143833D01*
X197500Y1144367D01*
X196900Y1145167D01*
X196500Y1146100D01*
X196300Y1147167D01*
Y1148233D01*
X196500Y1149300D01*
X196900Y1150233D01*
X197500Y1151033D01*
X198200Y1151567D01*
X199000Y1151700D01*
X199800Y1151567D01*
X200500Y1151033D01*
X201100Y1150233D01*
X201500Y1149300D01*
X201700Y1148233D01*
Y1147167D01*
X201500Y1146100D01*
X201100Y1145167D01*
X200500Y1144367D01*
X199800Y1143833D01*
X199000Y1143700D01*
G01X205000D02*
Y1151700D01*
X207500D01*
X208300Y1151300D01*
X208800Y1150767D01*
X209000Y1149700D01*
X208800Y1148633D01*
X208200Y1147967D01*
X207500Y1147567D01*
X205000D01*
G01X207500D02*
X209000Y1143700D01*
G01X223800Y1147967D02*
X224200Y1148367D01*
X224500Y1149033D01*
X224700Y1149967D01*
X224500Y1150767D01*
X224100Y1151300D01*
X223400Y1151700D01*
X220700D01*
Y1143700D01*
X224000D01*
X224700Y1144233D01*
X225100Y1145033D01*
X225300Y1145967D01*
X225100Y1146900D01*
X224500Y1147700D01*
X223800Y1147967D01*
X220700D01*
G01X231000Y1143700D02*
X230200Y1143833D01*
X229500Y1144367D01*
X228900Y1145167D01*
X228500Y1146100D01*
X228300Y1147167D01*
Y1148233D01*
X228500Y1149300D01*
X228900Y1150233D01*
X229500Y1151033D01*
X230200Y1151567D01*
X231000Y1151700D01*
X231800Y1151567D01*
X232500Y1151033D01*
X233100Y1150233D01*
X233500Y1149300D01*
X233700Y1148233D01*
Y1147167D01*
X233500Y1146100D01*
X233100Y1145167D01*
X232500Y1144367D01*
X231800Y1143833D01*
X231000Y1143700D01*
G01X239000Y1151700D02*
Y1143700D01*
G01X236700Y1151700D02*
X241300D01*
G01X244900Y1143700D02*
Y1151700D01*
G01X249100D02*
Y1143700D01*
G01Y1147700D02*
X244900D01*
G01X-347000Y1158700D02*
Y1166700D01*
X-344600D01*
X-343800Y1166300D01*
X-343200Y1165367D01*
X-343000Y1164300D01*
X-343200Y1163233D01*
X-343700Y1162433D01*
X-344600Y1162033D01*
X-347000D01*
G01X-339000Y1166700D02*
Y1158700D01*
X-335000D01*
G01X-327000D02*
X-331000D01*
Y1166700D01*
X-327000D01*
G01X-328600Y1162833D02*
X-331000D01*
G01X-323500Y1158700D02*
X-321000Y1166700D01*
X-318500Y1158700D01*
G01X-319400Y1161500D02*
X-322600D01*
G01X-315100Y1159766D02*
X-314300Y1159100D01*
X-313400Y1158700D01*
X-312600D01*
X-311800Y1159100D01*
X-311200Y1159766D01*
X-310900Y1160700D01*
X-311100Y1161633D01*
X-311600Y1162433D01*
X-312500Y1162967D01*
X-313700Y1163233D01*
X-314400Y1163767D01*
X-314700Y1164700D01*
X-314500Y1165633D01*
X-314000Y1166300D01*
X-313300Y1166700D01*
X-312600D01*
X-311900Y1166433D01*
X-311300Y1165767D01*
G01X-303000Y1158700D02*
X-307000D01*
Y1166700D01*
X-303000D01*
G01X-304600Y1162833D02*
X-307000D01*
G01X-290900Y1158700D02*
Y1166700D01*
X-287100D01*
G01X-288500Y1162833D02*
X-290900D01*
G01X-281000Y1158700D02*
X-281800Y1158833D01*
X-282500Y1159367D01*
X-283100Y1160167D01*
X-283500Y1161100D01*
X-283700Y1162167D01*
Y1163233D01*
X-283500Y1164300D01*
X-283100Y1165233D01*
X-282500Y1166033D01*
X-281800Y1166567D01*
X-281000Y1166700D01*
X-280200Y1166567D01*
X-279500Y1166033D01*
X-278900Y1165233D01*
X-278500Y1164300D01*
X-278300Y1163233D01*
Y1162167D01*
X-278500Y1161100D01*
X-278900Y1160167D01*
X-279500Y1159367D01*
X-280200Y1158833D01*
X-281000Y1158700D01*
G01X-275000Y1166700D02*
Y1158700D01*
X-271000D01*
G01X-267000Y1166700D02*
Y1158700D01*
X-263000D01*
G01X-257000D02*
X-257800Y1158833D01*
X-258500Y1159367D01*
X-259100Y1160167D01*
X-259500Y1161100D01*
X-259700Y1162167D01*
Y1163233D01*
X-259500Y1164300D01*
X-259100Y1165233D01*
X-258500Y1166033D01*
X-257800Y1166567D01*
X-257000Y1166700D01*
X-256200Y1166567D01*
X-255500Y1166033D01*
X-254900Y1165233D01*
X-254500Y1164300D01*
X-254300Y1163233D01*
Y1162167D01*
X-254500Y1161100D01*
X-254900Y1160167D01*
X-255500Y1159367D01*
X-256200Y1158833D01*
X-257000Y1158700D01*
G01X-252000Y1166700D02*
X-250600Y1158700D01*
X-249000Y1166700D01*
X-247400Y1158700D01*
X-246000Y1166700D01*
G01X-233000D02*
Y1158700D01*
G01X-235300Y1166700D02*
X-230700D01*
G01X-227100Y1158700D02*
Y1166700D01*
G01X-222900D02*
Y1158700D01*
G01Y1162700D02*
X-227100D01*
G01X-215000Y1158700D02*
X-219000D01*
Y1166700D01*
X-215000D01*
G01X-216600Y1162833D02*
X-219000D01*
G01X-203100Y1159766D02*
X-202300Y1159100D01*
X-201400Y1158700D01*
X-200600D01*
X-199800Y1159100D01*
X-199200Y1159766D01*
X-198900Y1160700D01*
X-199100Y1161633D01*
X-199600Y1162433D01*
X-200500Y1162967D01*
X-201700Y1163233D01*
X-202400Y1163767D01*
X-202700Y1164700D01*
X-202500Y1165633D01*
X-202000Y1166300D01*
X-201300Y1166700D01*
X-200600D01*
X-199900Y1166433D01*
X-199300Y1165767D01*
G01X-195000Y1166700D02*
Y1158700D01*
X-191000D01*
G01X-186200Y1166700D02*
X-183800D01*
G01X-185000D02*
Y1158700D01*
G01X-186200D02*
X-183800D01*
G01X-179200D02*
Y1166700D01*
X-177200D01*
X-176400Y1166300D01*
X-175800Y1165767D01*
X-175300Y1164967D01*
X-174900Y1164033D01*
X-174800Y1162700D01*
X-174900Y1161367D01*
X-175300Y1160433D01*
X-175800Y1159633D01*
X-176400Y1159100D01*
X-177200Y1158700D01*
X-179200D01*
G01X-167000D02*
X-171000D01*
Y1166700D01*
X-167000D01*
G01X-168600Y1162833D02*
X-171000D01*
G01X-163100Y1159766D02*
X-162300Y1159100D01*
X-161400Y1158700D01*
X-160600D01*
X-159800Y1159100D01*
X-159200Y1159766D01*
X-158900Y1160700D01*
X-159100Y1161633D01*
X-159600Y1162433D01*
X-160500Y1162967D01*
X-161700Y1163233D01*
X-162400Y1163767D01*
X-162700Y1164700D01*
X-162500Y1165633D01*
X-162000Y1166300D01*
X-161300Y1166700D01*
X-160600D01*
X-159900Y1166433D01*
X-159300Y1165767D01*
G01X-145000Y1166700D02*
Y1158700D01*
G01X-147300Y1166700D02*
X-142700D01*
G01X-137000Y1158700D02*
X-137800Y1158833D01*
X-138500Y1159367D01*
X-139100Y1160167D01*
X-139500Y1161100D01*
X-139700Y1162167D01*
Y1163233D01*
X-139500Y1164300D01*
X-139100Y1165233D01*
X-138500Y1166033D01*
X-137800Y1166567D01*
X-137000Y1166700D01*
X-136200Y1166567D01*
X-135500Y1166033D01*
X-134900Y1165233D01*
X-134500Y1164300D01*
X-134300Y1163233D01*
Y1162167D01*
X-134500Y1161100D01*
X-134900Y1160167D01*
X-135500Y1159367D01*
X-136200Y1158833D01*
X-137000Y1158700D01*
G01X-120400Y1162700D02*
X-118400D01*
Y1160300D01*
X-119000Y1159500D01*
X-119700Y1158967D01*
X-120700Y1158700D01*
X-121700Y1158967D01*
X-122400Y1159500D01*
X-123000Y1160300D01*
X-123400Y1161233D01*
X-123600Y1162300D01*
Y1163233D01*
X-123400Y1164033D01*
X-123000Y1164967D01*
X-122400Y1165767D01*
X-121800Y1166300D01*
X-121000Y1166700D01*
X-120300D01*
X-119500Y1166433D01*
X-118900Y1165900D01*
G01X-111000Y1158700D02*
X-115000D01*
Y1166700D01*
X-111000D01*
G01X-112600Y1162833D02*
X-115000D01*
G01X-107300Y1158700D02*
Y1166700D01*
X-102700Y1158700D01*
Y1166700D01*
G01X-95000Y1158700D02*
X-99000D01*
Y1166700D01*
X-95000D01*
G01X-96600Y1162833D02*
X-99000D01*
G01X-91000Y1158700D02*
Y1166700D01*
X-88500D01*
X-87700Y1166300D01*
X-87200Y1165767D01*
X-87000Y1164700D01*
X-87200Y1163633D01*
X-87800Y1162967D01*
X-88500Y1162567D01*
X-91000D01*
G01X-88500D02*
X-87000Y1158700D01*
G01X-83500D02*
X-81000Y1166700D01*
X-78500Y1158700D01*
G01X-79400Y1161500D02*
X-82600D01*
G01X-73000Y1166700D02*
Y1158700D01*
G01X-75300Y1166700D02*
X-70700D01*
G01X-63000Y1158700D02*
X-67000D01*
Y1166700D01*
X-63000D01*
G01X-64600Y1162833D02*
X-67000D01*
G01X-49000Y1166700D02*
Y1158700D01*
G01X-51300Y1166700D02*
X-46700D01*
G01X-43100Y1158700D02*
Y1166700D01*
G01X-38900D02*
Y1158700D01*
G01Y1162700D02*
X-43100D01*
G01X-31000Y1158700D02*
X-35000D01*
Y1166700D01*
X-31000D01*
G01X-32600Y1162833D02*
X-35000D01*
G01X-19000Y1158700D02*
Y1166700D01*
X-16600D01*
X-15800Y1166300D01*
X-15200Y1165367D01*
X-15000Y1164300D01*
X-15200Y1163233D01*
X-15700Y1162433D01*
X-16600Y1162033D01*
X-19000D01*
G01X-11500Y1158700D02*
X-9000Y1166700D01*
X-6500Y1158700D01*
G01X-7400Y1161500D02*
X-10600D01*
G01X-3200Y1158700D02*
Y1166700D01*
X-1200D01*
X-400Y1166300D01*
X200Y1165767D01*
X700Y1164967D01*
X1100Y1164033D01*
X1200Y1162700D01*
X1100Y1161367D01*
X700Y1160433D01*
X200Y1159633D01*
X-400Y1159100D01*
X-1200Y1158700D01*
X-3200D01*
G01X4900Y1159766D02*
X5700Y1159100D01*
X6600Y1158700D01*
X7400D01*
X8200Y1159100D01*
X8800Y1159766D01*
X9100Y1160700D01*
X8900Y1161633D01*
X8400Y1162433D01*
X7500Y1162967D01*
X6300Y1163233D01*
X5600Y1163767D01*
X5300Y1164700D01*
X5500Y1165633D01*
X6000Y1166300D01*
X6700Y1166700D01*
X7400D01*
X8100Y1166433D01*
X8700Y1165767D01*
G01X20500Y1158700D02*
X23000Y1166700D01*
X25500Y1158700D01*
G01X24600Y1161500D02*
X21400D01*
G01X28700Y1158700D02*
Y1166700D01*
X33300Y1158700D01*
Y1166700D01*
G01X36800Y1158700D02*
Y1166700D01*
X38800D01*
X39600Y1166300D01*
X40200Y1165767D01*
X40700Y1164967D01*
X41100Y1164033D01*
X41200Y1162700D01*
X41100Y1161367D01*
X40700Y1160433D01*
X40200Y1159633D01*
X39600Y1159100D01*
X38800Y1158700D01*
X36800D01*
G01X52400D02*
Y1166700D01*
X55000Y1160033D01*
X57600Y1166700D01*
Y1158700D01*
G01X60500D02*
X63000Y1166700D01*
X65500Y1158700D01*
G01X64600Y1161500D02*
X61400D01*
G01X68900Y1159766D02*
X69700Y1159100D01*
X70600Y1158700D01*
X71400D01*
X72200Y1159100D01*
X72800Y1159766D01*
X73100Y1160700D01*
X72900Y1161633D01*
X72400Y1162433D01*
X71500Y1162967D01*
X70300Y1163233D01*
X69600Y1163767D01*
X69300Y1164700D01*
X69500Y1165633D01*
X70000Y1166300D01*
X70700Y1166700D01*
X71400D01*
X72100Y1166433D01*
X72700Y1165767D01*
G01X76800Y1158700D02*
Y1166700D01*
G01X80600D02*
X76800Y1161766D01*
G01X81200Y1158700D02*
X78500Y1164033D01*
G01X92500Y1158700D02*
X95000Y1166700D01*
X97500Y1158700D01*
G01X96600Y1161500D02*
X93400D01*
G01X100700Y1158700D02*
Y1166700D01*
X105300Y1158700D01*
Y1166700D01*
G01X108800Y1158700D02*
Y1166700D01*
X110800D01*
X111600Y1166300D01*
X112200Y1165767D01*
X112700Y1164967D01*
X113100Y1164033D01*
X113200Y1162700D01*
X113100Y1161367D01*
X112700Y1160433D01*
X112200Y1159633D01*
X111600Y1159100D01*
X110800Y1158700D01*
X108800D01*
G01X124500D02*
X127000Y1166700D01*
X129500Y1158700D01*
G01X128600Y1161500D02*
X125400D01*
G01X132800Y1158700D02*
Y1166700D01*
X134800D01*
X135600Y1166300D01*
X136200Y1165767D01*
X136700Y1164967D01*
X137100Y1164033D01*
X137200Y1162700D01*
X137100Y1161367D01*
X136700Y1160433D01*
X136200Y1159633D01*
X135600Y1159100D01*
X134800Y1158700D01*
X132800D01*
G01X140800D02*
Y1166700D01*
X142800D01*
X143600Y1166300D01*
X144200Y1165767D01*
X144700Y1164967D01*
X145100Y1164033D01*
X145200Y1162700D01*
X145100Y1161367D01*
X144700Y1160433D01*
X144200Y1159633D01*
X143600Y1159100D01*
X142800Y1158700D01*
X140800D01*
G01X159000Y1166700D02*
Y1158700D01*
G01X156700Y1166700D02*
X161300D01*
G01X164900Y1158700D02*
Y1166700D01*
G01X169100D02*
Y1158700D01*
G01Y1162700D02*
X164900D01*
G01X177000Y1158700D02*
X173000D01*
Y1166700D01*
X177000D01*
G01X175400Y1162833D02*
X173000D01*
G01X191000Y1166700D02*
Y1158700D01*
G01X188700Y1166700D02*
X193300D01*
G01X201000Y1158700D02*
X197000D01*
Y1166700D01*
X201000D01*
G01X199400Y1162833D02*
X197000D01*
G01X204900Y1159766D02*
X205700Y1159100D01*
X206600Y1158700D01*
X207400D01*
X208200Y1159100D01*
X208800Y1159766D01*
X209100Y1160700D01*
X208900Y1161633D01*
X208400Y1162433D01*
X207500Y1162967D01*
X206300Y1163233D01*
X205600Y1163767D01*
X205300Y1164700D01*
X205500Y1165633D01*
X206000Y1166300D01*
X206700Y1166700D01*
X207400D01*
X208100Y1166433D01*
X208700Y1165767D01*
G01X215000Y1166700D02*
Y1158700D01*
G01X212700Y1166700D02*
X217300D01*
G01X229000Y1158700D02*
Y1166700D01*
X231400D01*
X232200Y1166300D01*
X232800Y1165367D01*
X233000Y1164300D01*
X232800Y1163233D01*
X232300Y1162433D01*
X231400Y1162033D01*
X229000D01*
G01X236500Y1158700D02*
X239000Y1166700D01*
X241500Y1158700D01*
G01X240600Y1161500D02*
X237400D01*
G01X244800Y1158700D02*
Y1166700D01*
X246800D01*
X247600Y1166300D01*
X248200Y1165767D01*
X248700Y1164967D01*
X249100Y1164033D01*
X249200Y1162700D01*
X249100Y1161367D01*
X248700Y1160433D01*
X248200Y1159633D01*
X247600Y1159100D01*
X246800Y1158700D01*
X244800D01*
G01X252900Y1159766D02*
X253700Y1159100D01*
X254600Y1158700D01*
X255400D01*
X256200Y1159100D01*
X256800Y1159766D01*
X257100Y1160700D01*
X256900Y1161633D01*
X256400Y1162433D01*
X255500Y1162967D01*
X254300Y1163233D01*
X253600Y1163767D01*
X253300Y1164700D01*
X253500Y1165633D01*
X254000Y1166300D01*
X254700Y1166700D01*
X255400D01*
X256100Y1166433D01*
X256700Y1165767D01*
G01X-347500Y1188700D02*
X-345000Y1196700D01*
X-342500Y1188700D01*
G01X-343400Y1191500D02*
X-346600D01*
G01X-339300Y1188700D02*
Y1196700D01*
X-334700Y1188700D01*
Y1196700D01*
G01X-329000Y1188700D02*
Y1192300D01*
X-331000Y1196700D01*
G01X-327000D02*
X-329000Y1192300D01*
G01X-315000Y1188700D02*
Y1196700D01*
X-312600D01*
X-311800Y1196300D01*
X-311200Y1195367D01*
X-311000Y1194300D01*
X-311200Y1193233D01*
X-311700Y1192433D01*
X-312600Y1192033D01*
X-315000D01*
G01X-307000Y1188700D02*
Y1196700D01*
X-304500D01*
X-303700Y1196300D01*
X-303200Y1195767D01*
X-303000Y1194700D01*
X-303200Y1193633D01*
X-303800Y1192967D01*
X-304500Y1192567D01*
X-307000D01*
G01X-304500D02*
X-303000Y1188700D01*
G01X-297000D02*
X-297800Y1188833D01*
X-298500Y1189367D01*
X-299100Y1190167D01*
X-299500Y1191100D01*
X-299700Y1192167D01*
Y1193233D01*
X-299500Y1194300D01*
X-299100Y1195233D01*
X-298500Y1196033D01*
X-297800Y1196567D01*
X-297000Y1196700D01*
X-296200Y1196567D01*
X-295500Y1196033D01*
X-294900Y1195233D01*
X-294500Y1194300D01*
X-294300Y1193233D01*
Y1192167D01*
X-294500Y1191100D01*
X-294900Y1190167D01*
X-295500Y1189367D01*
X-296200Y1188833D01*
X-297000Y1188700D01*
G01X-291000D02*
Y1196700D01*
X-288600D01*
X-287800Y1196300D01*
X-287200Y1195367D01*
X-287000Y1194300D01*
X-287200Y1193233D01*
X-287700Y1192433D01*
X-288600Y1192033D01*
X-291000D01*
G01X-281000Y1188700D02*
X-281800Y1188833D01*
X-282500Y1189367D01*
X-283100Y1190167D01*
X-283500Y1191100D01*
X-283700Y1192167D01*
Y1193233D01*
X-283500Y1194300D01*
X-283100Y1195233D01*
X-282500Y1196033D01*
X-281800Y1196567D01*
X-281000Y1196700D01*
X-280200Y1196567D01*
X-279500Y1196033D01*
X-278900Y1195233D01*
X-278500Y1194300D01*
X-278300Y1193233D01*
Y1192167D01*
X-278500Y1191100D01*
X-278900Y1190167D01*
X-279500Y1189367D01*
X-280200Y1188833D01*
X-281000Y1188700D01*
G01X-275100Y1189766D02*
X-274300Y1189100D01*
X-273400Y1188700D01*
X-272600D01*
X-271800Y1189100D01*
X-271200Y1189766D01*
X-270900Y1190700D01*
X-271100Y1191633D01*
X-271600Y1192433D01*
X-272500Y1192967D01*
X-273700Y1193233D01*
X-274400Y1193767D01*
X-274700Y1194700D01*
X-274500Y1195633D01*
X-274000Y1196300D01*
X-273300Y1196700D01*
X-272600D01*
X-271900Y1196433D01*
X-271300Y1195767D01*
G01X-263000Y1188700D02*
X-267000D01*
Y1196700D01*
X-263000D01*
G01X-264600Y1192833D02*
X-267000D01*
G01X-259200Y1188700D02*
Y1196700D01*
X-257200D01*
X-256400Y1196300D01*
X-255800Y1195767D01*
X-255300Y1194967D01*
X-254900Y1194033D01*
X-254800Y1192700D01*
X-254900Y1191367D01*
X-255300Y1190433D01*
X-255800Y1189633D01*
X-256400Y1189100D01*
X-257200Y1188700D01*
X-259200D01*
G01X-238800Y1196033D02*
X-239400Y1196433D01*
X-240100Y1196700D01*
X-240900D01*
X-241800Y1196300D01*
X-242500Y1195633D01*
X-243000Y1194833D01*
X-243400Y1193500D01*
X-243500Y1192300D01*
X-243300Y1191100D01*
X-243000Y1190300D01*
X-242400Y1189500D01*
X-241700Y1188967D01*
X-241000Y1188700D01*
X-240300D01*
X-239600Y1188967D01*
X-239000Y1189367D01*
X-238500Y1189900D01*
G01X-235100Y1188700D02*
Y1196700D01*
G01X-230900D02*
Y1188700D01*
G01Y1192700D02*
X-235100D01*
G01X-227500Y1188700D02*
X-225000Y1196700D01*
X-222500Y1188700D01*
G01X-223400Y1191500D02*
X-226600D01*
G01X-219300Y1188700D02*
Y1196700D01*
X-214700Y1188700D01*
Y1196700D01*
G01X-208400Y1192700D02*
X-206400D01*
Y1190300D01*
X-207000Y1189500D01*
X-207700Y1188967D01*
X-208700Y1188700D01*
X-209700Y1188967D01*
X-210400Y1189500D01*
X-211000Y1190300D01*
X-211400Y1191233D01*
X-211600Y1192300D01*
Y1193233D01*
X-211400Y1194033D01*
X-211000Y1194967D01*
X-210400Y1195767D01*
X-209800Y1196300D01*
X-209000Y1196700D01*
X-208300D01*
X-207500Y1196433D01*
X-206900Y1195900D01*
G01X-199000Y1188700D02*
X-203000D01*
Y1196700D01*
X-199000D01*
G01X-200600Y1192833D02*
X-203000D01*
G01X-187000Y1188700D02*
Y1196700D01*
X-184500D01*
X-183700Y1196300D01*
X-183200Y1195767D01*
X-183000Y1194700D01*
X-183200Y1193633D01*
X-183800Y1192967D01*
X-184500Y1192567D01*
X-187000D01*
G01X-184500D02*
X-183000Y1188700D01*
G01X-175000D02*
X-179000D01*
Y1196700D01*
X-175000D01*
G01X-176600Y1192833D02*
X-179000D01*
G01X-169000Y1188700D02*
X-169800Y1188833D01*
X-170500Y1189367D01*
X-171100Y1190167D01*
X-171500Y1191100D01*
X-171700Y1192167D01*
Y1193233D01*
X-171500Y1194300D01*
X-171100Y1195233D01*
X-170500Y1196033D01*
X-169800Y1196567D01*
X-169000Y1196700D01*
X-168200Y1196567D01*
X-167500Y1196033D01*
X-166900Y1195233D01*
X-166500Y1194300D01*
X-166300Y1193233D01*
Y1192167D01*
X-166500Y1191100D01*
X-166900Y1190167D01*
X-167500Y1189367D01*
X-168200Y1188833D01*
X-169000Y1188700D01*
G01X-168200Y1190833D02*
X-167000Y1188700D01*
G01X-163200Y1196700D02*
Y1190967D01*
X-162800Y1189766D01*
X-162000Y1188967D01*
X-161000Y1188700D01*
X-160000Y1188967D01*
X-159200Y1189766D01*
X-158800Y1190967D01*
Y1196700D01*
G01X-151000Y1188700D02*
X-155000D01*
Y1196700D01*
X-151000D01*
G01X-152600Y1192833D02*
X-155000D01*
G01X-147100Y1189766D02*
X-146300Y1189100D01*
X-145400Y1188700D01*
X-144600D01*
X-143800Y1189100D01*
X-143200Y1189766D01*
X-142900Y1190700D01*
X-143100Y1191633D01*
X-143600Y1192433D01*
X-144500Y1192967D01*
X-145700Y1193233D01*
X-146400Y1193767D01*
X-146700Y1194700D01*
X-146500Y1195633D01*
X-146000Y1196300D01*
X-145300Y1196700D01*
X-144600D01*
X-143900Y1196433D01*
X-143300Y1195767D01*
G01X-137000Y1196700D02*
Y1188700D01*
G01X-139300Y1196700D02*
X-134700D01*
G01X-123600Y1188700D02*
Y1196700D01*
X-121000Y1190033D01*
X-118400Y1196700D01*
Y1188700D01*
G01X-115200Y1196700D02*
Y1190967D01*
X-114800Y1189766D01*
X-114000Y1188967D01*
X-113000Y1188700D01*
X-112000Y1188967D01*
X-111200Y1189766D01*
X-110800Y1190967D01*
Y1196700D01*
G01X-107100Y1189766D02*
X-106300Y1189100D01*
X-105400Y1188700D01*
X-104600D01*
X-103800Y1189100D01*
X-103200Y1189766D01*
X-102900Y1190700D01*
X-103100Y1191633D01*
X-103600Y1192433D01*
X-104500Y1192967D01*
X-105700Y1193233D01*
X-106400Y1193767D01*
X-106700Y1194700D01*
X-106500Y1195633D01*
X-106000Y1196300D01*
X-105300Y1196700D01*
X-104600D01*
X-103900Y1196433D01*
X-103300Y1195767D01*
G01X-97000Y1196700D02*
Y1188700D01*
G01X-99300Y1196700D02*
X-94700D01*
G01X-80200Y1192967D02*
X-79800Y1193367D01*
X-79500Y1194033D01*
X-79300Y1194967D01*
X-79500Y1195767D01*
X-79900Y1196300D01*
X-80600Y1196700D01*
X-83300D01*
Y1188700D01*
X-80000D01*
X-79300Y1189233D01*
X-78900Y1190033D01*
X-78700Y1190967D01*
X-78900Y1191900D01*
X-79500Y1192700D01*
X-80200Y1192967D01*
X-83300D01*
G01X-71000Y1188700D02*
X-75000D01*
Y1196700D01*
X-71000D01*
G01X-72600Y1192833D02*
X-75000D01*
G01X-59500Y1188700D02*
X-57000Y1196700D01*
X-54500Y1188700D01*
G01X-55400Y1191500D02*
X-58600D01*
G01X-51000Y1188700D02*
Y1196700D01*
X-48600D01*
X-47800Y1196300D01*
X-47200Y1195367D01*
X-47000Y1194300D01*
X-47200Y1193233D01*
X-47700Y1192433D01*
X-48600Y1192033D01*
X-51000D01*
G01X-43000Y1188700D02*
Y1196700D01*
X-40600D01*
X-39800Y1196300D01*
X-39200Y1195367D01*
X-39000Y1194300D01*
X-39200Y1193233D01*
X-39700Y1192433D01*
X-40600Y1192033D01*
X-43000D01*
G01X-35000Y1188700D02*
Y1196700D01*
X-32500D01*
X-31700Y1196300D01*
X-31200Y1195767D01*
X-31000Y1194700D01*
X-31200Y1193633D01*
X-31800Y1192967D01*
X-32500Y1192567D01*
X-35000D01*
G01X-32500D02*
X-31000Y1188700D01*
G01X-25000D02*
X-25800Y1188833D01*
X-26500Y1189367D01*
X-27100Y1190167D01*
X-27500Y1191100D01*
X-27700Y1192167D01*
Y1193233D01*
X-27500Y1194300D01*
X-27100Y1195233D01*
X-26500Y1196033D01*
X-25800Y1196567D01*
X-25000Y1196700D01*
X-24200Y1196567D01*
X-23500Y1196033D01*
X-22900Y1195233D01*
X-22500Y1194300D01*
X-22300Y1193233D01*
Y1192167D01*
X-22500Y1191100D01*
X-22900Y1190167D01*
X-23500Y1189367D01*
X-24200Y1188833D01*
X-25000Y1188700D01*
G01X-19500Y1196700D02*
X-17000Y1188700D01*
X-14500Y1196700D01*
G01X-7000Y1188700D02*
X-11000D01*
Y1196700D01*
X-7000D01*
G01X-8600Y1192833D02*
X-11000D01*
G01X-3200Y1188700D02*
Y1196700D01*
X-1200D01*
X-400Y1196300D01*
X200Y1195767D01*
X700Y1194967D01*
X1100Y1194033D01*
X1200Y1192700D01*
X1100Y1191367D01*
X700Y1190433D01*
X200Y1189633D01*
X-400Y1189100D01*
X-1200Y1188700D01*
X-3200D01*
G01X15800Y1192967D02*
X16200Y1193367D01*
X16500Y1194033D01*
X16700Y1194967D01*
X16500Y1195767D01*
X16100Y1196300D01*
X15400Y1196700D01*
X12700D01*
Y1188700D01*
X16000D01*
X16700Y1189233D01*
X17100Y1190033D01*
X17300Y1190967D01*
X17100Y1191900D01*
X16500Y1192700D01*
X15800Y1192967D01*
X12700D01*
G01X23000Y1188700D02*
Y1192300D01*
X21000Y1196700D01*
G01X25000D02*
X23000Y1192300D01*
G01X39000Y1188700D02*
X38200Y1188833D01*
X37500Y1189367D01*
X36900Y1190167D01*
X36500Y1191100D01*
X36300Y1192167D01*
Y1193233D01*
X36500Y1194300D01*
X36900Y1195233D01*
X37500Y1196033D01*
X38200Y1196567D01*
X39000Y1196700D01*
X39800Y1196567D01*
X40500Y1196033D01*
X41100Y1195233D01*
X41500Y1194300D01*
X41700Y1193233D01*
Y1192167D01*
X41500Y1191100D01*
X41100Y1190167D01*
X40500Y1189367D01*
X39800Y1188833D01*
X39000Y1188700D01*
G01X39800Y1190833D02*
X41000Y1188700D01*
G01X44800Y1196700D02*
Y1190967D01*
X45200Y1189766D01*
X46000Y1188967D01*
X47000Y1188700D01*
X48000Y1188967D01*
X48800Y1189766D01*
X49200Y1190967D01*
Y1196700D01*
G01X52500Y1188700D02*
X55000Y1196700D01*
X57500Y1188700D01*
G01X56600Y1191500D02*
X53400D01*
G01X60700Y1188700D02*
Y1196700D01*
X65300Y1188700D01*
Y1196700D01*
G01X71000D02*
Y1188700D01*
G01X68700Y1196700D02*
X73300D01*
G01X76500Y1188700D02*
X79000Y1196700D01*
X81500Y1188700D01*
G01X80600Y1191500D02*
X77400D01*
G01X93000Y1188700D02*
Y1196700D01*
X95400D01*
X96200Y1196300D01*
X96800Y1195367D01*
X97000Y1194300D01*
X96800Y1193233D01*
X96300Y1192433D01*
X95400Y1192033D01*
X93000D01*
G01X101000Y1188700D02*
Y1196700D01*
X103500D01*
X104300Y1196300D01*
X104800Y1195767D01*
X105000Y1194700D01*
X104800Y1193633D01*
X104200Y1192967D01*
X103500Y1192567D01*
X101000D01*
G01X103500D02*
X105000Y1188700D01*
G01X109800Y1196700D02*
X112200D01*
G01X111000D02*
Y1188700D01*
G01X109800D02*
X112200D01*
G01X119000D02*
X118200Y1188833D01*
X117500Y1189367D01*
X116900Y1190167D01*
X116500Y1191100D01*
X116300Y1192167D01*
Y1193233D01*
X116500Y1194300D01*
X116900Y1195233D01*
X117500Y1196033D01*
X118200Y1196567D01*
X119000Y1196700D01*
X119800Y1196567D01*
X120500Y1196033D01*
X121100Y1195233D01*
X121500Y1194300D01*
X121700Y1193233D01*
Y1192167D01*
X121500Y1191100D01*
X121100Y1190167D01*
X120500Y1189367D01*
X119800Y1188833D01*
X119000Y1188700D01*
G01X125000D02*
Y1196700D01*
X127500D01*
X128300Y1196300D01*
X128800Y1195767D01*
X129000Y1194700D01*
X128800Y1193633D01*
X128200Y1192967D01*
X127500Y1192567D01*
X125000D01*
G01X127500D02*
X129000Y1188700D01*
G01X143000Y1196700D02*
Y1188700D01*
G01X140700Y1196700D02*
X145300D01*
G01X151000Y1188700D02*
X150200Y1188833D01*
X149500Y1189367D01*
X148900Y1190167D01*
X148500Y1191100D01*
X148300Y1192167D01*
Y1193233D01*
X148500Y1194300D01*
X148900Y1195233D01*
X149500Y1196033D01*
X150200Y1196567D01*
X151000Y1196700D01*
X151800Y1196567D01*
X152500Y1196033D01*
X153100Y1195233D01*
X153500Y1194300D01*
X153700Y1193233D01*
Y1192167D01*
X153500Y1191100D01*
X153100Y1190167D01*
X152500Y1189367D01*
X151800Y1188833D01*
X151000Y1188700D01*
G01X165800Y1196700D02*
X168200D01*
G01X167000D02*
Y1188700D01*
G01X165800D02*
X168200D01*
G01X175000Y1196700D02*
Y1188700D01*
G01X172700Y1196700D02*
X177300D01*
G01X180900Y1189766D02*
X181700Y1189100D01*
X182600Y1188700D01*
X183400D01*
X184200Y1189100D01*
X184800Y1189766D01*
X185100Y1190700D01*
X184900Y1191633D01*
X184400Y1192433D01*
X183500Y1192967D01*
X182300Y1193233D01*
X181600Y1193767D01*
X181300Y1194700D01*
X181500Y1195633D01*
X182000Y1196300D01*
X182700Y1196700D01*
X183400D01*
X184100Y1196433D01*
X184700Y1195767D01*
G01X197800Y1196700D02*
X200200D01*
G01X199000D02*
Y1188700D01*
G01X197800D02*
X200200D01*
G01X204400D02*
Y1196700D01*
X207000Y1190033D01*
X209600Y1196700D01*
Y1188700D01*
G01X213000D02*
Y1196700D01*
X215400D01*
X216200Y1196300D01*
X216800Y1195367D01*
X217000Y1194300D01*
X216800Y1193233D01*
X216300Y1192433D01*
X215400Y1192033D01*
X213000D01*
G01X221000Y1196700D02*
Y1188700D01*
X225000D01*
G01X233000D02*
X229000D01*
Y1196700D01*
X233000D01*
G01X231400Y1192833D02*
X229000D01*
G01X236400Y1188700D02*
Y1196700D01*
X239000Y1190033D01*
X241600Y1196700D01*
Y1188700D01*
G01X249000D02*
X245000D01*
Y1196700D01*
X249000D01*
G01X247400Y1192833D02*
X245000D01*
G01X252700Y1188700D02*
Y1196700D01*
X257300Y1188700D01*
Y1196700D01*
G01X263000D02*
Y1188700D01*
G01X260700Y1196700D02*
X265300D01*
G01X268500Y1188700D02*
X271000Y1196700D01*
X273500Y1188700D01*
G01X272600Y1191500D02*
X269400D01*
G01X279000Y1196700D02*
Y1188700D01*
G01X276700Y1196700D02*
X281300D01*
G01X285800D02*
X288200D01*
G01X287000D02*
Y1188700D01*
G01X285800D02*
X288200D01*
G01X295000D02*
X294200Y1188833D01*
X293500Y1189367D01*
X292900Y1190167D01*
X292500Y1191100D01*
X292300Y1192167D01*
Y1193233D01*
X292500Y1194300D01*
X292900Y1195233D01*
X293500Y1196033D01*
X294200Y1196567D01*
X295000Y1196700D01*
X295800Y1196567D01*
X296500Y1196033D01*
X297100Y1195233D01*
X297500Y1194300D01*
X297700Y1193233D01*
Y1192167D01*
X297500Y1191100D01*
X297100Y1190167D01*
X296500Y1189367D01*
X295800Y1188833D01*
X295000Y1188700D01*
G01X300700D02*
Y1196700D01*
X305300Y1188700D01*
Y1196700D01*
G01X311000Y1188433D02*
X310800Y1188567D01*
Y1188833D01*
X311000Y1188967D01*
X311200Y1188833D01*
Y1188567D01*
X311000Y1188433D01*
G01X-346200Y1211700D02*
X-343800D01*
G01X-345000D02*
Y1203700D01*
G01X-346200D02*
X-343800D01*
G01X-339600D02*
Y1211700D01*
X-337000Y1205033D01*
X-334400Y1211700D01*
Y1203700D01*
G01X-331000D02*
Y1211700D01*
X-328600D01*
X-327800Y1211300D01*
X-327200Y1210367D01*
X-327000Y1209300D01*
X-327200Y1208233D01*
X-327700Y1207433D01*
X-328600Y1207033D01*
X-331000D01*
G01X-319000Y1203700D02*
X-323000D01*
Y1211700D01*
X-319000D01*
G01X-320600Y1207833D02*
X-323000D01*
G01X-315200Y1203700D02*
Y1211700D01*
X-313200D01*
X-312400Y1211300D01*
X-311800Y1210767D01*
X-311300Y1209967D01*
X-310900Y1209033D01*
X-310800Y1207700D01*
X-310900Y1206367D01*
X-311300Y1205433D01*
X-311800Y1204633D01*
X-312400Y1204100D01*
X-313200Y1203700D01*
X-315200D01*
G01X-307500D02*
X-305000Y1211700D01*
X-302500Y1203700D01*
G01X-303400Y1206500D02*
X-306600D01*
G01X-299300Y1203700D02*
Y1211700D01*
X-294700Y1203700D01*
Y1211700D01*
G01X-286800Y1211033D02*
X-287400Y1211433D01*
X-288100Y1211700D01*
X-288900D01*
X-289800Y1211300D01*
X-290500Y1210633D01*
X-291000Y1209833D01*
X-291400Y1208500D01*
X-291500Y1207300D01*
X-291300Y1206100D01*
X-291000Y1205300D01*
X-290400Y1204500D01*
X-289700Y1203967D01*
X-289000Y1203700D01*
X-288300D01*
X-287600Y1203967D01*
X-287000Y1204367D01*
X-286500Y1204900D01*
G01X-279000Y1203700D02*
X-283000D01*
Y1211700D01*
X-279000D01*
G01X-280600Y1207833D02*
X-283000D01*
G01X-275100Y1204766D02*
X-274300Y1204100D01*
X-273400Y1203700D01*
X-272600D01*
X-271800Y1204100D01*
X-271200Y1204766D01*
X-270900Y1205700D01*
X-271100Y1206633D01*
X-271600Y1207433D01*
X-272500Y1207967D01*
X-273700Y1208233D01*
X-274400Y1208767D01*
X-274700Y1209700D01*
X-274500Y1210633D01*
X-274000Y1211300D01*
X-273300Y1211700D01*
X-272600D01*
X-271900Y1211433D01*
X-271300Y1210767D01*
G01X-259500Y1203700D02*
X-257000Y1211700D01*
X-254500Y1203700D01*
G01X-255400Y1206500D02*
X-258600D01*
G01X-251300Y1203700D02*
Y1211700D01*
X-246700Y1203700D01*
Y1211700D01*
G01X-243200Y1203700D02*
Y1211700D01*
X-241200D01*
X-240400Y1211300D01*
X-239800Y1210767D01*
X-239300Y1209967D01*
X-238900Y1209033D01*
X-238800Y1207700D01*
X-238900Y1206367D01*
X-239300Y1205433D01*
X-239800Y1204633D01*
X-240400Y1204100D01*
X-241200Y1203700D01*
X-243200D01*
G01X-224200Y1207967D02*
X-223800Y1208367D01*
X-223500Y1209033D01*
X-223300Y1209967D01*
X-223500Y1210767D01*
X-223900Y1211300D01*
X-224600Y1211700D01*
X-227300D01*
Y1203700D01*
X-224000D01*
X-223300Y1204233D01*
X-222900Y1205033D01*
X-222700Y1205967D01*
X-222900Y1206900D01*
X-223500Y1207700D01*
X-224200Y1207967D01*
X-227300D01*
G01X-217000Y1203700D02*
X-217800Y1203833D01*
X-218500Y1204367D01*
X-219100Y1205167D01*
X-219500Y1206100D01*
X-219700Y1207167D01*
Y1208233D01*
X-219500Y1209300D01*
X-219100Y1210233D01*
X-218500Y1211033D01*
X-217800Y1211567D01*
X-217000Y1211700D01*
X-216200Y1211567D01*
X-215500Y1211033D01*
X-214900Y1210233D01*
X-214500Y1209300D01*
X-214300Y1208233D01*
Y1207167D01*
X-214500Y1206100D01*
X-214900Y1205167D01*
X-215500Y1204367D01*
X-216200Y1203833D01*
X-217000Y1203700D01*
G01X-211500D02*
X-209000Y1211700D01*
X-206500Y1203700D01*
G01X-207400Y1206500D02*
X-210600D01*
G01X-203000Y1203700D02*
Y1211700D01*
X-200500D01*
X-199700Y1211300D01*
X-199200Y1210767D01*
X-199000Y1209700D01*
X-199200Y1208633D01*
X-199800Y1207967D01*
X-200500Y1207567D01*
X-203000D01*
G01X-200500D02*
X-199000Y1203700D01*
G01X-195200D02*
Y1211700D01*
X-193200D01*
X-192400Y1211300D01*
X-191800Y1210767D01*
X-191300Y1209967D01*
X-190900Y1209033D01*
X-190800Y1207700D01*
X-190900Y1206367D01*
X-191300Y1205433D01*
X-191800Y1204633D01*
X-192400Y1204100D01*
X-193200Y1203700D01*
X-195200D01*
G01X-177000Y1211700D02*
Y1203700D01*
G01X-179300Y1211700D02*
X-174700D01*
G01X-171100Y1203700D02*
Y1211700D01*
G01X-166900D02*
Y1203700D01*
G01Y1207700D02*
X-171100D01*
G01X-162200Y1211700D02*
X-159800D01*
G01X-161000D02*
Y1203700D01*
G01X-162200D02*
X-159800D01*
G01X-150800Y1211033D02*
X-151400Y1211433D01*
X-152100Y1211700D01*
X-152900D01*
X-153800Y1211300D01*
X-154500Y1210633D01*
X-155000Y1209833D01*
X-155400Y1208500D01*
X-155500Y1207300D01*
X-155300Y1206100D01*
X-155000Y1205300D01*
X-154400Y1204500D01*
X-153700Y1203967D01*
X-153000Y1203700D01*
X-152300D01*
X-151600Y1203967D01*
X-151000Y1204367D01*
X-150500Y1204900D01*
G01X-147200Y1203700D02*
Y1211700D01*
G01X-143400D02*
X-147200Y1206766D01*
G01X-142800Y1203700D02*
X-145500Y1209033D01*
G01X-139300Y1203700D02*
Y1211700D01*
X-134700Y1203700D01*
Y1211700D01*
G01X-127000Y1203700D02*
X-131000D01*
Y1211700D01*
X-127000D01*
G01X-128600Y1207833D02*
X-131000D01*
G01X-123100Y1204766D02*
X-122300Y1204100D01*
X-121400Y1203700D01*
X-120600D01*
X-119800Y1204100D01*
X-119200Y1204766D01*
X-118900Y1205700D01*
X-119100Y1206633D01*
X-119600Y1207433D01*
X-120500Y1207967D01*
X-121700Y1208233D01*
X-122400Y1208767D01*
X-122700Y1209700D01*
X-122500Y1210633D01*
X-122000Y1211300D01*
X-121300Y1211700D01*
X-120600D01*
X-119900Y1211433D01*
X-119300Y1210767D01*
G01X-115100Y1204766D02*
X-114300Y1204100D01*
X-113400Y1203700D01*
X-112600D01*
X-111800Y1204100D01*
X-111200Y1204766D01*
X-110900Y1205700D01*
X-111100Y1206633D01*
X-111600Y1207433D01*
X-112500Y1207967D01*
X-113700Y1208233D01*
X-114400Y1208767D01*
X-114700Y1209700D01*
X-114500Y1210633D01*
X-114000Y1211300D01*
X-113300Y1211700D01*
X-112600D01*
X-111900Y1211433D01*
X-111300Y1210767D01*
G01X-105000Y1203433D02*
X-105200Y1203567D01*
Y1203833D01*
X-105000Y1203967D01*
X-104800Y1203833D01*
Y1203567D01*
X-105000Y1203433D01*
G01X-347100Y1219766D02*
X-346300Y1219100D01*
X-345400Y1218700D01*
X-344600D01*
X-343800Y1219100D01*
X-343200Y1219766D01*
X-342900Y1220700D01*
X-343100Y1221633D01*
X-343600Y1222433D01*
X-344500Y1222967D01*
X-345700Y1223233D01*
X-346400Y1223767D01*
X-346700Y1224700D01*
X-346500Y1225633D01*
X-346000Y1226300D01*
X-345300Y1226700D01*
X-344600D01*
X-343900Y1226433D01*
X-343300Y1225767D01*
G01X-339000Y1218700D02*
Y1226700D01*
X-336600D01*
X-335800Y1226300D01*
X-335200Y1225367D01*
X-335000Y1224300D01*
X-335200Y1223233D01*
X-335700Y1222433D01*
X-336600Y1222033D01*
X-339000D01*
G01X-331500Y1218700D02*
X-329000Y1226700D01*
X-326500Y1218700D01*
G01X-327400Y1221500D02*
X-330600D01*
G01X-318800Y1226033D02*
X-319400Y1226433D01*
X-320100Y1226700D01*
X-320900D01*
X-321800Y1226300D01*
X-322500Y1225633D01*
X-323000Y1224833D01*
X-323400Y1223500D01*
X-323500Y1222300D01*
X-323300Y1221100D01*
X-323000Y1220300D01*
X-322400Y1219500D01*
X-321700Y1218967D01*
X-321000Y1218700D01*
X-320300D01*
X-319600Y1218967D01*
X-319000Y1219367D01*
X-318500Y1219900D01*
G01X-314200Y1226700D02*
X-311800D01*
G01X-313000D02*
Y1218700D01*
G01X-314200D02*
X-311800D01*
G01X-307300D02*
Y1226700D01*
X-302700Y1218700D01*
Y1226700D01*
G01X-296400Y1222700D02*
X-294400D01*
Y1220300D01*
X-295000Y1219500D01*
X-295700Y1218967D01*
X-296700Y1218700D01*
X-297700Y1218967D01*
X-298400Y1219500D01*
X-299000Y1220300D01*
X-299400Y1221233D01*
X-299600Y1222300D01*
Y1223233D01*
X-299400Y1224033D01*
X-299000Y1224967D01*
X-298400Y1225767D01*
X-297800Y1226300D01*
X-297000Y1226700D01*
X-296300D01*
X-295500Y1226433D01*
X-294900Y1225900D01*
G01X-283500Y1218700D02*
X-281000Y1226700D01*
X-278500Y1218700D01*
G01X-279400Y1221500D02*
X-282600D01*
G01X-275300Y1218700D02*
Y1226700D01*
X-270700Y1218700D01*
Y1226700D01*
G01X-267200Y1218700D02*
Y1226700D01*
X-265200D01*
X-264400Y1226300D01*
X-263800Y1225767D01*
X-263300Y1224967D01*
X-262900Y1224033D01*
X-262800Y1222700D01*
X-262900Y1221367D01*
X-263300Y1220433D01*
X-263800Y1219633D01*
X-264400Y1219100D01*
X-265200Y1218700D01*
X-267200D01*
G01X-251600D02*
Y1226700D01*
X-249000Y1220033D01*
X-246400Y1226700D01*
Y1218700D01*
G01X-243500D02*
X-241000Y1226700D01*
X-238500Y1218700D01*
G01X-239400Y1221500D02*
X-242600D01*
G01X-233000Y1226700D02*
Y1218700D01*
G01X-235300Y1226700D02*
X-230700D01*
G01X-223000Y1218700D02*
X-227000D01*
Y1226700D01*
X-223000D01*
G01X-224600Y1222833D02*
X-227000D01*
G01X-219000Y1218700D02*
Y1226700D01*
X-216500D01*
X-215700Y1226300D01*
X-215200Y1225767D01*
X-215000Y1224700D01*
X-215200Y1223633D01*
X-215800Y1222967D01*
X-216500Y1222567D01*
X-219000D01*
G01X-216500D02*
X-215000Y1218700D01*
G01X-210200Y1226700D02*
X-207800D01*
G01X-209000D02*
Y1218700D01*
G01X-210200D02*
X-207800D01*
G01X-203500D02*
X-201000Y1226700D01*
X-198500Y1218700D01*
G01X-199400Y1221500D02*
X-202600D01*
G01X-195000Y1226700D02*
Y1218700D01*
X-191000D01*
G01X-179200D02*
Y1226700D01*
X-177200D01*
X-176400Y1226300D01*
X-175800Y1225767D01*
X-175300Y1224967D01*
X-174900Y1224033D01*
X-174800Y1222700D01*
X-174900Y1221367D01*
X-175300Y1220433D01*
X-175800Y1219633D01*
X-176400Y1219100D01*
X-177200Y1218700D01*
X-179200D01*
G01X-170200Y1226700D02*
X-167800D01*
G01X-169000D02*
Y1218700D01*
G01X-170200D02*
X-167800D01*
G01X-159000D02*
X-163000D01*
Y1226700D01*
X-159000D01*
G01X-160600Y1222833D02*
X-163000D01*
G01X-155000Y1226700D02*
Y1218700D01*
X-151000D01*
G01X-143000D02*
X-147000D01*
Y1226700D01*
X-143000D01*
G01X-144600Y1222833D02*
X-147000D01*
G01X-134800Y1226033D02*
X-135400Y1226433D01*
X-136100Y1226700D01*
X-136900D01*
X-137800Y1226300D01*
X-138500Y1225633D01*
X-139000Y1224833D01*
X-139400Y1223500D01*
X-139500Y1222300D01*
X-139300Y1221100D01*
X-139000Y1220300D01*
X-138400Y1219500D01*
X-137700Y1218967D01*
X-137000Y1218700D01*
X-136300D01*
X-135600Y1218967D01*
X-135000Y1219367D01*
X-134500Y1219900D01*
G01X-129000Y1226700D02*
Y1218700D01*
G01X-131300Y1226700D02*
X-126700D01*
G01X-123000Y1218700D02*
Y1226700D01*
X-120500D01*
X-119700Y1226300D01*
X-119200Y1225767D01*
X-119000Y1224700D01*
X-119200Y1223633D01*
X-119800Y1222967D01*
X-120500Y1222567D01*
X-123000D01*
G01X-120500D02*
X-119000Y1218700D01*
G01X-114200Y1226700D02*
X-111800D01*
G01X-113000D02*
Y1218700D01*
G01X-114200D02*
X-111800D01*
G01X-102800Y1226033D02*
X-103400Y1226433D01*
X-104100Y1226700D01*
X-104900D01*
X-105800Y1226300D01*
X-106500Y1225633D01*
X-107000Y1224833D01*
X-107400Y1223500D01*
X-107500Y1222300D01*
X-107300Y1221100D01*
X-107000Y1220300D01*
X-106400Y1219500D01*
X-105700Y1218967D01*
X-105000Y1218700D01*
X-104300D01*
X-103600Y1218967D01*
X-103000Y1219367D01*
X-102500Y1219900D01*
G01X-86800Y1226033D02*
X-87400Y1226433D01*
X-88100Y1226700D01*
X-88900D01*
X-89800Y1226300D01*
X-90500Y1225633D01*
X-91000Y1224833D01*
X-91400Y1223500D01*
X-91500Y1222300D01*
X-91300Y1221100D01*
X-91000Y1220300D01*
X-90400Y1219500D01*
X-89700Y1218967D01*
X-89000Y1218700D01*
X-88300D01*
X-87600Y1218967D01*
X-87000Y1219367D01*
X-86500Y1219900D01*
G01X-81000Y1218700D02*
X-81800Y1218833D01*
X-82500Y1219367D01*
X-83100Y1220167D01*
X-83500Y1221100D01*
X-83700Y1222167D01*
Y1223233D01*
X-83500Y1224300D01*
X-83100Y1225233D01*
X-82500Y1226033D01*
X-81800Y1226567D01*
X-81000Y1226700D01*
X-80200Y1226567D01*
X-79500Y1226033D01*
X-78900Y1225233D01*
X-78500Y1224300D01*
X-78300Y1223233D01*
Y1222167D01*
X-78500Y1221100D01*
X-78900Y1220167D01*
X-79500Y1219367D01*
X-80200Y1218833D01*
X-81000Y1218700D01*
G01X-75300D02*
Y1226700D01*
X-70700Y1218700D01*
Y1226700D01*
G01X-67100Y1219766D02*
X-66300Y1219100D01*
X-65400Y1218700D01*
X-64600D01*
X-63800Y1219100D01*
X-63200Y1219766D01*
X-62900Y1220700D01*
X-63100Y1221633D01*
X-63600Y1222433D01*
X-64500Y1222967D01*
X-65700Y1223233D01*
X-66400Y1223767D01*
X-66700Y1224700D01*
X-66500Y1225633D01*
X-66000Y1226300D01*
X-65300Y1226700D01*
X-64600D01*
X-63900Y1226433D01*
X-63300Y1225767D01*
G01X-57000Y1226700D02*
Y1218700D01*
G01X-59300Y1226700D02*
X-54700D01*
G01X-51500Y1218700D02*
X-49000Y1226700D01*
X-46500Y1218700D01*
G01X-47400Y1221500D02*
X-50600D01*
G01X-43300Y1218700D02*
Y1226700D01*
X-38700Y1218700D01*
Y1226700D01*
G01X-33000D02*
Y1218700D01*
G01X-35300Y1226700D02*
X-30700D01*
G01X-17000D02*
Y1218700D01*
G01X-19300Y1226700D02*
X-14700D01*
G01X-9000Y1218700D02*
X-9800Y1218833D01*
X-10500Y1219367D01*
X-11100Y1220167D01*
X-11500Y1221100D01*
X-11700Y1222167D01*
Y1223233D01*
X-11500Y1224300D01*
X-11100Y1225233D01*
X-10500Y1226033D01*
X-9800Y1226567D01*
X-9000Y1226700D01*
X-8200Y1226567D01*
X-7500Y1226033D01*
X-6900Y1225233D01*
X-6500Y1224300D01*
X-6300Y1223233D01*
Y1222167D01*
X-6500Y1221100D01*
X-6900Y1220167D01*
X-7500Y1219367D01*
X-8200Y1218833D01*
X-9000Y1218700D01*
G01X4500D02*
X7000Y1226700D01*
X9500Y1218700D01*
G01X8600Y1221500D02*
X5400D01*
G01X17200Y1226033D02*
X16600Y1226433D01*
X15900Y1226700D01*
X15100D01*
X14200Y1226300D01*
X13500Y1225633D01*
X13000Y1224833D01*
X12600Y1223500D01*
X12500Y1222300D01*
X12700Y1221100D01*
X13000Y1220300D01*
X13600Y1219500D01*
X14300Y1218967D01*
X15000Y1218700D01*
X15700D01*
X16400Y1218967D01*
X17000Y1219367D01*
X17500Y1219900D01*
G01X20900Y1218700D02*
Y1226700D01*
G01X25100D02*
Y1218700D01*
G01Y1222700D02*
X20900D01*
G01X29800Y1226700D02*
X32200D01*
G01X31000D02*
Y1218700D01*
G01X29800D02*
X32200D01*
G01X41000D02*
X37000D01*
Y1226700D01*
X41000D01*
G01X39400Y1222833D02*
X37000D01*
G01X44500Y1226700D02*
X47000Y1218700D01*
X49500Y1226700D01*
G01X57000Y1218700D02*
X53000D01*
Y1226700D01*
X57000D01*
G01X55400Y1222833D02*
X53000D01*
G01X69000Y1218700D02*
Y1226700D01*
X71500D01*
X72300Y1226300D01*
X72800Y1225767D01*
X73000Y1224700D01*
X72800Y1223633D01*
X72200Y1222967D01*
X71500Y1222567D01*
X69000D01*
G01X71500D02*
X73000Y1218700D01*
G01X81000D02*
X77000D01*
Y1226700D01*
X81000D01*
G01X79400Y1222833D02*
X77000D01*
G01X87000Y1218700D02*
X86200Y1218833D01*
X85500Y1219367D01*
X84900Y1220167D01*
X84500Y1221100D01*
X84300Y1222167D01*
Y1223233D01*
X84500Y1224300D01*
X84900Y1225233D01*
X85500Y1226033D01*
X86200Y1226567D01*
X87000Y1226700D01*
X87800Y1226567D01*
X88500Y1226033D01*
X89100Y1225233D01*
X89500Y1224300D01*
X89700Y1223233D01*
Y1222167D01*
X89500Y1221100D01*
X89100Y1220167D01*
X88500Y1219367D01*
X87800Y1218833D01*
X87000Y1218700D01*
G01X87800Y1220833D02*
X89000Y1218700D01*
G01X92800Y1226700D02*
Y1220967D01*
X93200Y1219766D01*
X94000Y1218967D01*
X95000Y1218700D01*
X96000Y1218967D01*
X96800Y1219766D01*
X97200Y1220967D01*
Y1226700D01*
G01X101800D02*
X104200D01*
G01X103000D02*
Y1218700D01*
G01X101800D02*
X104200D01*
G01X109000D02*
Y1226700D01*
X111500D01*
X112300Y1226300D01*
X112800Y1225767D01*
X113000Y1224700D01*
X112800Y1223633D01*
X112200Y1222967D01*
X111500Y1222567D01*
X109000D01*
G01X111500D02*
X113000Y1218700D01*
G01X121000D02*
X117000D01*
Y1226700D01*
X121000D01*
G01X119400Y1222833D02*
X117000D01*
G01X124800Y1218700D02*
Y1226700D01*
X126800D01*
X127600Y1226300D01*
X128200Y1225767D01*
X128700Y1224967D01*
X129100Y1224033D01*
X129200Y1222700D01*
X129100Y1221367D01*
X128700Y1220433D01*
X128200Y1219633D01*
X127600Y1219100D01*
X126800Y1218700D01*
X124800D01*
G01X-342800Y1241033D02*
X-343400Y1241433D01*
X-344100Y1241700D01*
X-344900D01*
X-345800Y1241300D01*
X-346500Y1240633D01*
X-347000Y1239833D01*
X-347400Y1238500D01*
X-347500Y1237300D01*
X-347300Y1236100D01*
X-347000Y1235300D01*
X-346400Y1234500D01*
X-345700Y1233967D01*
X-345000Y1233700D01*
X-344300D01*
X-343600Y1233967D01*
X-343000Y1234367D01*
X-342500Y1234900D01*
G01X-339100Y1233700D02*
Y1241700D01*
G01X-334900D02*
Y1233700D01*
G01Y1237700D02*
X-339100D01*
G01X-331500Y1233700D02*
X-329000Y1241700D01*
X-326500Y1233700D01*
G01X-327400Y1236500D02*
X-330600D01*
G01X-323000Y1233700D02*
Y1241700D01*
X-320500D01*
X-319700Y1241300D01*
X-319200Y1240767D01*
X-319000Y1239700D01*
X-319200Y1238633D01*
X-319800Y1237967D01*
X-320500Y1237567D01*
X-323000D01*
G01X-320500D02*
X-319000Y1233700D01*
G01X-313000Y1241700D02*
Y1233700D01*
G01X-315300Y1241700D02*
X-310700D01*
G01X-305000Y1233433D02*
X-305200Y1233567D01*
Y1233833D01*
X-305000Y1233967D01*
X-304800Y1233833D01*
Y1233567D01*
X-305000Y1233433D01*
G01X-291600Y1233700D02*
Y1241700D01*
X-289000Y1235033D01*
X-286400Y1241700D01*
Y1233700D01*
G01X-283500D02*
X-281000Y1241700D01*
X-278500Y1233700D01*
G01X-279400Y1236500D02*
X-282600D01*
G01X-275300Y1233700D02*
Y1241700D01*
X-270700Y1233700D01*
Y1241700D01*
G01X-267200D02*
Y1235967D01*
X-266800Y1234766D01*
X-266000Y1233967D01*
X-265000Y1233700D01*
X-264000Y1233967D01*
X-263200Y1234766D01*
X-262800Y1235967D01*
Y1241700D01*
G01X-258900Y1233700D02*
Y1241700D01*
X-255100D01*
G01X-256500Y1237833D02*
X-258900D01*
G01X-251500Y1233700D02*
X-249000Y1241700D01*
X-246500Y1233700D01*
G01X-247400Y1236500D02*
X-250600D01*
G01X-238800Y1241033D02*
X-239400Y1241433D01*
X-240100Y1241700D01*
X-240900D01*
X-241800Y1241300D01*
X-242500Y1240633D01*
X-243000Y1239833D01*
X-243400Y1238500D01*
X-243500Y1237300D01*
X-243300Y1236100D01*
X-243000Y1235300D01*
X-242400Y1234500D01*
X-241700Y1233967D01*
X-241000Y1233700D01*
X-240300D01*
X-239600Y1233967D01*
X-239000Y1234367D01*
X-238500Y1234900D01*
G01X-233000Y1241700D02*
Y1233700D01*
G01X-235300Y1241700D02*
X-230700D01*
G01X-227200D02*
Y1235967D01*
X-226800Y1234766D01*
X-226000Y1233967D01*
X-225000Y1233700D01*
X-224000Y1233967D01*
X-223200Y1234766D01*
X-222800Y1235967D01*
Y1241700D01*
G01X-219000Y1233700D02*
Y1241700D01*
X-216500D01*
X-215700Y1241300D01*
X-215200Y1240767D01*
X-215000Y1239700D01*
X-215200Y1238633D01*
X-215800Y1237967D01*
X-216500Y1237567D01*
X-219000D01*
G01X-216500D02*
X-215000Y1233700D01*
G01X-207000D02*
X-211000D01*
Y1241700D01*
X-207000D01*
G01X-208600Y1237833D02*
X-211000D01*
G01X-203000Y1233700D02*
Y1241700D01*
X-200500D01*
X-199700Y1241300D01*
X-199200Y1240767D01*
X-199000Y1239700D01*
X-199200Y1238633D01*
X-199800Y1237967D01*
X-200500Y1237567D01*
X-203000D01*
G01X-200500D02*
X-199000Y1233700D01*
G01X-186200Y1241700D02*
X-183800D01*
G01X-185000D02*
Y1233700D01*
G01X-186200D02*
X-183800D01*
G01X-179100Y1234766D02*
X-178300Y1234100D01*
X-177400Y1233700D01*
X-176600D01*
X-175800Y1234100D01*
X-175200Y1234766D01*
X-174900Y1235700D01*
X-175100Y1236633D01*
X-175600Y1237433D01*
X-176500Y1237967D01*
X-177700Y1238233D01*
X-178400Y1238767D01*
X-178700Y1239700D01*
X-178500Y1240633D01*
X-178000Y1241300D01*
X-177300Y1241700D01*
X-176600D01*
X-175900Y1241433D01*
X-175300Y1240767D01*
G01X-162900Y1233700D02*
Y1241700D01*
X-159100D01*
G01X-160500Y1237833D02*
X-162900D01*
G01X-155000Y1233700D02*
Y1241700D01*
X-152500D01*
X-151700Y1241300D01*
X-151200Y1240767D01*
X-151000Y1239700D01*
X-151200Y1238633D01*
X-151800Y1237967D01*
X-152500Y1237567D01*
X-155000D01*
G01X-152500D02*
X-151000Y1233700D01*
G01X-143000D02*
X-147000D01*
Y1241700D01*
X-143000D01*
G01X-144600Y1237833D02*
X-147000D01*
G01X-135000Y1233700D02*
X-139000D01*
Y1241700D01*
X-135000D01*
G01X-136600Y1237833D02*
X-139000D01*
G01X-121000Y1241700D02*
Y1233700D01*
G01X-123300Y1241700D02*
X-118700D01*
G01X-113000Y1233700D02*
X-113800Y1233833D01*
X-114500Y1234367D01*
X-115100Y1235167D01*
X-115500Y1236100D01*
X-115700Y1237167D01*
Y1238233D01*
X-115500Y1239300D01*
X-115100Y1240233D01*
X-114500Y1241033D01*
X-113800Y1241567D01*
X-113000Y1241700D01*
X-112200Y1241567D01*
X-111500Y1241033D01*
X-110900Y1240233D01*
X-110500Y1239300D01*
X-110300Y1238233D01*
Y1237167D01*
X-110500Y1236100D01*
X-110900Y1235167D01*
X-111500Y1234367D01*
X-112200Y1233833D01*
X-113000Y1233700D01*
G01X-99500D02*
X-97000Y1241700D01*
X-94500Y1233700D01*
G01X-95400Y1236500D02*
X-98600D01*
G01X-91200Y1233700D02*
Y1241700D01*
X-89200D01*
X-88400Y1241300D01*
X-87800Y1240767D01*
X-87300Y1239967D01*
X-86900Y1239033D01*
X-86800Y1237700D01*
X-86900Y1236367D01*
X-87300Y1235433D01*
X-87800Y1234633D01*
X-88400Y1234100D01*
X-89200Y1233700D01*
X-91200D01*
G01X-83000Y1235300D02*
X-82500Y1234500D01*
X-81900Y1233967D01*
X-81200Y1233700D01*
X-80400Y1233967D01*
X-79800Y1234500D01*
X-79200Y1235300D01*
X-79000Y1236367D01*
Y1241700D01*
G01X-75200D02*
Y1235967D01*
X-74800Y1234766D01*
X-74000Y1233967D01*
X-73000Y1233700D01*
X-72000Y1233967D01*
X-71200Y1234766D01*
X-70800Y1235967D01*
Y1241700D01*
G01X-67100Y1234766D02*
X-66300Y1234100D01*
X-65400Y1233700D01*
X-64600D01*
X-63800Y1234100D01*
X-63200Y1234766D01*
X-62900Y1235700D01*
X-63100Y1236633D01*
X-63600Y1237433D01*
X-64500Y1237967D01*
X-65700Y1238233D01*
X-66400Y1238767D01*
X-66700Y1239700D01*
X-66500Y1240633D01*
X-66000Y1241300D01*
X-65300Y1241700D01*
X-64600D01*
X-63900Y1241433D01*
X-63300Y1240767D01*
G01X-57000Y1241700D02*
Y1233700D01*
G01X-59300Y1241700D02*
X-54700D01*
G01X-41000D02*
Y1233700D01*
G01X-43300Y1241700D02*
X-38700D01*
G01X-35000Y1233700D02*
Y1241700D01*
X-32500D01*
X-31700Y1241300D01*
X-31200Y1240767D01*
X-31000Y1239700D01*
X-31200Y1238633D01*
X-31800Y1237967D01*
X-32500Y1237567D01*
X-35000D01*
G01X-32500D02*
X-31000Y1233700D01*
G01X-27500D02*
X-25000Y1241700D01*
X-22500Y1233700D01*
G01X-23400Y1236500D02*
X-26600D01*
G01X-14800Y1241033D02*
X-15400Y1241433D01*
X-16100Y1241700D01*
X-16900D01*
X-17800Y1241300D01*
X-18500Y1240633D01*
X-19000Y1239833D01*
X-19400Y1238500D01*
X-19500Y1237300D01*
X-19300Y1236100D01*
X-19000Y1235300D01*
X-18400Y1234500D01*
X-17700Y1233967D01*
X-17000Y1233700D01*
X-16300D01*
X-15600Y1233967D01*
X-15000Y1234367D01*
X-14500Y1234900D01*
G01X-7000Y1233700D02*
X-11000D01*
Y1241700D01*
X-7000D01*
G01X-8600Y1237833D02*
X-11000D01*
G01X4000Y1241700D02*
X5400Y1233700D01*
X7000Y1241700D01*
X8600Y1233700D01*
X10000Y1241700D01*
G01X13800D02*
X16200D01*
G01X15000D02*
Y1233700D01*
G01X13800D02*
X16200D01*
G01X20800D02*
Y1241700D01*
X22800D01*
X23600Y1241300D01*
X24200Y1240767D01*
X24700Y1239967D01*
X25100Y1239033D01*
X25200Y1237700D01*
X25100Y1236367D01*
X24700Y1235433D01*
X24200Y1234633D01*
X23600Y1234100D01*
X22800Y1233700D01*
X20800D01*
G01X31000Y1241700D02*
Y1233700D01*
G01X28700Y1241700D02*
X33300D01*
G01X36900Y1233700D02*
Y1241700D01*
G01X41100D02*
Y1233700D01*
G01Y1237700D02*
X36900D01*
G01X44900Y1234766D02*
X45700Y1234100D01*
X46600Y1233700D01*
X47400D01*
X48200Y1234100D01*
X48800Y1234766D01*
X49100Y1235700D01*
X48900Y1236633D01*
X48400Y1237433D01*
X47500Y1237967D01*
X46300Y1238233D01*
X45600Y1238767D01*
X45300Y1239700D01*
X45500Y1240633D01*
X46000Y1241300D01*
X46700Y1241700D01*
X47400D01*
X48100Y1241433D01*
X48700Y1240767D01*
G01X54800Y1232233D02*
X55200Y1233967D01*
G01X76800Y1233700D02*
Y1241700D01*
X78800D01*
X79600Y1241300D01*
X80200Y1240767D01*
X80700Y1239967D01*
X81100Y1239033D01*
X81200Y1237700D01*
X81100Y1236367D01*
X80700Y1235433D01*
X80200Y1234633D01*
X79600Y1234100D01*
X78800Y1233700D01*
X76800D01*
G01X85800Y1241700D02*
X88200D01*
G01X87000D02*
Y1233700D01*
G01X85800D02*
X88200D01*
G01X97000D02*
X93000D01*
Y1241700D01*
X97000D01*
G01X95400Y1237833D02*
X93000D01*
G01X101000Y1241700D02*
Y1233700D01*
X105000D01*
G01X113000D02*
X109000D01*
Y1241700D01*
X113000D01*
G01X111400Y1237833D02*
X109000D01*
G01X121200Y1241033D02*
X120600Y1241433D01*
X119900Y1241700D01*
X119100D01*
X118200Y1241300D01*
X117500Y1240633D01*
X117000Y1239833D01*
X116600Y1238500D01*
X116500Y1237300D01*
X116700Y1236100D01*
X117000Y1235300D01*
X117600Y1234500D01*
X118300Y1233967D01*
X119000Y1233700D01*
X119700D01*
X120400Y1233967D01*
X121000Y1234367D01*
X121500Y1234900D01*
G01X127000Y1241700D02*
Y1233700D01*
G01X124700Y1241700D02*
X129300D01*
G01X133000Y1233700D02*
Y1241700D01*
X135500D01*
X136300Y1241300D01*
X136800Y1240767D01*
X137000Y1239700D01*
X136800Y1238633D01*
X136200Y1237967D01*
X135500Y1237567D01*
X133000D01*
G01X135500D02*
X137000Y1233700D01*
G01X141800Y1241700D02*
X144200D01*
G01X143000D02*
Y1233700D01*
G01X141800D02*
X144200D01*
G01X153200Y1241033D02*
X152600Y1241433D01*
X151900Y1241700D01*
X151100D01*
X150200Y1241300D01*
X149500Y1240633D01*
X149000Y1239833D01*
X148600Y1238500D01*
X148500Y1237300D01*
X148700Y1236100D01*
X149000Y1235300D01*
X149600Y1234500D01*
X150300Y1233967D01*
X151000Y1233700D01*
X151700D01*
X152400Y1233967D01*
X153000Y1234367D01*
X153500Y1234900D01*
G01X-341400Y1267700D02*
X-339400D01*
Y1265300D01*
X-340000Y1264500D01*
X-340700Y1263967D01*
X-341700Y1263700D01*
X-342700Y1263967D01*
X-343400Y1264500D01*
X-344000Y1265300D01*
X-344400Y1266233D01*
X-344600Y1267300D01*
Y1268233D01*
X-344400Y1269033D01*
X-344000Y1269967D01*
X-343400Y1270767D01*
X-342800Y1271300D01*
X-342000Y1271700D01*
X-341300D01*
X-340500Y1271433D01*
X-339900Y1270900D01*
G01X-334000Y1263433D02*
X-334200Y1263567D01*
Y1263833D01*
X-334000Y1263967D01*
X-333800Y1263833D01*
Y1263567D01*
X-334000Y1263433D01*
G01X-328300Y1263700D02*
Y1271700D01*
X-323700Y1263700D01*
Y1271700D01*
G01X-316000Y1263700D02*
X-320000D01*
Y1271700D01*
X-316000D01*
G01X-317600Y1267833D02*
X-320000D01*
G01X-308000Y1263700D02*
X-312000D01*
Y1271700D01*
X-308000D01*
G01X-309600Y1267833D02*
X-312000D01*
G01X-304200Y1263700D02*
Y1271700D01*
X-302200D01*
X-301400Y1271300D01*
X-300800Y1270767D01*
X-300300Y1269967D01*
X-299900Y1269033D01*
X-299800Y1267700D01*
X-299900Y1266367D01*
X-300300Y1265433D01*
X-300800Y1264633D01*
X-301400Y1264100D01*
X-302200Y1263700D01*
X-304200D01*
G01X-288200Y1271700D02*
Y1265967D01*
X-287800Y1264766D01*
X-287000Y1263967D01*
X-286000Y1263700D01*
X-285000Y1263967D01*
X-284200Y1264766D01*
X-283800Y1265967D01*
Y1271700D01*
G01X-280000D02*
Y1263700D01*
X-276000D01*
G01X-264600D02*
Y1271700D01*
X-262000Y1265033D01*
X-259400Y1271700D01*
Y1263700D01*
G01X-256500D02*
X-254000Y1271700D01*
X-251500Y1263700D01*
G01X-252400Y1266500D02*
X-255600D01*
G01X-248000Y1263700D02*
Y1271700D01*
X-245500D01*
X-244700Y1271300D01*
X-244200Y1270767D01*
X-244000Y1269700D01*
X-244200Y1268633D01*
X-244800Y1267967D01*
X-245500Y1267567D01*
X-248000D01*
G01X-245500D02*
X-244000Y1263700D01*
G01X-240200D02*
Y1271700D01*
G01X-236400D02*
X-240200Y1266766D01*
G01X-235800Y1263700D02*
X-238500Y1269033D01*
G01X-224500Y1263700D02*
X-222000Y1271700D01*
X-219500Y1263700D01*
G01X-220400Y1266500D02*
X-223600D01*
G01X-216300Y1263700D02*
Y1271700D01*
X-211700Y1263700D01*
Y1271700D01*
G01X-208200Y1263700D02*
Y1271700D01*
X-206200D01*
X-205400Y1271300D01*
X-204800Y1270767D01*
X-204300Y1269967D01*
X-203900Y1269033D01*
X-203800Y1267700D01*
X-203900Y1266367D01*
X-204300Y1265433D01*
X-204800Y1264633D01*
X-205400Y1264100D01*
X-206200Y1263700D01*
X-208200D01*
G01X-192200Y1271700D02*
Y1265967D01*
X-191800Y1264766D01*
X-191000Y1263967D01*
X-190000Y1263700D01*
X-189000Y1263967D01*
X-188200Y1264766D01*
X-187800Y1265967D01*
Y1271700D01*
G01X-184000D02*
Y1263700D01*
X-180000D01*
G01X-167900D02*
Y1271700D01*
X-164100D01*
G01X-165500Y1267833D02*
X-167900D01*
G01X-159200Y1271700D02*
X-156800D01*
G01X-158000D02*
Y1263700D01*
G01X-159200D02*
X-156800D01*
G01X-152000Y1271700D02*
Y1263700D01*
X-148000D01*
G01X-140000D02*
X-144000D01*
Y1271700D01*
X-140000D01*
G01X-141600Y1267833D02*
X-144000D01*
G01X-128300Y1263700D02*
Y1271700D01*
X-123700Y1263700D01*
Y1271700D01*
G01X-120200D02*
Y1265967D01*
X-119800Y1264766D01*
X-119000Y1263967D01*
X-118000Y1263700D01*
X-117000Y1263967D01*
X-116200Y1264766D01*
X-115800Y1265967D01*
Y1271700D01*
G01X-112600Y1263700D02*
Y1271700D01*
X-110000Y1265033D01*
X-107400Y1271700D01*
Y1263700D01*
G01X-101200Y1267967D02*
X-100800Y1268367D01*
X-100500Y1269033D01*
X-100300Y1269967D01*
X-100500Y1270767D01*
X-100900Y1271300D01*
X-101600Y1271700D01*
X-104300D01*
Y1263700D01*
X-101000D01*
X-100300Y1264233D01*
X-99900Y1265033D01*
X-99700Y1265967D01*
X-99900Y1266900D01*
X-100500Y1267700D01*
X-101200Y1267967D01*
X-104300D01*
G01X-92000Y1263700D02*
X-96000D01*
Y1271700D01*
X-92000D01*
G01X-93600Y1267833D02*
X-96000D01*
G01X-88000Y1263700D02*
Y1271700D01*
X-85500D01*
X-84700Y1271300D01*
X-84200Y1270767D01*
X-84000Y1269700D01*
X-84200Y1268633D01*
X-84800Y1267967D01*
X-85500Y1267567D01*
X-88000D01*
G01X-85500D02*
X-84000Y1263700D01*
G01X-70000D02*
X-70600Y1263833D01*
X-71200Y1264367D01*
X-71600Y1265300D01*
X-71800Y1266367D01*
X-71600Y1267433D01*
X-71200Y1268367D01*
X-70600Y1268900D01*
X-70000Y1269033D01*
X-69400Y1268900D01*
X-68800Y1268367D01*
X-68400Y1267433D01*
X-68300Y1266367D01*
X-68400Y1265300D01*
X-68800Y1264367D01*
X-69400Y1263833D01*
X-70000Y1263700D01*
G01X-63700D02*
Y1269033D01*
G01Y1267700D02*
X-63300Y1268367D01*
X-62700Y1268900D01*
X-61900Y1269033D01*
X-61200Y1268900D01*
X-60600Y1268367D01*
X-60300Y1267433D01*
Y1263700D01*
G01X-48100Y1264766D02*
X-47300Y1264100D01*
X-46400Y1263700D01*
X-45600D01*
X-44800Y1264100D01*
X-44200Y1264766D01*
X-43900Y1265700D01*
X-44100Y1266633D01*
X-44600Y1267433D01*
X-45500Y1267967D01*
X-46700Y1268233D01*
X-47400Y1268767D01*
X-47700Y1269700D01*
X-47500Y1270633D01*
X-47000Y1271300D01*
X-46300Y1271700D01*
X-45600D01*
X-44900Y1271433D01*
X-44300Y1270767D01*
G01X-39200Y1271700D02*
X-36800D01*
G01X-38000D02*
Y1263700D01*
G01X-39200D02*
X-36800D01*
G01X-32000Y1271700D02*
Y1263700D01*
X-28000D01*
G01X-24200D02*
Y1271700D01*
G01X-20400D02*
X-24200Y1266766D01*
G01X-19800Y1263700D02*
X-22500Y1269033D01*
G01X-16100Y1264766D02*
X-15300Y1264100D01*
X-14400Y1263700D01*
X-13600D01*
X-12800Y1264100D01*
X-12200Y1264766D01*
X-11900Y1265700D01*
X-12100Y1266633D01*
X-12600Y1267433D01*
X-13500Y1267967D01*
X-14700Y1268233D01*
X-15400Y1268767D01*
X-15700Y1269700D01*
X-15500Y1270633D01*
X-15000Y1271300D01*
X-14300Y1271700D01*
X-13600D01*
X-12900Y1271433D01*
X-12300Y1270767D01*
G01X-3800Y1271033D02*
X-4400Y1271433D01*
X-5100Y1271700D01*
X-5900D01*
X-6800Y1271300D01*
X-7500Y1270633D01*
X-8000Y1269833D01*
X-8400Y1268500D01*
X-8500Y1267300D01*
X-8300Y1266100D01*
X-8000Y1265300D01*
X-7400Y1264500D01*
X-6700Y1263967D01*
X-6000Y1263700D01*
X-5300D01*
X-4600Y1263967D01*
X-4000Y1264367D01*
X-3500Y1264900D01*
G01X0Y1263700D02*
Y1271700D01*
X2500D01*
X3300Y1271300D01*
X3800Y1270767D01*
X4000Y1269700D01*
X3800Y1268633D01*
X3200Y1267967D01*
X2500Y1267567D01*
X0D01*
G01X2500D02*
X4000Y1263700D01*
G01X12000D02*
X8000D01*
Y1271700D01*
X12000D01*
G01X10400Y1267833D02*
X8000D01*
G01X20000Y1263700D02*
X16000D01*
Y1271700D01*
X20000D01*
G01X18400Y1267833D02*
X16000D01*
G01X23700Y1263700D02*
Y1271700D01*
X28300Y1263700D01*
Y1271700D01*
G01X42000D02*
Y1263700D01*
G01X39700Y1271700D02*
X44300D01*
G01X50000Y1263700D02*
X49200Y1263833D01*
X48500Y1264367D01*
X47900Y1265167D01*
X47500Y1266100D01*
X47300Y1267167D01*
Y1268233D01*
X47500Y1269300D01*
X47900Y1270233D01*
X48500Y1271033D01*
X49200Y1271567D01*
X50000Y1271700D01*
X50800Y1271567D01*
X51500Y1271033D01*
X52100Y1270233D01*
X52500Y1269300D01*
X52700Y1268233D01*
Y1267167D01*
X52500Y1266100D01*
X52100Y1265167D01*
X51500Y1264367D01*
X50800Y1263833D01*
X50000Y1263700D01*
G01X56000D02*
Y1271700D01*
X58400D01*
X59200Y1271300D01*
X59800Y1270367D01*
X60000Y1269300D01*
X59800Y1268233D01*
X59300Y1267433D01*
X58400Y1267033D01*
X56000D01*
G01X71900Y1264766D02*
X72700Y1264100D01*
X73600Y1263700D01*
X74400D01*
X75200Y1264100D01*
X75800Y1264766D01*
X76100Y1265700D01*
X75900Y1266633D01*
X75400Y1267433D01*
X74500Y1267967D01*
X73300Y1268233D01*
X72600Y1268767D01*
X72300Y1269700D01*
X72500Y1270633D01*
X73000Y1271300D01*
X73700Y1271700D01*
X74400D01*
X75100Y1271433D01*
X75700Y1270767D01*
G01X80800Y1271700D02*
X83200D01*
G01X82000D02*
Y1263700D01*
G01X80800D02*
X83200D01*
G01X87800D02*
Y1271700D01*
X89800D01*
X90600Y1271300D01*
X91200Y1270767D01*
X91700Y1269967D01*
X92100Y1269033D01*
X92200Y1267700D01*
X92100Y1266367D01*
X91700Y1265433D01*
X91200Y1264633D01*
X90600Y1264100D01*
X89800Y1263700D01*
X87800D01*
G01X100000D02*
X96000D01*
Y1271700D01*
X100000D01*
G01X98400Y1267833D02*
X96000D01*
G01X-343900Y1278700D02*
Y1286700D01*
X-340100D01*
G01X-341500Y1282833D02*
X-343900D01*
G01X-334000Y1278433D02*
X-334200Y1278567D01*
Y1278833D01*
X-334000Y1278967D01*
X-333800Y1278833D01*
Y1278567D01*
X-334000Y1278433D01*
G01X-328300Y1278700D02*
Y1286700D01*
X-323700Y1278700D01*
Y1286700D01*
G01X-316000Y1278700D02*
X-320000D01*
Y1286700D01*
X-316000D01*
G01X-317600Y1282833D02*
X-320000D01*
G01X-308000Y1278700D02*
X-312000D01*
Y1286700D01*
X-308000D01*
G01X-309600Y1282833D02*
X-312000D01*
G01X-304200Y1278700D02*
Y1286700D01*
X-302200D01*
X-301400Y1286300D01*
X-300800Y1285767D01*
X-300300Y1284967D01*
X-299900Y1284033D01*
X-299800Y1282700D01*
X-299900Y1281367D01*
X-300300Y1280433D01*
X-300800Y1279633D01*
X-301400Y1279100D01*
X-302200Y1278700D01*
X-304200D01*
G01X-288000D02*
Y1286700D01*
X-285600D01*
X-284800Y1286300D01*
X-284200Y1285367D01*
X-284000Y1284300D01*
X-284200Y1283233D01*
X-284700Y1282433D01*
X-285600Y1282033D01*
X-288000D01*
G01X-275800Y1286033D02*
X-276400Y1286433D01*
X-277100Y1286700D01*
X-277900D01*
X-278800Y1286300D01*
X-279500Y1285633D01*
X-280000Y1284833D01*
X-280400Y1283500D01*
X-280500Y1282300D01*
X-280300Y1281100D01*
X-280000Y1280300D01*
X-279400Y1279500D01*
X-278700Y1278967D01*
X-278000Y1278700D01*
X-277300D01*
X-276600Y1278967D01*
X-276000Y1279367D01*
X-275500Y1279900D01*
G01X-269200Y1282967D02*
X-268800Y1283367D01*
X-268500Y1284033D01*
X-268300Y1284967D01*
X-268500Y1285767D01*
X-268900Y1286300D01*
X-269600Y1286700D01*
X-272300D01*
Y1278700D01*
X-269000D01*
X-268300Y1279233D01*
X-267900Y1280033D01*
X-267700Y1280967D01*
X-267900Y1281900D01*
X-268500Y1282700D01*
X-269200Y1282967D01*
X-272300D01*
G01X-256600Y1278700D02*
Y1286700D01*
X-254000Y1280033D01*
X-251400Y1286700D01*
Y1278700D01*
G01X-248500D02*
X-246000Y1286700D01*
X-243500Y1278700D01*
G01X-244400Y1281500D02*
X-247600D01*
G01X-240200Y1278700D02*
Y1286700D01*
G01X-236400D02*
X-240200Y1281766D01*
G01X-235800Y1278700D02*
X-238500Y1284033D01*
G01X-228000Y1278700D02*
X-232000D01*
Y1286700D01*
X-228000D01*
G01X-229600Y1282833D02*
X-232000D01*
G01X-224000Y1278700D02*
Y1286700D01*
X-221500D01*
X-220700Y1286300D01*
X-220200Y1285767D01*
X-220000Y1284700D01*
X-220200Y1283633D01*
X-220800Y1282967D01*
X-221500Y1282567D01*
X-224000D01*
G01X-221500D02*
X-220000Y1278700D01*
G01X-208000Y1286700D02*
Y1278700D01*
X-204000D01*
G01X-198000D02*
X-198800Y1278833D01*
X-199500Y1279367D01*
X-200100Y1280167D01*
X-200500Y1281100D01*
X-200700Y1282167D01*
Y1283233D01*
X-200500Y1284300D01*
X-200100Y1285233D01*
X-199500Y1286033D01*
X-198800Y1286567D01*
X-198000Y1286700D01*
X-197200Y1286567D01*
X-196500Y1286033D01*
X-195900Y1285233D01*
X-195500Y1284300D01*
X-195300Y1283233D01*
Y1282167D01*
X-195500Y1281100D01*
X-195900Y1280167D01*
X-196500Y1279367D01*
X-197200Y1278833D01*
X-198000Y1278700D01*
G01X-189400Y1282700D02*
X-187400D01*
Y1280300D01*
X-188000Y1279500D01*
X-188700Y1278967D01*
X-189700Y1278700D01*
X-190700Y1278967D01*
X-191400Y1279500D01*
X-192000Y1280300D01*
X-192400Y1281233D01*
X-192600Y1282300D01*
Y1283233D01*
X-192400Y1284033D01*
X-192000Y1284967D01*
X-191400Y1285767D01*
X-190800Y1286300D01*
X-190000Y1286700D01*
X-189300D01*
X-188500Y1286433D01*
X-187900Y1285900D01*
G01X-182000Y1278700D02*
X-182800Y1278833D01*
X-183500Y1279367D01*
X-184100Y1280167D01*
X-184500Y1281100D01*
X-184700Y1282167D01*
Y1283233D01*
X-184500Y1284300D01*
X-184100Y1285233D01*
X-183500Y1286033D01*
X-182800Y1286567D01*
X-182000Y1286700D01*
X-181200Y1286567D01*
X-180500Y1286033D01*
X-179900Y1285233D01*
X-179500Y1284300D01*
X-179300Y1283233D01*
Y1282167D01*
X-179500Y1281100D01*
X-179900Y1280167D01*
X-180500Y1279367D01*
X-181200Y1278833D01*
X-182000Y1278700D01*
G01X-168500D02*
X-166000Y1286700D01*
X-163500Y1278700D01*
G01X-164400Y1281500D02*
X-167600D01*
G01X-160300Y1278700D02*
Y1286700D01*
X-155700Y1278700D01*
Y1286700D01*
G01X-152200Y1278700D02*
Y1286700D01*
X-150200D01*
X-149400Y1286300D01*
X-148800Y1285767D01*
X-148300Y1284967D01*
X-147900Y1284033D01*
X-147800Y1282700D01*
X-147900Y1281367D01*
X-148300Y1280433D01*
X-148800Y1279633D01*
X-149400Y1279100D01*
X-150200Y1278700D01*
X-152200D01*
G01X-136200D02*
Y1286700D01*
X-134200D01*
X-133400Y1286300D01*
X-132800Y1285767D01*
X-132300Y1284967D01*
X-131900Y1284033D01*
X-131800Y1282700D01*
X-131900Y1281367D01*
X-132300Y1280433D01*
X-132800Y1279633D01*
X-133400Y1279100D01*
X-134200Y1278700D01*
X-136200D01*
G01X-128500D02*
X-126000Y1286700D01*
X-123500Y1278700D01*
G01X-124400Y1281500D02*
X-127600D01*
G01X-118000Y1286700D02*
Y1278700D01*
G01X-120300Y1286700D02*
X-115700D01*
G01X-108000Y1278700D02*
X-112000D01*
Y1286700D01*
X-108000D01*
G01X-109600Y1282833D02*
X-112000D01*
G01X-91800Y1286033D02*
X-92400Y1286433D01*
X-93100Y1286700D01*
X-93900D01*
X-94800Y1286300D01*
X-95500Y1285633D01*
X-96000Y1284833D01*
X-96400Y1283500D01*
X-96500Y1282300D01*
X-96300Y1281100D01*
X-96000Y1280300D01*
X-95400Y1279500D01*
X-94700Y1278967D01*
X-94000Y1278700D01*
X-93300D01*
X-92600Y1278967D01*
X-92000Y1279367D01*
X-91500Y1279900D01*
G01X-86000Y1278700D02*
X-86800Y1278833D01*
X-87500Y1279367D01*
X-88100Y1280167D01*
X-88500Y1281100D01*
X-88700Y1282167D01*
Y1283233D01*
X-88500Y1284300D01*
X-88100Y1285233D01*
X-87500Y1286033D01*
X-86800Y1286567D01*
X-86000Y1286700D01*
X-85200Y1286567D01*
X-84500Y1286033D01*
X-83900Y1285233D01*
X-83500Y1284300D01*
X-83300Y1283233D01*
Y1282167D01*
X-83500Y1281100D01*
X-83900Y1280167D01*
X-84500Y1279367D01*
X-85200Y1278833D01*
X-86000Y1278700D01*
G01X-80200D02*
Y1286700D01*
X-78200D01*
X-77400Y1286300D01*
X-76800Y1285767D01*
X-76300Y1284967D01*
X-75900Y1284033D01*
X-75800Y1282700D01*
X-75900Y1281367D01*
X-76300Y1280433D01*
X-76800Y1279633D01*
X-77400Y1279100D01*
X-78200Y1278700D01*
X-80200D01*
G01X-68000D02*
X-72000D01*
Y1286700D01*
X-68000D01*
G01X-69600Y1282833D02*
X-72000D01*
G01X-54500Y1276033D02*
X-55500Y1277367D01*
X-56000Y1278700D01*
Y1284033D01*
X-55500Y1285367D01*
X-54500Y1286700D01*
G01X-49000D02*
X-47600Y1278700D01*
X-46000Y1286700D01*
X-44400Y1278700D01*
X-43000Y1286700D01*
G01X-41000D02*
X-39600Y1278700D01*
X-38000Y1286700D01*
X-36400Y1278700D01*
X-35000Y1286700D01*
G01X-30000Y1278700D02*
Y1282300D01*
X-32000Y1286700D01*
G01X-28000D02*
X-30000Y1282300D01*
G01X-22000Y1278700D02*
Y1282300D01*
X-24000Y1286700D01*
G01X-20000D02*
X-22000Y1282300D01*
G01X-13500Y1276033D02*
X-12500Y1277367D01*
X-12000Y1278700D01*
Y1284033D01*
X-12500Y1285367D01*
X-13500Y1286700D01*
G01X2000Y1278700D02*
X1400Y1278833D01*
X800Y1279367D01*
X400Y1280300D01*
X200Y1281367D01*
X400Y1282433D01*
X800Y1283367D01*
X1400Y1283900D01*
X2000Y1284033D01*
X2600Y1283900D01*
X3200Y1283367D01*
X3600Y1282433D01*
X3700Y1281367D01*
X3600Y1280300D01*
X3200Y1279367D01*
X2600Y1278833D01*
X2000Y1278700D01*
G01X8300D02*
Y1284033D01*
G01Y1282700D02*
X8700Y1283367D01*
X9300Y1283900D01*
X10100Y1284033D01*
X10800Y1283900D01*
X11400Y1283367D01*
X11700Y1282433D01*
Y1278700D01*
G01X23900Y1279766D02*
X24700Y1279100D01*
X25600Y1278700D01*
X26400D01*
X27200Y1279100D01*
X27800Y1279766D01*
X28100Y1280700D01*
X27900Y1281633D01*
X27400Y1282433D01*
X26500Y1282967D01*
X25300Y1283233D01*
X24600Y1283767D01*
X24300Y1284700D01*
X24500Y1285633D01*
X25000Y1286300D01*
X25700Y1286700D01*
X26400D01*
X27100Y1286433D01*
X27700Y1285767D01*
G01X32800Y1286700D02*
X35200D01*
G01X34000D02*
Y1278700D01*
G01X32800D02*
X35200D01*
G01X40000Y1286700D02*
Y1278700D01*
X44000D01*
G01X47800D02*
Y1286700D01*
G01X51600D02*
X47800Y1281766D01*
G01X52200Y1278700D02*
X49500Y1284033D01*
G01X55900Y1279766D02*
X56700Y1279100D01*
X57600Y1278700D01*
X58400D01*
X59200Y1279100D01*
X59800Y1279766D01*
X60100Y1280700D01*
X59900Y1281633D01*
X59400Y1282433D01*
X58500Y1282967D01*
X57300Y1283233D01*
X56600Y1283767D01*
X56300Y1284700D01*
X56500Y1285633D01*
X57000Y1286300D01*
X57700Y1286700D01*
X58400D01*
X59100Y1286433D01*
X59700Y1285767D01*
G01X68200Y1286033D02*
X67600Y1286433D01*
X66900Y1286700D01*
X66100D01*
X65200Y1286300D01*
X64500Y1285633D01*
X64000Y1284833D01*
X63600Y1283500D01*
X63500Y1282300D01*
X63700Y1281100D01*
X64000Y1280300D01*
X64600Y1279500D01*
X65300Y1278967D01*
X66000Y1278700D01*
X66700D01*
X67400Y1278967D01*
X68000Y1279367D01*
X68500Y1279900D01*
G01X72000Y1278700D02*
Y1286700D01*
X74500D01*
X75300Y1286300D01*
X75800Y1285767D01*
X76000Y1284700D01*
X75800Y1283633D01*
X75200Y1282967D01*
X74500Y1282567D01*
X72000D01*
G01X74500D02*
X76000Y1278700D01*
G01X84000D02*
X80000D01*
Y1286700D01*
X84000D01*
G01X82400Y1282833D02*
X80000D01*
G01X92000Y1278700D02*
X88000D01*
Y1286700D01*
X92000D01*
G01X90400Y1282833D02*
X88000D01*
G01X95700Y1278700D02*
Y1286700D01*
X100300Y1278700D01*
Y1286700D01*
G01X114000D02*
Y1278700D01*
G01X111700Y1286700D02*
X116300D01*
G01X122000Y1278700D02*
X121200Y1278833D01*
X120500Y1279367D01*
X119900Y1280167D01*
X119500Y1281100D01*
X119300Y1282167D01*
Y1283233D01*
X119500Y1284300D01*
X119900Y1285233D01*
X120500Y1286033D01*
X121200Y1286567D01*
X122000Y1286700D01*
X122800Y1286567D01*
X123500Y1286033D01*
X124100Y1285233D01*
X124500Y1284300D01*
X124700Y1283233D01*
Y1282167D01*
X124500Y1281100D01*
X124100Y1280167D01*
X123500Y1279367D01*
X122800Y1278833D01*
X122000Y1278700D01*
G01X128000D02*
Y1286700D01*
X130400D01*
X131200Y1286300D01*
X131800Y1285367D01*
X132000Y1284300D01*
X131800Y1283233D01*
X131300Y1282433D01*
X130400Y1282033D01*
X128000D01*
G01X143900Y1279766D02*
X144700Y1279100D01*
X145600Y1278700D01*
X146400D01*
X147200Y1279100D01*
X147800Y1279766D01*
X148100Y1280700D01*
X147900Y1281633D01*
X147400Y1282433D01*
X146500Y1282967D01*
X145300Y1283233D01*
X144600Y1283767D01*
X144300Y1284700D01*
X144500Y1285633D01*
X145000Y1286300D01*
X145700Y1286700D01*
X146400D01*
X147100Y1286433D01*
X147700Y1285767D01*
G01X152800Y1286700D02*
X155200D01*
G01X154000D02*
Y1278700D01*
G01X152800D02*
X155200D01*
G01X159800D02*
Y1286700D01*
X161800D01*
X162600Y1286300D01*
X163200Y1285767D01*
X163700Y1284967D01*
X164100Y1284033D01*
X164200Y1282700D01*
X164100Y1281367D01*
X163700Y1280433D01*
X163200Y1279633D01*
X162600Y1279100D01*
X161800Y1278700D01*
X159800D01*
G01X172000D02*
X168000D01*
Y1286700D01*
X172000D01*
G01X170400Y1282833D02*
X168000D01*
G01X189000Y1276033D02*
X184000Y1284033D01*
Y1285367D01*
X185000Y1286700D01*
X186000D01*
X187000Y1285367D01*
Y1284033D01*
X186000Y1282700D01*
X184000Y1281367D01*
X183000Y1280033D01*
Y1277367D01*
X184000Y1276033D01*
X187000D01*
X189000Y1278700D01*
G01X202800Y1282967D02*
X203200Y1283367D01*
X203500Y1284033D01*
X203700Y1284967D01*
X203500Y1285767D01*
X203100Y1286300D01*
X202400Y1286700D01*
X199700D01*
Y1278700D01*
X203000D01*
X203700Y1279233D01*
X204100Y1280033D01*
X204300Y1280967D01*
X204100Y1281900D01*
X203500Y1282700D01*
X202800Y1282967D01*
X199700D01*
G01X208000Y1278700D02*
Y1286700D01*
X210500D01*
X211300Y1286300D01*
X211800Y1285767D01*
X212000Y1284700D01*
X211800Y1283633D01*
X211200Y1282967D01*
X210500Y1282567D01*
X208000D01*
G01X210500D02*
X212000Y1278700D01*
G01X220000D02*
X216000D01*
Y1286700D01*
X220000D01*
G01X218400Y1282833D02*
X216000D01*
G01X223500Y1278700D02*
X226000Y1286700D01*
X228500Y1278700D01*
G01X227600Y1281500D02*
X224400D01*
G01X231800Y1278700D02*
Y1286700D01*
G01X235600D02*
X231800Y1281766D01*
G01X236200Y1278700D02*
X233500Y1284033D01*
G01X239500Y1278700D02*
X242000Y1286700D01*
X244500Y1278700D01*
G01X243600Y1281500D02*
X240400D01*
G01X247000Y1286700D02*
X248400Y1278700D01*
X250000Y1286700D01*
X251600Y1278700D01*
X253000Y1286700D01*
G01X255500Y1278700D02*
X258000Y1286700D01*
X260500Y1278700D01*
G01X259600Y1281500D02*
X256400D01*
G01X266000Y1278700D02*
Y1282300D01*
X264000Y1286700D01*
G01X268000D02*
X266000Y1282300D01*
G01X-340000Y1293700D02*
X-344000D01*
Y1301700D01*
X-340000D01*
G01X-341600Y1297833D02*
X-344000D01*
G01X-334000Y1293433D02*
X-334200Y1293567D01*
Y1293833D01*
X-334000Y1293967D01*
X-333800Y1293833D01*
Y1293567D01*
X-334000Y1293433D01*
G01X-328000Y1293700D02*
Y1301700D01*
X-325600D01*
X-324800Y1301300D01*
X-324200Y1300367D01*
X-324000Y1299300D01*
X-324200Y1298233D01*
X-324700Y1297433D01*
X-325600Y1297033D01*
X-328000D01*
G01X-320000Y1293700D02*
Y1301700D01*
X-317500D01*
X-316700Y1301300D01*
X-316200Y1300767D01*
X-316000Y1299700D01*
X-316200Y1298633D01*
X-316800Y1297967D01*
X-317500Y1297567D01*
X-320000D01*
G01X-317500D02*
X-316000Y1293700D01*
G01X-310000D02*
X-310800Y1293833D01*
X-311500Y1294367D01*
X-312100Y1295167D01*
X-312500Y1296100D01*
X-312700Y1297167D01*
Y1298233D01*
X-312500Y1299300D01*
X-312100Y1300233D01*
X-311500Y1301033D01*
X-310800Y1301567D01*
X-310000Y1301700D01*
X-309200Y1301567D01*
X-308500Y1301033D01*
X-307900Y1300233D01*
X-307500Y1299300D01*
X-307300Y1298233D01*
Y1297167D01*
X-307500Y1296100D01*
X-307900Y1295167D01*
X-308500Y1294367D01*
X-309200Y1293833D01*
X-310000Y1293700D01*
G01X-304500Y1301700D02*
X-302000Y1293700D01*
X-299500Y1301700D01*
G01X-295200D02*
X-292800D01*
G01X-294000D02*
Y1293700D01*
G01X-295200D02*
X-292800D01*
G01X-288200D02*
Y1301700D01*
X-286200D01*
X-285400Y1301300D01*
X-284800Y1300767D01*
X-284300Y1299967D01*
X-283900Y1299033D01*
X-283800Y1297700D01*
X-283900Y1296367D01*
X-284300Y1295433D01*
X-284800Y1294633D01*
X-285400Y1294100D01*
X-286200Y1293700D01*
X-288200D01*
G01X-276000D02*
X-280000D01*
Y1301700D01*
X-276000D01*
G01X-277600Y1297833D02*
X-280000D01*
G01X-264000Y1293700D02*
Y1301700D01*
X-261600D01*
X-260800Y1301300D01*
X-260200Y1300367D01*
X-260000Y1299300D01*
X-260200Y1298233D01*
X-260700Y1297433D01*
X-261600Y1297033D01*
X-264000D01*
G01X-251800Y1301033D02*
X-252400Y1301433D01*
X-253100Y1301700D01*
X-253900D01*
X-254800Y1301300D01*
X-255500Y1300633D01*
X-256000Y1299833D01*
X-256400Y1298500D01*
X-256500Y1297300D01*
X-256300Y1296100D01*
X-256000Y1295300D01*
X-255400Y1294500D01*
X-254700Y1293967D01*
X-254000Y1293700D01*
X-253300D01*
X-252600Y1293967D01*
X-252000Y1294367D01*
X-251500Y1294900D01*
G01X-245200Y1297967D02*
X-244800Y1298367D01*
X-244500Y1299033D01*
X-244300Y1299967D01*
X-244500Y1300767D01*
X-244900Y1301300D01*
X-245600Y1301700D01*
X-248300D01*
Y1293700D01*
X-245000D01*
X-244300Y1294233D01*
X-243900Y1295033D01*
X-243700Y1295967D01*
X-243900Y1296900D01*
X-244500Y1297700D01*
X-245200Y1297967D01*
X-248300D01*
G01X-231900Y1293700D02*
Y1301700D01*
X-228100D01*
G01X-229500Y1297833D02*
X-231900D01*
G01X-223200Y1301700D02*
X-220800D01*
G01X-222000D02*
Y1293700D01*
G01X-223200D02*
X-220800D01*
G01X-216000Y1301700D02*
Y1293700D01*
X-212000D01*
G01X-208600D02*
Y1301700D01*
X-206000Y1295033D01*
X-203400Y1301700D01*
Y1293700D01*
G01X-344200Y1308700D02*
Y1316700D01*
X-342200D01*
X-341400Y1316300D01*
X-340800Y1315767D01*
X-340300Y1314967D01*
X-339900Y1314033D01*
X-339800Y1312700D01*
X-339900Y1311367D01*
X-340300Y1310433D01*
X-340800Y1309633D01*
X-341400Y1309100D01*
X-342200Y1308700D01*
X-344200D01*
G01X-334000Y1308433D02*
X-334200Y1308567D01*
Y1308833D01*
X-334000Y1308967D01*
X-333800Y1308833D01*
Y1308567D01*
X-334000Y1308433D01*
G01X-328000Y1308700D02*
Y1316700D01*
X-325600D01*
X-324800Y1316300D01*
X-324200Y1315367D01*
X-324000Y1314300D01*
X-324200Y1313233D01*
X-324700Y1312433D01*
X-325600Y1312033D01*
X-328000D01*
G01X-320000Y1308700D02*
Y1316700D01*
X-317500D01*
X-316700Y1316300D01*
X-316200Y1315767D01*
X-316000Y1314700D01*
X-316200Y1313633D01*
X-316800Y1312967D01*
X-317500Y1312567D01*
X-320000D01*
G01X-317500D02*
X-316000Y1308700D01*
G01X-310000D02*
X-310800Y1308833D01*
X-311500Y1309367D01*
X-312100Y1310167D01*
X-312500Y1311100D01*
X-312700Y1312167D01*
Y1313233D01*
X-312500Y1314300D01*
X-312100Y1315233D01*
X-311500Y1316033D01*
X-310800Y1316567D01*
X-310000Y1316700D01*
X-309200Y1316567D01*
X-308500Y1316033D01*
X-307900Y1315233D01*
X-307500Y1314300D01*
X-307300Y1313233D01*
Y1312167D01*
X-307500Y1311100D01*
X-307900Y1310167D01*
X-308500Y1309367D01*
X-309200Y1308833D01*
X-310000Y1308700D01*
G01X-304500Y1316700D02*
X-302000Y1308700D01*
X-299500Y1316700D01*
G01X-295200D02*
X-292800D01*
G01X-294000D02*
Y1308700D01*
G01X-295200D02*
X-292800D01*
G01X-288200D02*
Y1316700D01*
X-286200D01*
X-285400Y1316300D01*
X-284800Y1315767D01*
X-284300Y1314967D01*
X-283900Y1314033D01*
X-283800Y1312700D01*
X-283900Y1311367D01*
X-284300Y1310433D01*
X-284800Y1309633D01*
X-285400Y1309100D01*
X-286200Y1308700D01*
X-288200D01*
G01X-276000D02*
X-280000D01*
Y1316700D01*
X-276000D01*
G01X-277600Y1312833D02*
X-280000D01*
G01X-263200Y1316700D02*
X-260800D01*
G01X-262000D02*
Y1308700D01*
G01X-263200D02*
X-260800D01*
G01X-256600D02*
Y1316700D01*
X-254000Y1310033D01*
X-251400Y1316700D01*
Y1308700D01*
G01X-248000D02*
Y1316700D01*
X-245600D01*
X-244800Y1316300D01*
X-244200Y1315367D01*
X-244000Y1314300D01*
X-244200Y1313233D01*
X-244700Y1312433D01*
X-245600Y1312033D01*
X-248000D01*
G01X-236000Y1308700D02*
X-240000D01*
Y1316700D01*
X-236000D01*
G01X-237600Y1312833D02*
X-240000D01*
G01X-232200Y1308700D02*
Y1316700D01*
X-230200D01*
X-229400Y1316300D01*
X-228800Y1315767D01*
X-228300Y1314967D01*
X-227900Y1314033D01*
X-227800Y1312700D01*
X-227900Y1311367D01*
X-228300Y1310433D01*
X-228800Y1309633D01*
X-229400Y1309100D01*
X-230200Y1308700D01*
X-232200D01*
G01X-224500D02*
X-222000Y1316700D01*
X-219500Y1308700D01*
G01X-220400Y1311500D02*
X-223600D01*
G01X-216300Y1308700D02*
Y1316700D01*
X-211700Y1308700D01*
Y1316700D01*
G01X-203800Y1316033D02*
X-204400Y1316433D01*
X-205100Y1316700D01*
X-205900D01*
X-206800Y1316300D01*
X-207500Y1315633D01*
X-208000Y1314833D01*
X-208400Y1313500D01*
X-208500Y1312300D01*
X-208300Y1311100D01*
X-208000Y1310300D01*
X-207400Y1309500D01*
X-206700Y1308967D01*
X-206000Y1308700D01*
X-205300D01*
X-204600Y1308967D01*
X-204000Y1309367D01*
X-203500Y1309900D01*
G01X-196000Y1308700D02*
X-200000D01*
Y1316700D01*
X-196000D01*
G01X-197600Y1312833D02*
X-200000D01*
G01X-179800Y1316033D02*
X-180400Y1316433D01*
X-181100Y1316700D01*
X-181900D01*
X-182800Y1316300D01*
X-183500Y1315633D01*
X-184000Y1314833D01*
X-184400Y1313500D01*
X-184500Y1312300D01*
X-184300Y1311100D01*
X-184000Y1310300D01*
X-183400Y1309500D01*
X-182700Y1308967D01*
X-182000Y1308700D01*
X-181300D01*
X-180600Y1308967D01*
X-180000Y1309367D01*
X-179500Y1309900D01*
G01X-174000Y1308700D02*
X-174800Y1308833D01*
X-175500Y1309367D01*
X-176100Y1310167D01*
X-176500Y1311100D01*
X-176700Y1312167D01*
Y1313233D01*
X-176500Y1314300D01*
X-176100Y1315233D01*
X-175500Y1316033D01*
X-174800Y1316567D01*
X-174000Y1316700D01*
X-173200Y1316567D01*
X-172500Y1316033D01*
X-171900Y1315233D01*
X-171500Y1314300D01*
X-171300Y1313233D01*
Y1312167D01*
X-171500Y1311100D01*
X-171900Y1310167D01*
X-172500Y1309367D01*
X-173200Y1308833D01*
X-174000Y1308700D01*
G01X-168200Y1316700D02*
Y1310967D01*
X-167800Y1309766D01*
X-167000Y1308967D01*
X-166000Y1308700D01*
X-165000Y1308967D01*
X-164200Y1309766D01*
X-163800Y1310967D01*
Y1316700D01*
G01X-160000Y1308700D02*
Y1316700D01*
X-157600D01*
X-156800Y1316300D01*
X-156200Y1315367D01*
X-156000Y1314300D01*
X-156200Y1313233D01*
X-156700Y1312433D01*
X-157600Y1312033D01*
X-160000D01*
G01X-150000Y1308700D02*
X-150800Y1308833D01*
X-151500Y1309367D01*
X-152100Y1310167D01*
X-152500Y1311100D01*
X-152700Y1312167D01*
Y1313233D01*
X-152500Y1314300D01*
X-152100Y1315233D01*
X-151500Y1316033D01*
X-150800Y1316567D01*
X-150000Y1316700D01*
X-149200Y1316567D01*
X-148500Y1316033D01*
X-147900Y1315233D01*
X-147500Y1314300D01*
X-147300Y1313233D01*
Y1312167D01*
X-147500Y1311100D01*
X-147900Y1310167D01*
X-148500Y1309367D01*
X-149200Y1308833D01*
X-150000Y1308700D01*
G01X-144300D02*
Y1316700D01*
X-139700Y1308700D01*
Y1316700D01*
G01X-128500Y1308700D02*
X-126000Y1316700D01*
X-123500Y1308700D01*
G01X-124400Y1311500D02*
X-127600D01*
G01X-120300Y1308700D02*
Y1316700D01*
X-115700Y1308700D01*
Y1316700D01*
G01X-112200Y1308700D02*
Y1316700D01*
X-110200D01*
X-109400Y1316300D01*
X-108800Y1315767D01*
X-108300Y1314967D01*
X-107900Y1314033D01*
X-107800Y1312700D01*
X-107900Y1311367D01*
X-108300Y1310433D01*
X-108800Y1309633D01*
X-109400Y1309100D01*
X-110200Y1308700D01*
X-112200D01*
G01X-96600D02*
Y1316700D01*
X-94000Y1310033D01*
X-91400Y1316700D01*
Y1308700D01*
G01X-84000D02*
X-88000D01*
Y1316700D01*
X-84000D01*
G01X-85600Y1312833D02*
X-88000D01*
G01X-80500Y1308700D02*
X-78000Y1316700D01*
X-75500Y1308700D01*
G01X-76400Y1311500D02*
X-79600D01*
G01X-72100Y1309766D02*
X-71300Y1309100D01*
X-70400Y1308700D01*
X-69600D01*
X-68800Y1309100D01*
X-68200Y1309766D01*
X-67900Y1310700D01*
X-68100Y1311633D01*
X-68600Y1312433D01*
X-69500Y1312967D01*
X-70700Y1313233D01*
X-71400Y1313767D01*
X-71700Y1314700D01*
X-71500Y1315633D01*
X-71000Y1316300D01*
X-70300Y1316700D01*
X-69600D01*
X-68900Y1316433D01*
X-68300Y1315767D01*
G01X-64200Y1316700D02*
Y1310967D01*
X-63800Y1309766D01*
X-63000Y1308967D01*
X-62000Y1308700D01*
X-61000Y1308967D01*
X-60200Y1309766D01*
X-59800Y1310967D01*
Y1316700D01*
G01X-56000Y1308700D02*
Y1316700D01*
X-53500D01*
X-52700Y1316300D01*
X-52200Y1315767D01*
X-52000Y1314700D01*
X-52200Y1313633D01*
X-52800Y1312967D01*
X-53500Y1312567D01*
X-56000D01*
G01X-53500D02*
X-52000Y1308700D01*
G01X-44000D02*
X-48000D01*
Y1316700D01*
X-44000D01*
G01X-45600Y1312833D02*
X-48000D01*
G01X-40600Y1308700D02*
Y1316700D01*
X-38000Y1310033D01*
X-35400Y1316700D01*
Y1308700D01*
G01X-28000D02*
X-32000D01*
Y1316700D01*
X-28000D01*
G01X-29600Y1312833D02*
X-32000D01*
G01X-24300Y1308700D02*
Y1316700D01*
X-19700Y1308700D01*
Y1316700D01*
G01X-14000D02*
Y1308700D01*
G01X-16300Y1316700D02*
X-11700D01*
G01X0Y1308700D02*
Y1316700D01*
X2500D01*
X3300Y1316300D01*
X3800Y1315767D01*
X4000Y1314700D01*
X3800Y1313633D01*
X3200Y1312967D01*
X2500Y1312567D01*
X0D01*
G01X2500D02*
X4000Y1308700D01*
G01X12000D02*
X8000D01*
Y1316700D01*
X12000D01*
G01X10400Y1312833D02*
X8000D01*
G01X16000Y1308700D02*
Y1316700D01*
X18400D01*
X19200Y1316300D01*
X19800Y1315367D01*
X20000Y1314300D01*
X19800Y1313233D01*
X19300Y1312433D01*
X18400Y1312033D01*
X16000D01*
G01X26000Y1308700D02*
X25200Y1308833D01*
X24500Y1309367D01*
X23900Y1310167D01*
X23500Y1311100D01*
X23300Y1312167D01*
Y1313233D01*
X23500Y1314300D01*
X23900Y1315233D01*
X24500Y1316033D01*
X25200Y1316567D01*
X26000Y1316700D01*
X26800Y1316567D01*
X27500Y1316033D01*
X28100Y1315233D01*
X28500Y1314300D01*
X28700Y1313233D01*
Y1312167D01*
X28500Y1311100D01*
X28100Y1310167D01*
X27500Y1309367D01*
X26800Y1308833D01*
X26000Y1308700D01*
G01X32000D02*
Y1316700D01*
X34500D01*
X35300Y1316300D01*
X35800Y1315767D01*
X36000Y1314700D01*
X35800Y1313633D01*
X35200Y1312967D01*
X34500Y1312567D01*
X32000D01*
G01X34500D02*
X36000Y1308700D01*
G01X42000Y1316700D02*
Y1308700D01*
G01X39700Y1316700D02*
X44300D01*
G01X-339800Y1331033D02*
X-340400Y1331433D01*
X-341100Y1331700D01*
X-341900D01*
X-342800Y1331300D01*
X-343500Y1330633D01*
X-344000Y1329833D01*
X-344400Y1328500D01*
X-344500Y1327300D01*
X-344300Y1326100D01*
X-344000Y1325300D01*
X-343400Y1324500D01*
X-342700Y1323967D01*
X-342000Y1323700D01*
X-341300D01*
X-340600Y1323967D01*
X-340000Y1324367D01*
X-339500Y1324900D01*
G01X-334000Y1323433D02*
X-334200Y1323567D01*
Y1323833D01*
X-334000Y1323967D01*
X-333800Y1323833D01*
Y1323567D01*
X-334000Y1323433D01*
G01X-328300Y1323700D02*
Y1331700D01*
X-323700Y1323700D01*
Y1331700D01*
G01X-318000Y1323700D02*
X-318800Y1323833D01*
X-319500Y1324367D01*
X-320100Y1325167D01*
X-320500Y1326100D01*
X-320700Y1327167D01*
Y1328233D01*
X-320500Y1329300D01*
X-320100Y1330233D01*
X-319500Y1331033D01*
X-318800Y1331567D01*
X-318000Y1331700D01*
X-317200Y1331567D01*
X-316500Y1331033D01*
X-315900Y1330233D01*
X-315500Y1329300D01*
X-315300Y1328233D01*
Y1327167D01*
X-315500Y1326100D01*
X-315900Y1325167D01*
X-316500Y1324367D01*
X-317200Y1323833D01*
X-318000Y1323700D01*
G01X-304300D02*
Y1331700D01*
X-299700Y1323700D01*
Y1331700D01*
G01X-292000Y1323700D02*
X-296000D01*
Y1331700D01*
X-292000D01*
G01X-293600Y1327833D02*
X-296000D01*
G01X-284000Y1323700D02*
X-288000D01*
Y1331700D01*
X-284000D01*
G01X-285600Y1327833D02*
X-288000D01*
G01X-280200Y1323700D02*
Y1331700D01*
X-278200D01*
X-277400Y1331300D01*
X-276800Y1330767D01*
X-276300Y1329967D01*
X-275900Y1329033D01*
X-275800Y1327700D01*
X-275900Y1326367D01*
X-276300Y1325433D01*
X-276800Y1324633D01*
X-277400Y1324100D01*
X-278200Y1323700D01*
X-280200D01*
G01X-262000Y1331700D02*
Y1323700D01*
G01X-264300Y1331700D02*
X-259700D01*
G01X-254000Y1323700D02*
X-254800Y1323833D01*
X-255500Y1324367D01*
X-256100Y1325167D01*
X-256500Y1326100D01*
X-256700Y1327167D01*
Y1328233D01*
X-256500Y1329300D01*
X-256100Y1330233D01*
X-255500Y1331033D01*
X-254800Y1331567D01*
X-254000Y1331700D01*
X-253200Y1331567D01*
X-252500Y1331033D01*
X-251900Y1330233D01*
X-251500Y1329300D01*
X-251300Y1328233D01*
Y1327167D01*
X-251500Y1326100D01*
X-251900Y1325167D01*
X-252500Y1324367D01*
X-253200Y1323833D01*
X-254000Y1323700D01*
G01X-240000D02*
Y1331700D01*
X-237600D01*
X-236800Y1331300D01*
X-236200Y1330367D01*
X-236000Y1329300D01*
X-236200Y1328233D01*
X-236700Y1327433D01*
X-237600Y1327033D01*
X-240000D01*
G01X-232000Y1331700D02*
Y1323700D01*
X-228000D01*
G01X-224200Y1331700D02*
Y1325967D01*
X-223800Y1324766D01*
X-223000Y1323967D01*
X-222000Y1323700D01*
X-221000Y1323967D01*
X-220200Y1324766D01*
X-219800Y1325967D01*
Y1331700D01*
G01X-213400Y1327700D02*
X-211400D01*
Y1325300D01*
X-212000Y1324500D01*
X-212700Y1323967D01*
X-213700Y1323700D01*
X-214700Y1323967D01*
X-215400Y1324500D01*
X-216000Y1325300D01*
X-216400Y1326233D01*
X-216600Y1327300D01*
Y1328233D01*
X-216400Y1329033D01*
X-216000Y1329967D01*
X-215400Y1330767D01*
X-214800Y1331300D01*
X-214000Y1331700D01*
X-213300D01*
X-212500Y1331433D01*
X-211900Y1330900D01*
G01X-198000Y1323700D02*
X-197300Y1323833D01*
X-196500Y1324233D01*
X-196000Y1324900D01*
X-195800Y1325833D01*
X-196000Y1326766D01*
X-196600Y1327567D01*
X-197500Y1327967D01*
X-198500D01*
X-199100Y1328233D01*
X-199600Y1328900D01*
X-199800Y1329833D01*
X-199500Y1330767D01*
X-198800Y1331433D01*
X-198000Y1331700D01*
X-197200Y1331433D01*
X-196500Y1330767D01*
X-196200Y1329833D01*
X-196400Y1328900D01*
X-196900Y1328233D01*
X-197500Y1327967D01*
X-198500D01*
X-199400Y1327567D01*
X-200000Y1326766D01*
X-200200Y1325833D01*
X-200000Y1324900D01*
X-199500Y1324233D01*
X-198700Y1323833D01*
X-198000Y1323700D01*
G01X-184100D02*
Y1331700D01*
G01X-179900D02*
Y1323700D01*
G01Y1327700D02*
X-184100D01*
G01X-174000Y1323700D02*
X-174800Y1323833D01*
X-175500Y1324367D01*
X-176100Y1325167D01*
X-176500Y1326100D01*
X-176700Y1327167D01*
Y1328233D01*
X-176500Y1329300D01*
X-176100Y1330233D01*
X-175500Y1331033D01*
X-174800Y1331567D01*
X-174000Y1331700D01*
X-173200Y1331567D01*
X-172500Y1331033D01*
X-171900Y1330233D01*
X-171500Y1329300D01*
X-171300Y1328233D01*
Y1327167D01*
X-171500Y1326100D01*
X-171900Y1325167D01*
X-172500Y1324367D01*
X-173200Y1323833D01*
X-174000Y1323700D01*
G01X-168000Y1331700D02*
Y1323700D01*
X-164000D01*
G01X-156000D02*
X-160000D01*
Y1331700D01*
X-156000D01*
G01X-157600Y1327833D02*
X-160000D01*
G01X-152100Y1324766D02*
X-151300Y1324100D01*
X-150400Y1323700D01*
X-149600D01*
X-148800Y1324100D01*
X-148200Y1324766D01*
X-147900Y1325700D01*
X-148100Y1326633D01*
X-148600Y1327433D01*
X-149500Y1327967D01*
X-150700Y1328233D01*
X-151400Y1328767D01*
X-151700Y1329700D01*
X-151500Y1330633D01*
X-151000Y1331300D01*
X-150300Y1331700D01*
X-149600D01*
X-148900Y1331433D01*
X-148300Y1330767D01*
G01X-136100Y1324766D02*
X-135300Y1324100D01*
X-134400Y1323700D01*
X-133600D01*
X-132800Y1324100D01*
X-132200Y1324766D01*
X-131900Y1325700D01*
X-132100Y1326633D01*
X-132600Y1327433D01*
X-133500Y1327967D01*
X-134700Y1328233D01*
X-135400Y1328767D01*
X-135700Y1329700D01*
X-135500Y1330633D01*
X-135000Y1331300D01*
X-134300Y1331700D01*
X-133600D01*
X-132900Y1331433D01*
X-132300Y1330767D01*
G01X-128200Y1331700D02*
Y1325967D01*
X-127800Y1324766D01*
X-127000Y1323967D01*
X-126000Y1323700D01*
X-125000Y1323967D01*
X-124200Y1324766D01*
X-123800Y1325967D01*
Y1331700D01*
G01X-120000Y1323700D02*
Y1331700D01*
X-117500D01*
X-116700Y1331300D01*
X-116200Y1330767D01*
X-116000Y1329700D01*
X-116200Y1328633D01*
X-116800Y1327967D01*
X-117500Y1327567D01*
X-120000D01*
G01X-117500D02*
X-116000Y1323700D01*
G01X-112000D02*
Y1331700D01*
X-109500D01*
X-108700Y1331300D01*
X-108200Y1330767D01*
X-108000Y1329700D01*
X-108200Y1328633D01*
X-108800Y1327967D01*
X-109500Y1327567D01*
X-112000D01*
G01X-109500D02*
X-108000Y1323700D01*
G01X-102000D02*
X-102800Y1323833D01*
X-103500Y1324367D01*
X-104100Y1325167D01*
X-104500Y1326100D01*
X-104700Y1327167D01*
Y1328233D01*
X-104500Y1329300D01*
X-104100Y1330233D01*
X-103500Y1331033D01*
X-102800Y1331567D01*
X-102000Y1331700D01*
X-101200Y1331567D01*
X-100500Y1331033D01*
X-99900Y1330233D01*
X-99500Y1329300D01*
X-99300Y1328233D01*
Y1327167D01*
X-99500Y1326100D01*
X-99900Y1325167D01*
X-100500Y1324367D01*
X-101200Y1323833D01*
X-102000Y1323700D01*
G01X-96200Y1331700D02*
Y1325967D01*
X-95800Y1324766D01*
X-95000Y1323967D01*
X-94000Y1323700D01*
X-93000Y1323967D01*
X-92200Y1324766D01*
X-91800Y1325967D01*
Y1331700D01*
G01X-88300Y1323700D02*
Y1331700D01*
X-83700Y1323700D01*
Y1331700D01*
G01X-80200Y1323700D02*
Y1331700D01*
X-78200D01*
X-77400Y1331300D01*
X-76800Y1330767D01*
X-76300Y1329967D01*
X-75900Y1329033D01*
X-75800Y1327700D01*
X-75900Y1326367D01*
X-76300Y1325433D01*
X-76800Y1324633D01*
X-77400Y1324100D01*
X-78200Y1323700D01*
X-80200D01*
G01X-71200Y1331700D02*
X-68800D01*
G01X-70000D02*
Y1323700D01*
G01X-71200D02*
X-68800D01*
G01X-64300D02*
Y1331700D01*
X-59700Y1323700D01*
Y1331700D01*
G01X-53400Y1327700D02*
X-51400D01*
Y1325300D01*
X-52000Y1324500D01*
X-52700Y1323967D01*
X-53700Y1323700D01*
X-54700Y1323967D01*
X-55400Y1324500D01*
X-56000Y1325300D01*
X-56400Y1326233D01*
X-56600Y1327300D01*
Y1328233D01*
X-56400Y1329033D01*
X-56000Y1329967D01*
X-55400Y1330767D01*
X-54800Y1331300D01*
X-54000Y1331700D01*
X-53300D01*
X-52500Y1331433D01*
X-51900Y1330900D01*
G01X-40100Y1324766D02*
X-39300Y1324100D01*
X-38400Y1323700D01*
X-37600D01*
X-36800Y1324100D01*
X-36200Y1324766D01*
X-35900Y1325700D01*
X-36100Y1326633D01*
X-36600Y1327433D01*
X-37500Y1327967D01*
X-38700Y1328233D01*
X-39400Y1328767D01*
X-39700Y1329700D01*
X-39500Y1330633D01*
X-39000Y1331300D01*
X-38300Y1331700D01*
X-37600D01*
X-36900Y1331433D01*
X-36300Y1330767D01*
G01X-27800Y1331033D02*
X-28400Y1331433D01*
X-29100Y1331700D01*
X-29900D01*
X-30800Y1331300D01*
X-31500Y1330633D01*
X-32000Y1329833D01*
X-32400Y1328500D01*
X-32500Y1327300D01*
X-32300Y1326100D01*
X-32000Y1325300D01*
X-31400Y1324500D01*
X-30700Y1323967D01*
X-30000Y1323700D01*
X-29300D01*
X-28600Y1323967D01*
X-28000Y1324367D01*
X-27500Y1324900D01*
G01X-24000Y1323700D02*
Y1331700D01*
X-21500D01*
X-20700Y1331300D01*
X-20200Y1330767D01*
X-20000Y1329700D01*
X-20200Y1328633D01*
X-20800Y1327967D01*
X-21500Y1327567D01*
X-24000D01*
G01X-21500D02*
X-20000Y1323700D01*
G01X-12000D02*
X-16000D01*
Y1331700D01*
X-12000D01*
G01X-13600Y1327833D02*
X-16000D01*
G01X-9000Y1331700D02*
X-7600Y1323700D01*
X-6000Y1331700D01*
X-4400Y1323700D01*
X-3000Y1331700D01*
G01X2000Y1323433D02*
X1800Y1323567D01*
Y1323833D01*
X2000Y1323967D01*
X2200Y1323833D01*
Y1323567D01*
X2000Y1323433D01*
G01X9500Y1321033D02*
X8500Y1322367D01*
X8000Y1323700D01*
Y1329033D01*
X8500Y1330367D01*
X9500Y1331700D01*
G01X16000Y1323700D02*
Y1331700D01*
X18400D01*
X19200Y1331300D01*
X19800Y1330367D01*
X20000Y1329300D01*
X19800Y1328233D01*
X19300Y1327433D01*
X18400Y1327033D01*
X16000D01*
G01X24000Y1331700D02*
Y1323700D01*
X28000D01*
G01X36000D02*
X32000D01*
Y1331700D01*
X36000D01*
G01X34400Y1327833D02*
X32000D01*
G01X39500Y1323700D02*
X42000Y1331700D01*
X44500Y1323700D01*
G01X43600Y1326500D02*
X40400D01*
G01X47900Y1324766D02*
X48700Y1324100D01*
X49600Y1323700D01*
X50400D01*
X51200Y1324100D01*
X51800Y1324766D01*
X52100Y1325700D01*
X51900Y1326633D01*
X51400Y1327433D01*
X50500Y1327967D01*
X49300Y1328233D01*
X48600Y1328767D01*
X48300Y1329700D01*
X48500Y1330633D01*
X49000Y1331300D01*
X49700Y1331700D01*
X50400D01*
X51100Y1331433D01*
X51700Y1330767D01*
G01X60000Y1323700D02*
X56000D01*
Y1331700D01*
X60000D01*
G01X58400Y1327833D02*
X56000D01*
G01X72800Y1331700D02*
X75200D01*
G01X74000D02*
Y1323700D01*
G01X72800D02*
X75200D01*
G01X82600Y1327700D02*
X84600D01*
Y1325300D01*
X84000Y1324500D01*
X83300Y1323967D01*
X82300Y1323700D01*
X81300Y1323967D01*
X80600Y1324500D01*
X80000Y1325300D01*
X79600Y1326233D01*
X79400Y1327300D01*
Y1328233D01*
X79600Y1329033D01*
X80000Y1329967D01*
X80600Y1330767D01*
X81200Y1331300D01*
X82000Y1331700D01*
X82700D01*
X83500Y1331433D01*
X84100Y1330900D01*
G01X87700Y1323700D02*
Y1331700D01*
X92300Y1323700D01*
Y1331700D01*
G01X98000Y1323700D02*
X97200Y1323833D01*
X96500Y1324367D01*
X95900Y1325167D01*
X95500Y1326100D01*
X95300Y1327167D01*
Y1328233D01*
X95500Y1329300D01*
X95900Y1330233D01*
X96500Y1331033D01*
X97200Y1331567D01*
X98000Y1331700D01*
X98800Y1331567D01*
X99500Y1331033D01*
X100100Y1330233D01*
X100500Y1329300D01*
X100700Y1328233D01*
Y1327167D01*
X100500Y1326100D01*
X100100Y1325167D01*
X99500Y1324367D01*
X98800Y1323833D01*
X98000Y1323700D01*
G01X104000D02*
Y1331700D01*
X106500D01*
X107300Y1331300D01*
X107800Y1330767D01*
X108000Y1329700D01*
X107800Y1328633D01*
X107200Y1327967D01*
X106500Y1327567D01*
X104000D01*
G01X106500D02*
X108000Y1323700D01*
G01X116000D02*
X112000D01*
Y1331700D01*
X116000D01*
G01X114400Y1327833D02*
X112000D01*
G01X130000Y1331700D02*
Y1323700D01*
G01X127700Y1331700D02*
X132300D01*
G01X135900Y1323700D02*
Y1331700D01*
G01X140100D02*
Y1323700D01*
G01Y1327700D02*
X135900D01*
G01X144800Y1331700D02*
X147200D01*
G01X146000D02*
Y1323700D01*
G01X144800D02*
X147200D01*
G01X151900Y1324766D02*
X152700Y1324100D01*
X153600Y1323700D01*
X154400D01*
X155200Y1324100D01*
X155800Y1324766D01*
X156100Y1325700D01*
X155900Y1326633D01*
X155400Y1327433D01*
X154500Y1327967D01*
X153300Y1328233D01*
X152600Y1328767D01*
X152300Y1329700D01*
X152500Y1330633D01*
X153000Y1331300D01*
X153700Y1331700D01*
X154400D01*
X155100Y1331433D01*
X155700Y1330767D01*
G01X168800Y1331700D02*
X171200D01*
G01X170000D02*
Y1323700D01*
G01X168800D02*
X171200D01*
G01X176100D02*
Y1331700D01*
X179900D01*
G01X178500Y1327833D02*
X176100D01*
G01X191700Y1323700D02*
Y1331700D01*
X196300Y1323700D01*
Y1331700D01*
G01X202000Y1323700D02*
X201200Y1323833D01*
X200500Y1324367D01*
X199900Y1325167D01*
X199500Y1326100D01*
X199300Y1327167D01*
Y1328233D01*
X199500Y1329300D01*
X199900Y1330233D01*
X200500Y1331033D01*
X201200Y1331567D01*
X202000Y1331700D01*
X202800Y1331567D01*
X203500Y1331033D01*
X204100Y1330233D01*
X204500Y1329300D01*
X204700Y1328233D01*
Y1327167D01*
X204500Y1326100D01*
X204100Y1325167D01*
X203500Y1324367D01*
X202800Y1323833D01*
X202000Y1323700D01*
G01X218000Y1331700D02*
Y1323700D01*
G01X215700Y1331700D02*
X220300D01*
G01X223900Y1323700D02*
Y1331700D01*
G01X228100D02*
Y1323700D01*
G01Y1327700D02*
X223900D01*
G01X232800Y1331700D02*
X235200D01*
G01X234000D02*
Y1323700D01*
G01X232800D02*
X235200D01*
G01X239900Y1324766D02*
X240700Y1324100D01*
X241600Y1323700D01*
X242400D01*
X243200Y1324100D01*
X243800Y1324766D01*
X244100Y1325700D01*
X243900Y1326633D01*
X243400Y1327433D01*
X242500Y1327967D01*
X241300Y1328233D01*
X240600Y1328767D01*
X240300Y1329700D01*
X240500Y1330633D01*
X241000Y1331300D01*
X241700Y1331700D01*
X242400D01*
X243100Y1331433D01*
X243700Y1330767D01*
G01X256800Y1331700D02*
X259200D01*
G01X258000D02*
Y1323700D01*
G01X256800D02*
X259200D01*
G01X266000Y1331700D02*
Y1323700D01*
G01X263700Y1331700D02*
X268300D01*
G01X276000Y1323700D02*
X272000D01*
Y1331700D01*
X276000D01*
G01X274400Y1327833D02*
X272000D01*
G01X279400Y1323700D02*
Y1331700D01*
X282000Y1325033D01*
X284600Y1331700D01*
Y1323700D01*
G01X296800Y1331700D02*
X299200D01*
G01X298000D02*
Y1323700D01*
G01X296800D02*
X299200D01*
G01X303700D02*
Y1331700D01*
X308300Y1323700D01*
Y1331700D01*
G01X322800Y1327967D02*
X323200Y1328367D01*
X323500Y1329033D01*
X323700Y1329967D01*
X323500Y1330767D01*
X323100Y1331300D01*
X322400Y1331700D01*
X319700D01*
Y1323700D01*
X323000D01*
X323700Y1324233D01*
X324100Y1325033D01*
X324300Y1325967D01*
X324100Y1326900D01*
X323500Y1327700D01*
X322800Y1327967D01*
X319700D01*
G01X330000Y1323700D02*
X329200Y1323833D01*
X328500Y1324367D01*
X327900Y1325167D01*
X327500Y1326100D01*
X327300Y1327167D01*
Y1328233D01*
X327500Y1329300D01*
X327900Y1330233D01*
X328500Y1331033D01*
X329200Y1331567D01*
X330000Y1331700D01*
X330800Y1331567D01*
X331500Y1331033D01*
X332100Y1330233D01*
X332500Y1329300D01*
X332700Y1328233D01*
Y1327167D01*
X332500Y1326100D01*
X332100Y1325167D01*
X331500Y1324367D01*
X330800Y1323833D01*
X330000Y1323700D01*
G01X335500D02*
X338000Y1331700D01*
X340500Y1323700D01*
G01X339600Y1326500D02*
X336400D01*
G01X344000Y1323700D02*
Y1331700D01*
X346500D01*
X347300Y1331300D01*
X347800Y1330767D01*
X348000Y1329700D01*
X347800Y1328633D01*
X347200Y1327967D01*
X346500Y1327567D01*
X344000D01*
G01X346500D02*
X348000Y1323700D01*
G01X351800D02*
Y1331700D01*
X353800D01*
X354600Y1331300D01*
X355200Y1330767D01*
X355700Y1329967D01*
X356100Y1329033D01*
X356200Y1327700D01*
X356100Y1326367D01*
X355700Y1325433D01*
X355200Y1324633D01*
X354600Y1324100D01*
X353800Y1323700D01*
X351800D01*
G01X368100D02*
Y1331700D01*
X371900D01*
G01X370500Y1327833D02*
X368100D01*
G01X376800Y1331700D02*
X379200D01*
G01X378000D02*
Y1323700D01*
G01X376800D02*
X379200D01*
G01X384000Y1331700D02*
Y1323700D01*
X388000D01*
G01X396000D02*
X392000D01*
Y1331700D01*
X396000D01*
G01X394400Y1327833D02*
X392000D01*
G01X402500Y1321033D02*
X403500Y1322367D01*
X404000Y1323700D01*
Y1329033D01*
X403500Y1330367D01*
X402500Y1331700D01*
G01X-341200Y1342967D02*
X-340800Y1343367D01*
X-340500Y1344033D01*
X-340300Y1344967D01*
X-340500Y1345767D01*
X-340900Y1346300D01*
X-341600Y1346700D01*
X-344300D01*
Y1338700D01*
X-341000D01*
X-340300Y1339233D01*
X-339900Y1340033D01*
X-339700Y1340967D01*
X-339900Y1341900D01*
X-340500Y1342700D01*
X-341200Y1342967D01*
X-344300D01*
G01X-334000Y1338433D02*
X-334200Y1338567D01*
Y1338833D01*
X-334000Y1338967D01*
X-333800Y1338833D01*
Y1338567D01*
X-334000Y1338433D01*
G01X-328500Y1338700D02*
X-326000Y1346700D01*
X-323500Y1338700D01*
G01X-324400Y1341500D02*
X-327600D01*
G01X-320000Y1346700D02*
Y1338700D01*
X-316000D01*
G01X-312000Y1346700D02*
Y1338700D01*
X-308000D01*
G01X-296500Y1346700D02*
X-294000Y1338700D01*
X-291500Y1346700D01*
G01X-287200D02*
X-284800D01*
G01X-286000D02*
Y1338700D01*
G01X-287200D02*
X-284800D01*
G01X-280500D02*
X-278000Y1346700D01*
X-275500Y1338700D01*
G01X-276400Y1341500D02*
X-279600D01*
G01X-272100Y1339766D02*
X-271300Y1339100D01*
X-270400Y1338700D01*
X-269600D01*
X-268800Y1339100D01*
X-268200Y1339766D01*
X-267900Y1340700D01*
X-268100Y1341633D01*
X-268600Y1342433D01*
X-269500Y1342967D01*
X-270700Y1343233D01*
X-271400Y1343767D01*
X-271700Y1344700D01*
X-271500Y1345633D01*
X-271000Y1346300D01*
X-270300Y1346700D01*
X-269600D01*
X-268900Y1346433D01*
X-268300Y1345767D01*
G01X-256000Y1338700D02*
Y1346700D01*
X-253600D01*
X-252800Y1346300D01*
X-252200Y1345367D01*
X-252000Y1344300D01*
X-252200Y1343233D01*
X-252700Y1342433D01*
X-253600Y1342033D01*
X-256000D01*
G01X-248000Y1346700D02*
Y1338700D01*
X-244000D01*
G01X-240200Y1346700D02*
Y1340967D01*
X-239800Y1339766D01*
X-239000Y1338967D01*
X-238000Y1338700D01*
X-237000Y1338967D01*
X-236200Y1339766D01*
X-235800Y1340967D01*
Y1346700D01*
G01X-229400Y1342700D02*
X-227400D01*
Y1340300D01*
X-228000Y1339500D01*
X-228700Y1338967D01*
X-229700Y1338700D01*
X-230700Y1338967D01*
X-231400Y1339500D01*
X-232000Y1340300D01*
X-232400Y1341233D01*
X-232600Y1342300D01*
Y1343233D01*
X-232400Y1344033D01*
X-232000Y1344967D01*
X-231400Y1345767D01*
X-230800Y1346300D01*
X-230000Y1346700D01*
X-229300D01*
X-228500Y1346433D01*
X-227900Y1345900D01*
G01X-221400Y1342700D02*
X-219400D01*
Y1340300D01*
X-220000Y1339500D01*
X-220700Y1338967D01*
X-221700Y1338700D01*
X-222700Y1338967D01*
X-223400Y1339500D01*
X-224000Y1340300D01*
X-224400Y1341233D01*
X-224600Y1342300D01*
Y1343233D01*
X-224400Y1344033D01*
X-224000Y1344967D01*
X-223400Y1345767D01*
X-222800Y1346300D01*
X-222000Y1346700D01*
X-221300D01*
X-220500Y1346433D01*
X-219900Y1345900D01*
G01X-212000Y1338700D02*
X-216000D01*
Y1346700D01*
X-212000D01*
G01X-213600Y1342833D02*
X-216000D01*
G01X-208200Y1338700D02*
Y1346700D01*
X-206200D01*
X-205400Y1346300D01*
X-204800Y1345767D01*
X-204300Y1344967D01*
X-203900Y1344033D01*
X-203800Y1342700D01*
X-203900Y1341367D01*
X-204300Y1340433D01*
X-204800Y1339633D01*
X-205400Y1339100D01*
X-206200Y1338700D01*
X-208200D01*
G01X-188000D02*
X-192000D01*
Y1346700D01*
X-188000D01*
G01X-189600Y1342833D02*
X-192000D01*
G01X-184100Y1338700D02*
X-179900Y1346700D01*
G01X-184100D02*
X-179900Y1338700D01*
G01X-171800Y1346033D02*
X-172400Y1346433D01*
X-173100Y1346700D01*
X-173900D01*
X-174800Y1346300D01*
X-175500Y1345633D01*
X-176000Y1344833D01*
X-176400Y1343500D01*
X-176500Y1342300D01*
X-176300Y1341100D01*
X-176000Y1340300D01*
X-175400Y1339500D01*
X-174700Y1338967D01*
X-174000Y1338700D01*
X-173300D01*
X-172600Y1338967D01*
X-172000Y1339367D01*
X-171500Y1339900D01*
G01X-164000Y1338700D02*
X-168000D01*
Y1346700D01*
X-164000D01*
G01X-165600Y1342833D02*
X-168000D01*
G01X-160000Y1338700D02*
Y1346700D01*
X-157600D01*
X-156800Y1346300D01*
X-156200Y1345367D01*
X-156000Y1344300D01*
X-156200Y1343233D01*
X-156700Y1342433D01*
X-157600Y1342033D01*
X-160000D01*
G01X-150000Y1346700D02*
Y1338700D01*
G01X-152300Y1346700D02*
X-147700D01*
G01X-135900Y1338700D02*
Y1346700D01*
X-132100D01*
G01X-133500Y1342833D02*
X-135900D01*
G01X-126000Y1338700D02*
X-126800Y1338833D01*
X-127500Y1339367D01*
X-128100Y1340167D01*
X-128500Y1341100D01*
X-128700Y1342167D01*
Y1343233D01*
X-128500Y1344300D01*
X-128100Y1345233D01*
X-127500Y1346033D01*
X-126800Y1346567D01*
X-126000Y1346700D01*
X-125200Y1346567D01*
X-124500Y1346033D01*
X-123900Y1345233D01*
X-123500Y1344300D01*
X-123300Y1343233D01*
Y1342167D01*
X-123500Y1341100D01*
X-123900Y1340167D01*
X-124500Y1339367D01*
X-125200Y1338833D01*
X-126000Y1338700D01*
G01X-120000D02*
Y1346700D01*
X-117500D01*
X-116700Y1346300D01*
X-116200Y1345767D01*
X-116000Y1344700D01*
X-116200Y1343633D01*
X-116800Y1342967D01*
X-117500Y1342567D01*
X-120000D01*
G01X-117500D02*
X-116000Y1338700D01*
G01X-344500Y1353700D02*
X-342000Y1361700D01*
X-339500Y1353700D01*
G01X-340400Y1356500D02*
X-343600D01*
G01X-334000Y1353433D02*
X-334200Y1353567D01*
Y1353833D01*
X-334000Y1353967D01*
X-333800Y1353833D01*
Y1353567D01*
X-334000Y1353433D01*
G01X-328500Y1361700D02*
X-326000Y1353700D01*
X-323500Y1361700D01*
G01X-319200D02*
X-316800D01*
G01X-318000D02*
Y1353700D01*
G01X-319200D02*
X-316800D01*
G01X-312500D02*
X-310000Y1361700D01*
X-307500Y1353700D01*
G01X-308400Y1356500D02*
X-311600D01*
G01X-294000Y1361700D02*
Y1353700D01*
G01X-296300Y1361700D02*
X-291700D01*
G01X-284000Y1353700D02*
X-288000D01*
Y1361700D01*
X-284000D01*
G01X-285600Y1357833D02*
X-288000D01*
G01X-280500Y1353700D02*
X-278000Y1361700D01*
X-275500Y1353700D01*
G01X-276400Y1356500D02*
X-279600D01*
G01X-272000Y1353700D02*
Y1361700D01*
X-269500D01*
X-268700Y1361300D01*
X-268200Y1360767D01*
X-268000Y1359700D01*
X-268200Y1358633D01*
X-268800Y1357967D01*
X-269500Y1357567D01*
X-272000D01*
G01X-269500D02*
X-268000Y1353700D01*
G01X-256200D02*
Y1361700D01*
X-254200D01*
X-253400Y1361300D01*
X-252800Y1360767D01*
X-252300Y1359967D01*
X-251900Y1359033D01*
X-251800Y1357700D01*
X-251900Y1356367D01*
X-252300Y1355433D01*
X-252800Y1354633D01*
X-253400Y1354100D01*
X-254200Y1353700D01*
X-256200D01*
G01X-248000D02*
Y1361700D01*
X-245500D01*
X-244700Y1361300D01*
X-244200Y1360767D01*
X-244000Y1359700D01*
X-244200Y1358633D01*
X-244800Y1357967D01*
X-245500Y1357567D01*
X-248000D01*
G01X-245500D02*
X-244000Y1353700D01*
G01X-238000D02*
X-238800Y1353833D01*
X-239500Y1354367D01*
X-240100Y1355167D01*
X-240500Y1356100D01*
X-240700Y1357167D01*
Y1358233D01*
X-240500Y1359300D01*
X-240100Y1360233D01*
X-239500Y1361033D01*
X-238800Y1361567D01*
X-238000Y1361700D01*
X-237200Y1361567D01*
X-236500Y1361033D01*
X-235900Y1360233D01*
X-235500Y1359300D01*
X-235300Y1358233D01*
Y1357167D01*
X-235500Y1356100D01*
X-235900Y1355167D01*
X-236500Y1354367D01*
X-237200Y1353833D01*
X-238000Y1353700D01*
G01X-232000D02*
Y1361700D01*
X-229600D01*
X-228800Y1361300D01*
X-228200Y1360367D01*
X-228000Y1359300D01*
X-228200Y1358233D01*
X-228700Y1357433D01*
X-229600Y1357033D01*
X-232000D01*
G01X-214500Y1351033D02*
X-215500Y1352367D01*
X-216000Y1353700D01*
Y1359033D01*
X-215500Y1360367D01*
X-214500Y1361700D01*
G01X-207900Y1353700D02*
Y1361700D01*
X-204100D01*
G01X-205500Y1357833D02*
X-207900D01*
G01X-198000Y1353700D02*
X-198800Y1353833D01*
X-199500Y1354367D01*
X-200100Y1355167D01*
X-200500Y1356100D01*
X-200700Y1357167D01*
Y1358233D01*
X-200500Y1359300D01*
X-200100Y1360233D01*
X-199500Y1361033D01*
X-198800Y1361567D01*
X-198000Y1361700D01*
X-197200Y1361567D01*
X-196500Y1361033D01*
X-195900Y1360233D01*
X-195500Y1359300D01*
X-195300Y1358233D01*
Y1357167D01*
X-195500Y1356100D01*
X-195900Y1355167D01*
X-196500Y1354367D01*
X-197200Y1353833D01*
X-198000Y1353700D01*
G01X-192000D02*
Y1361700D01*
X-189500D01*
X-188700Y1361300D01*
X-188200Y1360767D01*
X-188000Y1359700D01*
X-188200Y1358633D01*
X-188800Y1357967D01*
X-189500Y1357567D01*
X-192000D01*
G01X-189500D02*
X-188000Y1353700D01*
G01X-176500D02*
X-174000Y1361700D01*
X-171500Y1353700D01*
G01X-172400Y1356500D02*
X-175600D01*
G01X-168000Y1361700D02*
Y1353700D01*
X-164000D01*
G01X-160000Y1361700D02*
Y1353700D01*
X-156000D01*
G01X-144500Y1361700D02*
X-142000Y1353700D01*
X-139500Y1361700D01*
G01X-135200D02*
X-132800D01*
G01X-134000D02*
Y1353700D01*
G01X-135200D02*
X-132800D01*
G01X-128500D02*
X-126000Y1361700D01*
X-123500Y1353700D01*
G01X-124400Y1356500D02*
X-127600D01*
G01X-120100Y1354766D02*
X-119300Y1354100D01*
X-118400Y1353700D01*
X-117600D01*
X-116800Y1354100D01*
X-116200Y1354766D01*
X-115900Y1355700D01*
X-116100Y1356633D01*
X-116600Y1357433D01*
X-117500Y1357967D01*
X-118700Y1358233D01*
X-119400Y1358767D01*
X-119700Y1359700D01*
X-119500Y1360633D01*
X-119000Y1361300D01*
X-118300Y1361700D01*
X-117600D01*
X-116900Y1361433D01*
X-116300Y1360767D01*
G01X-104500Y1353700D02*
X-102000Y1361700D01*
X-99500Y1353700D01*
G01X-100400Y1356500D02*
X-103600D01*
G01X-96300Y1353700D02*
Y1361700D01*
X-91700Y1353700D01*
Y1361700D01*
G01X-88200Y1353700D02*
Y1361700D01*
X-86200D01*
X-85400Y1361300D01*
X-84800Y1360767D01*
X-84300Y1359967D01*
X-83900Y1359033D01*
X-83800Y1357700D01*
X-83900Y1356367D01*
X-84300Y1355433D01*
X-84800Y1354633D01*
X-85400Y1354100D01*
X-86200Y1353700D01*
X-88200D01*
G01X-72000D02*
Y1361700D01*
X-69600D01*
X-68800Y1361300D01*
X-68200Y1360367D01*
X-68000Y1359300D01*
X-68200Y1358233D01*
X-68700Y1357433D01*
X-69600Y1357033D01*
X-72000D01*
G01X-63200Y1361700D02*
X-60800D01*
G01X-62000D02*
Y1353700D01*
G01X-63200D02*
X-60800D01*
G01X-56300D02*
Y1361700D01*
X-51700Y1353700D01*
Y1361700D01*
G01X-48100Y1354766D02*
X-47300Y1354100D01*
X-46400Y1353700D01*
X-45600D01*
X-44800Y1354100D01*
X-44200Y1354766D01*
X-43900Y1355700D01*
X-44100Y1356633D01*
X-44600Y1357433D01*
X-45500Y1357967D01*
X-46700Y1358233D01*
X-47400Y1358767D01*
X-47700Y1359700D01*
X-47500Y1360633D01*
X-47000Y1361300D01*
X-46300Y1361700D01*
X-45600D01*
X-44900Y1361433D01*
X-44300Y1360767D01*
G01X-37500Y1351033D02*
X-36500Y1352367D01*
X-36000Y1353700D01*
Y1359033D01*
X-36500Y1360367D01*
X-37500Y1361700D01*
G01X-30000Y1353433D02*
X-30200Y1353567D01*
Y1353833D01*
X-30000Y1353967D01*
X-29800Y1353833D01*
Y1353567D01*
X-30000Y1353433D01*
G01X-286378Y847207D02*
X-329685D01*
G01X-286378Y862956D02*
X-329685D01*
G01X-324700Y874760D02*
X-337200D01*
X-328242Y869025D01*
Y876775D01*
G01X-324700Y881270D02*
X-337200D01*
X-326783Y885300D01*
X-337200Y889330D01*
X-324700D01*
G01Y893670D02*
X-337200D01*
X-326783Y897700D01*
X-337200Y901730D01*
X-324700D01*
G01X-334200Y1012967D02*
X-333800Y1013367D01*
X-333500Y1014033D01*
X-333300Y1014967D01*
X-333500Y1015767D01*
X-333900Y1016300D01*
X-334600Y1016700D01*
X-337300D01*
Y1008700D01*
X-334000D01*
X-333300Y1009233D01*
X-332900Y1010033D01*
X-332700Y1010967D01*
X-332900Y1011900D01*
X-333500Y1012700D01*
X-334200Y1012967D01*
X-337300D01*
G01X-327000Y1008433D02*
X-327200Y1008567D01*
Y1008833D01*
X-327000Y1008967D01*
X-326800Y1008833D01*
Y1008567D01*
X-327000Y1008433D01*
G01X-320200Y1016700D02*
X-317800D01*
G01X-319000D02*
Y1008700D01*
G01X-320200D02*
X-317800D01*
G01X-312900D02*
Y1016700D01*
X-309100D01*
G01X-310500Y1012833D02*
X-312900D01*
G01X-295000Y1016700D02*
Y1008700D01*
G01X-297300Y1016700D02*
X-292700D01*
G01X-289100Y1008700D02*
Y1016700D01*
G01X-284900D02*
Y1008700D01*
G01Y1012700D02*
X-289100D01*
G01X-277000Y1008700D02*
X-281000D01*
Y1016700D01*
X-277000D01*
G01X-278600Y1012833D02*
X-281000D01*
G01X-265000Y1008700D02*
Y1016700D01*
X-262600D01*
X-261800Y1016300D01*
X-261200Y1015367D01*
X-261000Y1014300D01*
X-261200Y1013233D01*
X-261700Y1012433D01*
X-262600Y1012033D01*
X-265000D01*
G01X-255000Y1016700D02*
Y1008700D01*
G01X-257300Y1016700D02*
X-252700D01*
G01X-249100Y1008700D02*
Y1016700D01*
G01X-244900D02*
Y1008700D01*
G01Y1012700D02*
X-249100D01*
G01X-231000Y1016700D02*
Y1008700D01*
G01X-233300Y1016700D02*
X-228700D01*
G01X-223000Y1008700D02*
X-223800Y1008833D01*
X-224500Y1009367D01*
X-225100Y1010167D01*
X-225500Y1011100D01*
X-225700Y1012167D01*
Y1013233D01*
X-225500Y1014300D01*
X-225100Y1015233D01*
X-224500Y1016033D01*
X-223800Y1016567D01*
X-223000Y1016700D01*
X-222200Y1016567D01*
X-221500Y1016033D01*
X-220900Y1015233D01*
X-220500Y1014300D01*
X-220300Y1013233D01*
Y1012167D01*
X-220500Y1011100D01*
X-220900Y1010167D01*
X-221500Y1009367D01*
X-222200Y1008833D01*
X-223000Y1008700D01*
G01X-215000D02*
X-215800Y1008833D01*
X-216500Y1009367D01*
X-217100Y1010167D01*
X-217500Y1011100D01*
X-217700Y1012167D01*
Y1013233D01*
X-217500Y1014300D01*
X-217100Y1015233D01*
X-216500Y1016033D01*
X-215800Y1016567D01*
X-215000Y1016700D01*
X-214200Y1016567D01*
X-213500Y1016033D01*
X-212900Y1015233D01*
X-212500Y1014300D01*
X-212300Y1013233D01*
Y1012167D01*
X-212500Y1011100D01*
X-212900Y1010167D01*
X-213500Y1009367D01*
X-214200Y1008833D01*
X-215000Y1008700D01*
G01X-209000Y1016700D02*
Y1008700D01*
X-205000D01*
G01X-200200Y1016700D02*
X-197800D01*
G01X-199000D02*
Y1008700D01*
G01X-200200D02*
X-197800D01*
G01X-193300D02*
Y1016700D01*
X-188700Y1008700D01*
Y1016700D01*
G01X-182400Y1012700D02*
X-180400D01*
Y1010300D01*
X-181000Y1009500D01*
X-181700Y1008967D01*
X-182700Y1008700D01*
X-183700Y1008967D01*
X-184400Y1009500D01*
X-185000Y1010300D01*
X-185400Y1011233D01*
X-185600Y1012300D01*
Y1013233D01*
X-185400Y1014033D01*
X-185000Y1014967D01*
X-184400Y1015767D01*
X-183800Y1016300D01*
X-183000Y1016700D01*
X-182300D01*
X-181500Y1016433D01*
X-180900Y1015900D01*
G01X-169100Y1008700D02*
Y1016700D01*
G01X-164900D02*
Y1008700D01*
G01Y1012700D02*
X-169100D01*
G01X-159000Y1008700D02*
X-159800Y1008833D01*
X-160500Y1009367D01*
X-161100Y1010167D01*
X-161500Y1011100D01*
X-161700Y1012167D01*
Y1013233D01*
X-161500Y1014300D01*
X-161100Y1015233D01*
X-160500Y1016033D01*
X-159800Y1016567D01*
X-159000Y1016700D01*
X-158200Y1016567D01*
X-157500Y1016033D01*
X-156900Y1015233D01*
X-156500Y1014300D01*
X-156300Y1013233D01*
Y1012167D01*
X-156500Y1011100D01*
X-156900Y1010167D01*
X-157500Y1009367D01*
X-158200Y1008833D01*
X-159000Y1008700D01*
G01X-153000Y1016700D02*
Y1008700D01*
X-149000D01*
G01X-141000D02*
X-145000D01*
Y1016700D01*
X-141000D01*
G01X-142600Y1012833D02*
X-145000D01*
G01X-128200Y1016700D02*
X-125800D01*
G01X-127000D02*
Y1008700D01*
G01X-128200D02*
X-125800D01*
G01X-121100Y1009766D02*
X-120300Y1009100D01*
X-119400Y1008700D01*
X-118600D01*
X-117800Y1009100D01*
X-117200Y1009766D01*
X-116900Y1010700D01*
X-117100Y1011633D01*
X-117600Y1012433D01*
X-118500Y1012967D01*
X-119700Y1013233D01*
X-120400Y1013767D01*
X-120700Y1014700D01*
X-120500Y1015633D01*
X-120000Y1016300D01*
X-119300Y1016700D01*
X-118600D01*
X-117900Y1016433D01*
X-117300Y1015767D01*
G01X-105600Y1008700D02*
Y1016700D01*
X-103000Y1010033D01*
X-100400Y1016700D01*
Y1008700D01*
G01X-97500D02*
X-95000Y1016700D01*
X-92500Y1008700D01*
G01X-93400Y1011500D02*
X-96600D01*
G01X-89200Y1008700D02*
Y1016700D01*
X-87200D01*
X-86400Y1016300D01*
X-85800Y1015767D01*
X-85300Y1014967D01*
X-84900Y1014033D01*
X-84800Y1012700D01*
X-84900Y1011367D01*
X-85300Y1010433D01*
X-85800Y1009633D01*
X-86400Y1009100D01*
X-87200Y1008700D01*
X-89200D01*
G01X-77000D02*
X-81000D01*
Y1016700D01*
X-77000D01*
G01X-78600Y1012833D02*
X-81000D01*
G01X-62200Y1012967D02*
X-61800Y1013367D01*
X-61500Y1014033D01*
X-61300Y1014967D01*
X-61500Y1015767D01*
X-61900Y1016300D01*
X-62600Y1016700D01*
X-65300D01*
Y1008700D01*
X-62000D01*
X-61300Y1009233D01*
X-60900Y1010033D01*
X-60700Y1010967D01*
X-60900Y1011900D01*
X-61500Y1012700D01*
X-62200Y1012967D01*
X-65300D01*
G01X-55000Y1008700D02*
Y1012300D01*
X-57000Y1016700D01*
G01X-53000D02*
X-55000Y1012300D01*
G01X-41000Y1008700D02*
Y1016700D01*
X-38500D01*
X-37700Y1016300D01*
X-37200Y1015767D01*
X-37000Y1014700D01*
X-37200Y1013633D01*
X-37800Y1012967D01*
X-38500Y1012567D01*
X-41000D01*
G01X-38500D02*
X-37000Y1008700D01*
G01X-31000D02*
X-31800Y1008833D01*
X-32500Y1009367D01*
X-33100Y1010167D01*
X-33500Y1011100D01*
X-33700Y1012167D01*
Y1013233D01*
X-33500Y1014300D01*
X-33100Y1015233D01*
X-32500Y1016033D01*
X-31800Y1016567D01*
X-31000Y1016700D01*
X-30200Y1016567D01*
X-29500Y1016033D01*
X-28900Y1015233D01*
X-28500Y1014300D01*
X-28300Y1013233D01*
Y1012167D01*
X-28500Y1011100D01*
X-28900Y1010167D01*
X-29500Y1009367D01*
X-30200Y1008833D01*
X-31000Y1008700D01*
G01X-25200Y1016700D02*
Y1010967D01*
X-24800Y1009766D01*
X-24000Y1008967D01*
X-23000Y1008700D01*
X-22000Y1008967D01*
X-21200Y1009766D01*
X-20800Y1010967D01*
Y1016700D01*
G01X-15000D02*
Y1008700D01*
G01X-17300Y1016700D02*
X-12700D01*
G01X-8200D02*
X-5800D01*
G01X-7000D02*
Y1008700D01*
G01X-8200D02*
X-5800D01*
G01X-1300D02*
Y1016700D01*
X3300Y1008700D01*
Y1016700D01*
G01X9600Y1012700D02*
X11600D01*
Y1010300D01*
X11000Y1009500D01*
X10300Y1008967D01*
X9300Y1008700D01*
X8300Y1008967D01*
X7600Y1009500D01*
X7000Y1010300D01*
X6600Y1011233D01*
X6400Y1012300D01*
Y1013233D01*
X6600Y1014033D01*
X7000Y1014967D01*
X7600Y1015767D01*
X8200Y1016300D01*
X9000Y1016700D01*
X9700D01*
X10500Y1016433D01*
X11100Y1015900D01*
G01X16800Y1007233D02*
X17200Y1008967D01*
G01X30700Y1008700D02*
Y1016700D01*
X35300Y1008700D01*
Y1016700D01*
G01X41000Y1008700D02*
X40200Y1008833D01*
X39500Y1009367D01*
X38900Y1010167D01*
X38500Y1011100D01*
X38300Y1012167D01*
Y1013233D01*
X38500Y1014300D01*
X38900Y1015233D01*
X39500Y1016033D01*
X40200Y1016567D01*
X41000Y1016700D01*
X41800Y1016567D01*
X42500Y1016033D01*
X43100Y1015233D01*
X43500Y1014300D01*
X43700Y1013233D01*
Y1012167D01*
X43500Y1011100D01*
X43100Y1010167D01*
X42500Y1009367D01*
X41800Y1008833D01*
X41000Y1008700D01*
G01X46700D02*
Y1016700D01*
X51300Y1008700D01*
Y1016700D01*
G01X55700Y1011367D02*
X58300D01*
G01X63100Y1008700D02*
Y1016700D01*
X66900D01*
G01X65500Y1012833D02*
X63100D01*
G01X70800Y1016700D02*
Y1010967D01*
X71200Y1009766D01*
X72000Y1008967D01*
X73000Y1008700D01*
X74000Y1008967D01*
X74800Y1009766D01*
X75200Y1010967D01*
Y1016700D01*
G01X78700Y1008700D02*
Y1016700D01*
X83300Y1008700D01*
Y1016700D01*
G01X91200Y1016033D02*
X90600Y1016433D01*
X89900Y1016700D01*
X89100D01*
X88200Y1016300D01*
X87500Y1015633D01*
X87000Y1014833D01*
X86600Y1013500D01*
X86500Y1012300D01*
X86700Y1011100D01*
X87000Y1010300D01*
X87600Y1009500D01*
X88300Y1008967D01*
X89000Y1008700D01*
X89700D01*
X90400Y1008967D01*
X91000Y1009367D01*
X91500Y1009900D01*
G01X97000Y1016700D02*
Y1008700D01*
G01X94700Y1016700D02*
X99300D01*
G01X103800D02*
X106200D01*
G01X105000D02*
Y1008700D01*
G01X103800D02*
X106200D01*
G01X113000D02*
X112200Y1008833D01*
X111500Y1009367D01*
X110900Y1010167D01*
X110500Y1011100D01*
X110300Y1012167D01*
Y1013233D01*
X110500Y1014300D01*
X110900Y1015233D01*
X111500Y1016033D01*
X112200Y1016567D01*
X113000Y1016700D01*
X113800Y1016567D01*
X114500Y1016033D01*
X115100Y1015233D01*
X115500Y1014300D01*
X115700Y1013233D01*
Y1012167D01*
X115500Y1011100D01*
X115100Y1010167D01*
X114500Y1009367D01*
X113800Y1008833D01*
X113000Y1008700D01*
G01X118700D02*
Y1016700D01*
X123300Y1008700D01*
Y1016700D01*
G01X126500Y1008700D02*
X129000Y1016700D01*
X131500Y1008700D01*
G01X130600Y1011500D02*
X127400D01*
G01X135000Y1016700D02*
Y1008700D01*
X139000D01*
G01X151000D02*
Y1016700D01*
X153400D01*
X154200Y1016300D01*
X154800Y1015367D01*
X155000Y1014300D01*
X154800Y1013233D01*
X154300Y1012433D01*
X153400Y1012033D01*
X151000D01*
G01X158500Y1008700D02*
X161000Y1016700D01*
X163500Y1008700D01*
G01X162600Y1011500D02*
X159400D01*
G01X166800Y1008700D02*
Y1016700D01*
X168800D01*
X169600Y1016300D01*
X170200Y1015767D01*
X170700Y1014967D01*
X171100Y1014033D01*
X171200Y1012700D01*
X171100Y1011367D01*
X170700Y1010433D01*
X170200Y1009633D01*
X169600Y1009100D01*
X168800Y1008700D01*
X166800D01*
G01X182900Y1009766D02*
X183700Y1009100D01*
X184600Y1008700D01*
X185400D01*
X186200Y1009100D01*
X186800Y1009766D01*
X187100Y1010700D01*
X186900Y1011633D01*
X186400Y1012433D01*
X185500Y1012967D01*
X184300Y1013233D01*
X183600Y1013767D01*
X183300Y1014700D01*
X183500Y1015633D01*
X184000Y1016300D01*
X184700Y1016700D01*
X185400D01*
X186100Y1016433D01*
X186700Y1015767D01*
G01X191800Y1016700D02*
X194200D01*
G01X193000D02*
Y1008700D01*
G01X191800D02*
X194200D01*
G01X199100Y1016700D02*
X202900D01*
X199100Y1008700D01*
X202900D01*
G01X211000D02*
X207000D01*
Y1016700D01*
X211000D01*
G01X209400Y1012833D02*
X207000D01*
G01X223800Y1016700D02*
X226200D01*
G01X225000D02*
Y1008700D01*
G01X223800D02*
X226200D01*
G01X230900Y1009766D02*
X231700Y1009100D01*
X232600Y1008700D01*
X233400D01*
X234200Y1009100D01*
X234800Y1009766D01*
X235100Y1010700D01*
X234900Y1011633D01*
X234400Y1012433D01*
X233500Y1012967D01*
X232300Y1013233D01*
X231600Y1013767D01*
X231300Y1014700D01*
X231500Y1015633D01*
X232000Y1016300D01*
X232700Y1016700D01*
X233400D01*
X234100Y1016433D01*
X234700Y1015767D01*
G01X249000Y1016700D02*
Y1008700D01*
G01X246700Y1016700D02*
X251300D01*
G01X254900Y1008700D02*
Y1016700D01*
G01X259100D02*
Y1008700D01*
G01Y1012700D02*
X254900D01*
G01X267000Y1008700D02*
X263000D01*
Y1016700D01*
X267000D01*
G01X265400Y1012833D02*
X263000D01*
G01X279000Y1008700D02*
Y1016700D01*
X281400D01*
X282200Y1016300D01*
X282800Y1015367D01*
X283000Y1014300D01*
X282800Y1013233D01*
X282300Y1012433D01*
X281400Y1012033D01*
X279000D01*
G01X287000Y1008700D02*
Y1016700D01*
X289500D01*
X290300Y1016300D01*
X290800Y1015767D01*
X291000Y1014700D01*
X290800Y1013633D01*
X290200Y1012967D01*
X289500Y1012567D01*
X287000D01*
G01X289500D02*
X291000Y1008700D01*
G01X297000D02*
X296200Y1008833D01*
X295500Y1009367D01*
X294900Y1010167D01*
X294500Y1011100D01*
X294300Y1012167D01*
Y1013233D01*
X294500Y1014300D01*
X294900Y1015233D01*
X295500Y1016033D01*
X296200Y1016567D01*
X297000Y1016700D01*
X297800Y1016567D01*
X298500Y1016033D01*
X299100Y1015233D01*
X299500Y1014300D01*
X299700Y1013233D01*
Y1012167D01*
X299500Y1011100D01*
X299100Y1010167D01*
X298500Y1009367D01*
X297800Y1008833D01*
X297000Y1008700D01*
G01X303100D02*
Y1016700D01*
X306900D01*
G01X305500Y1012833D02*
X303100D01*
G01X311800Y1016700D02*
X314200D01*
G01X313000D02*
Y1008700D01*
G01X311800D02*
X314200D01*
G01X319000Y1016700D02*
Y1008700D01*
X323000D01*
G01X331000D02*
X327000D01*
Y1016700D01*
X331000D01*
G01X329400Y1012833D02*
X327000D01*
G01X342900Y1009766D02*
X343700Y1009100D01*
X344600Y1008700D01*
X345400D01*
X346200Y1009100D01*
X346800Y1009766D01*
X347100Y1010700D01*
X346900Y1011633D01*
X346400Y1012433D01*
X345500Y1012967D01*
X344300Y1013233D01*
X343600Y1013767D01*
X343300Y1014700D01*
X343500Y1015633D01*
X344000Y1016300D01*
X344700Y1016700D01*
X345400D01*
X346100Y1016433D01*
X346700Y1015767D01*
G01X351800Y1016700D02*
X354200D01*
G01X353000D02*
Y1008700D01*
G01X351800D02*
X354200D01*
G01X359100Y1016700D02*
X362900D01*
X359100Y1008700D01*
X362900D01*
G01X371000D02*
X367000D01*
Y1016700D01*
X371000D01*
G01X369400Y1012833D02*
X367000D01*
G01X383900Y1011367D02*
X386300D01*
G01X385000Y1013100D02*
Y1009633D01*
G01X399100Y1015367D02*
X399700Y1016167D01*
X400400Y1016567D01*
X401200Y1016700D01*
X402200Y1016433D01*
X402900Y1015767D01*
X403100Y1014967D01*
X403000Y1014166D01*
X402600Y1013500D01*
X400600Y1012167D01*
X399700Y1011233D01*
X399100Y1009900D01*
X398900Y1008700D01*
X403100D01*
G01X409000Y1016700D02*
X408200Y1016433D01*
X407600Y1015767D01*
X407200Y1014967D01*
X406900Y1013900D01*
X406800Y1012700D01*
X406900Y1011500D01*
X407200Y1010433D01*
X407600Y1009633D01*
X408200Y1008967D01*
X409000Y1008700D01*
X409800Y1008967D01*
X410400Y1009633D01*
X410800Y1010433D01*
X411100Y1011500D01*
X411200Y1012700D01*
X411100Y1013900D01*
X410800Y1014967D01*
X410400Y1015767D01*
X409800Y1016433D01*
X409000Y1016700D01*
G01X414400Y1008700D02*
Y1016700D01*
X417000Y1010033D01*
X419600Y1016700D01*
Y1008700D01*
G01X423800Y1016700D02*
X426200D01*
G01X425000D02*
Y1008700D01*
G01X423800D02*
X426200D01*
G01X431000Y1016700D02*
Y1008700D01*
X435000D01*
G01X-337500Y1023700D02*
X-335000Y1031700D01*
X-332500Y1023700D01*
G01X-333400Y1026500D02*
X-336600D01*
G01X-327000Y1023433D02*
X-327200Y1023567D01*
Y1023833D01*
X-327000Y1023967D01*
X-326800Y1023833D01*
Y1023567D01*
X-327000Y1023433D01*
G01X-320200Y1031700D02*
X-317800D01*
G01X-319000D02*
Y1023700D01*
G01X-320200D02*
X-317800D01*
G01X-312900D02*
Y1031700D01*
X-309100D01*
G01X-310500Y1027833D02*
X-312900D01*
G01X-295000Y1031700D02*
Y1023700D01*
G01X-297300Y1031700D02*
X-292700D01*
G01X-289100Y1023700D02*
Y1031700D01*
G01X-284900D02*
Y1023700D01*
G01Y1027700D02*
X-289100D01*
G01X-277000Y1023700D02*
X-281000D01*
Y1031700D01*
X-277000D01*
G01X-278600Y1027833D02*
X-281000D01*
G01X-265000Y1023700D02*
Y1031700D01*
X-262600D01*
X-261800Y1031300D01*
X-261200Y1030367D01*
X-261000Y1029300D01*
X-261200Y1028233D01*
X-261700Y1027433D01*
X-262600Y1027033D01*
X-265000D01*
G01X-255000Y1031700D02*
Y1023700D01*
G01X-257300Y1031700D02*
X-252700D01*
G01X-249100Y1023700D02*
Y1031700D01*
G01X-244900D02*
Y1023700D01*
G01Y1027700D02*
X-249100D01*
G01X-231000Y1031700D02*
Y1023700D01*
G01X-233300Y1031700D02*
X-228700D01*
G01X-223000Y1023700D02*
X-223800Y1023833D01*
X-224500Y1024367D01*
X-225100Y1025167D01*
X-225500Y1026100D01*
X-225700Y1027167D01*
Y1028233D01*
X-225500Y1029300D01*
X-225100Y1030233D01*
X-224500Y1031033D01*
X-223800Y1031567D01*
X-223000Y1031700D01*
X-222200Y1031567D01*
X-221500Y1031033D01*
X-220900Y1030233D01*
X-220500Y1029300D01*
X-220300Y1028233D01*
Y1027167D01*
X-220500Y1026100D01*
X-220900Y1025167D01*
X-221500Y1024367D01*
X-222200Y1023833D01*
X-223000Y1023700D01*
G01X-215000D02*
X-215800Y1023833D01*
X-216500Y1024367D01*
X-217100Y1025167D01*
X-217500Y1026100D01*
X-217700Y1027167D01*
Y1028233D01*
X-217500Y1029300D01*
X-217100Y1030233D01*
X-216500Y1031033D01*
X-215800Y1031567D01*
X-215000Y1031700D01*
X-214200Y1031567D01*
X-213500Y1031033D01*
X-212900Y1030233D01*
X-212500Y1029300D01*
X-212300Y1028233D01*
Y1027167D01*
X-212500Y1026100D01*
X-212900Y1025167D01*
X-213500Y1024367D01*
X-214200Y1023833D01*
X-215000Y1023700D01*
G01X-209000Y1031700D02*
Y1023700D01*
X-205000D01*
G01X-200200Y1031700D02*
X-197800D01*
G01X-199000D02*
Y1023700D01*
G01X-200200D02*
X-197800D01*
G01X-193300D02*
Y1031700D01*
X-188700Y1023700D01*
Y1031700D01*
G01X-182400Y1027700D02*
X-180400D01*
Y1025300D01*
X-181000Y1024500D01*
X-181700Y1023967D01*
X-182700Y1023700D01*
X-183700Y1023967D01*
X-184400Y1024500D01*
X-185000Y1025300D01*
X-185400Y1026233D01*
X-185600Y1027300D01*
Y1028233D01*
X-185400Y1029033D01*
X-185000Y1029967D01*
X-184400Y1030767D01*
X-183800Y1031300D01*
X-183000Y1031700D01*
X-182300D01*
X-181500Y1031433D01*
X-180900Y1030900D01*
G01X-169100Y1023700D02*
Y1031700D01*
G01X-164900D02*
Y1023700D01*
G01Y1027700D02*
X-169100D01*
G01X-159000Y1023700D02*
X-159800Y1023833D01*
X-160500Y1024367D01*
X-161100Y1025167D01*
X-161500Y1026100D01*
X-161700Y1027167D01*
Y1028233D01*
X-161500Y1029300D01*
X-161100Y1030233D01*
X-160500Y1031033D01*
X-159800Y1031567D01*
X-159000Y1031700D01*
X-158200Y1031567D01*
X-157500Y1031033D01*
X-156900Y1030233D01*
X-156500Y1029300D01*
X-156300Y1028233D01*
Y1027167D01*
X-156500Y1026100D01*
X-156900Y1025167D01*
X-157500Y1024367D01*
X-158200Y1023833D01*
X-159000Y1023700D01*
G01X-153000Y1031700D02*
Y1023700D01*
X-149000D01*
G01X-141000D02*
X-145000D01*
Y1031700D01*
X-141000D01*
G01X-142600Y1027833D02*
X-145000D01*
G01X-128200Y1031700D02*
X-125800D01*
G01X-127000D02*
Y1023700D01*
G01X-128200D02*
X-125800D01*
G01X-121100Y1024766D02*
X-120300Y1024100D01*
X-119400Y1023700D01*
X-118600D01*
X-117800Y1024100D01*
X-117200Y1024766D01*
X-116900Y1025700D01*
X-117100Y1026633D01*
X-117600Y1027433D01*
X-118500Y1027967D01*
X-119700Y1028233D01*
X-120400Y1028767D01*
X-120700Y1029700D01*
X-120500Y1030633D01*
X-120000Y1031300D01*
X-119300Y1031700D01*
X-118600D01*
X-117900Y1031433D01*
X-117300Y1030767D01*
G01X-105600Y1023700D02*
Y1031700D01*
X-103000Y1025033D01*
X-100400Y1031700D01*
Y1023700D01*
G01X-97500D02*
X-95000Y1031700D01*
X-92500Y1023700D01*
G01X-93400Y1026500D02*
X-96600D01*
G01X-89200Y1023700D02*
Y1031700D01*
X-87200D01*
X-86400Y1031300D01*
X-85800Y1030767D01*
X-85300Y1029967D01*
X-84900Y1029033D01*
X-84800Y1027700D01*
X-84900Y1026367D01*
X-85300Y1025433D01*
X-85800Y1024633D01*
X-86400Y1024100D01*
X-87200Y1023700D01*
X-89200D01*
G01X-77000D02*
X-81000D01*
Y1031700D01*
X-77000D01*
G01X-78600Y1027833D02*
X-81000D01*
G01X-62200Y1027967D02*
X-61800Y1028367D01*
X-61500Y1029033D01*
X-61300Y1029967D01*
X-61500Y1030767D01*
X-61900Y1031300D01*
X-62600Y1031700D01*
X-65300D01*
Y1023700D01*
X-62000D01*
X-61300Y1024233D01*
X-60900Y1025033D01*
X-60700Y1025967D01*
X-60900Y1026900D01*
X-61500Y1027700D01*
X-62200Y1027967D01*
X-65300D01*
G01X-55000Y1023700D02*
Y1027300D01*
X-57000Y1031700D01*
G01X-53000D02*
X-55000Y1027300D01*
G01X-41200Y1023700D02*
Y1031700D01*
X-39200D01*
X-38400Y1031300D01*
X-37800Y1030767D01*
X-37300Y1029967D01*
X-36900Y1029033D01*
X-36800Y1027700D01*
X-36900Y1026367D01*
X-37300Y1025433D01*
X-37800Y1024633D01*
X-38400Y1024100D01*
X-39200Y1023700D01*
X-41200D01*
G01X-33000D02*
Y1031700D01*
X-30500D01*
X-29700Y1031300D01*
X-29200Y1030767D01*
X-29000Y1029700D01*
X-29200Y1028633D01*
X-29800Y1027967D01*
X-30500Y1027567D01*
X-33000D01*
G01X-30500D02*
X-29000Y1023700D01*
G01X-24200Y1031700D02*
X-21800D01*
G01X-23000D02*
Y1023700D01*
G01X-24200D02*
X-21800D01*
G01X-17000Y1031700D02*
Y1023700D01*
X-13000D01*
G01X-9000Y1031700D02*
Y1023700D01*
X-5000D01*
G01X-200Y1031700D02*
X2200D01*
G01X1000D02*
Y1023700D01*
G01X-200D02*
X2200D01*
G01X6700D02*
Y1031700D01*
X11300Y1023700D01*
Y1031700D01*
G01X17600Y1027700D02*
X19600D01*
Y1025300D01*
X19000Y1024500D01*
X18300Y1023967D01*
X17300Y1023700D01*
X16300Y1023967D01*
X15600Y1024500D01*
X15000Y1025300D01*
X14600Y1026233D01*
X14400Y1027300D01*
Y1028233D01*
X14600Y1029033D01*
X15000Y1029967D01*
X15600Y1030767D01*
X16200Y1031300D01*
X17000Y1031700D01*
X17700D01*
X18500Y1031433D01*
X19100Y1030900D01*
G01X24800Y1022233D02*
X25200Y1023967D01*
G01X38700Y1023700D02*
Y1031700D01*
X43300Y1023700D01*
Y1031700D01*
G01X49000Y1023700D02*
X48200Y1023833D01*
X47500Y1024367D01*
X46900Y1025167D01*
X46500Y1026100D01*
X46300Y1027167D01*
Y1028233D01*
X46500Y1029300D01*
X46900Y1030233D01*
X47500Y1031033D01*
X48200Y1031567D01*
X49000Y1031700D01*
X49800Y1031567D01*
X50500Y1031033D01*
X51100Y1030233D01*
X51500Y1029300D01*
X51700Y1028233D01*
Y1027167D01*
X51500Y1026100D01*
X51100Y1025167D01*
X50500Y1024367D01*
X49800Y1023833D01*
X49000Y1023700D01*
G01X54700D02*
Y1031700D01*
X59300Y1023700D01*
Y1031700D01*
G01X63700Y1026367D02*
X66300D01*
G01X71100Y1023700D02*
Y1031700D01*
X74900D01*
G01X73500Y1027833D02*
X71100D01*
G01X78800Y1031700D02*
Y1025967D01*
X79200Y1024766D01*
X80000Y1023967D01*
X81000Y1023700D01*
X82000Y1023967D01*
X82800Y1024766D01*
X83200Y1025967D01*
Y1031700D01*
G01X86700Y1023700D02*
Y1031700D01*
X91300Y1023700D01*
Y1031700D01*
G01X99200Y1031033D02*
X98600Y1031433D01*
X97900Y1031700D01*
X97100D01*
X96200Y1031300D01*
X95500Y1030633D01*
X95000Y1029833D01*
X94600Y1028500D01*
X94500Y1027300D01*
X94700Y1026100D01*
X95000Y1025300D01*
X95600Y1024500D01*
X96300Y1023967D01*
X97000Y1023700D01*
X97700D01*
X98400Y1023967D01*
X99000Y1024367D01*
X99500Y1024900D01*
G01X105000Y1031700D02*
Y1023700D01*
G01X102700Y1031700D02*
X107300D01*
G01X111800D02*
X114200D01*
G01X113000D02*
Y1023700D01*
G01X111800D02*
X114200D01*
G01X121000D02*
X120200Y1023833D01*
X119500Y1024367D01*
X118900Y1025167D01*
X118500Y1026100D01*
X118300Y1027167D01*
Y1028233D01*
X118500Y1029300D01*
X118900Y1030233D01*
X119500Y1031033D01*
X120200Y1031567D01*
X121000Y1031700D01*
X121800Y1031567D01*
X122500Y1031033D01*
X123100Y1030233D01*
X123500Y1029300D01*
X123700Y1028233D01*
Y1027167D01*
X123500Y1026100D01*
X123100Y1025167D01*
X122500Y1024367D01*
X121800Y1023833D01*
X121000Y1023700D01*
G01X126700D02*
Y1031700D01*
X131300Y1023700D01*
Y1031700D01*
G01X134500Y1023700D02*
X137000Y1031700D01*
X139500Y1023700D01*
G01X138600Y1026500D02*
X135400D01*
G01X143000Y1031700D02*
Y1023700D01*
X147000D01*
G01X159000D02*
Y1031700D01*
X161400D01*
X162200Y1031300D01*
X162800Y1030367D01*
X163000Y1029300D01*
X162800Y1028233D01*
X162300Y1027433D01*
X161400Y1027033D01*
X159000D01*
G01X166500Y1023700D02*
X169000Y1031700D01*
X171500Y1023700D01*
G01X170600Y1026500D02*
X167400D01*
G01X174800Y1023700D02*
Y1031700D01*
X176800D01*
X177600Y1031300D01*
X178200Y1030767D01*
X178700Y1029967D01*
X179100Y1029033D01*
X179200Y1027700D01*
X179100Y1026367D01*
X178700Y1025433D01*
X178200Y1024633D01*
X177600Y1024100D01*
X176800Y1023700D01*
X174800D01*
G01X190900Y1024766D02*
X191700Y1024100D01*
X192600Y1023700D01*
X193400D01*
X194200Y1024100D01*
X194800Y1024766D01*
X195100Y1025700D01*
X194900Y1026633D01*
X194400Y1027433D01*
X193500Y1027967D01*
X192300Y1028233D01*
X191600Y1028767D01*
X191300Y1029700D01*
X191500Y1030633D01*
X192000Y1031300D01*
X192700Y1031700D01*
X193400D01*
X194100Y1031433D01*
X194700Y1030767D01*
G01X199800Y1031700D02*
X202200D01*
G01X201000D02*
Y1023700D01*
G01X199800D02*
X202200D01*
G01X207100Y1031700D02*
X210900D01*
X207100Y1023700D01*
X210900D01*
G01X219000D02*
X215000D01*
Y1031700D01*
X219000D01*
G01X217400Y1027833D02*
X215000D01*
G01X231800Y1031700D02*
X234200D01*
G01X233000D02*
Y1023700D01*
G01X231800D02*
X234200D01*
G01X238900Y1024766D02*
X239700Y1024100D01*
X240600Y1023700D01*
X241400D01*
X242200Y1024100D01*
X242800Y1024766D01*
X243100Y1025700D01*
X242900Y1026633D01*
X242400Y1027433D01*
X241500Y1027967D01*
X240300Y1028233D01*
X239600Y1028767D01*
X239300Y1029700D01*
X239500Y1030633D01*
X240000Y1031300D01*
X240700Y1031700D01*
X241400D01*
X242100Y1031433D01*
X242700Y1030767D01*
G01X257000Y1031700D02*
Y1023700D01*
G01X254700Y1031700D02*
X259300D01*
G01X262900Y1023700D02*
Y1031700D01*
G01X267100D02*
Y1023700D01*
G01Y1027700D02*
X262900D01*
G01X275000Y1023700D02*
X271000D01*
Y1031700D01*
X275000D01*
G01X273400Y1027833D02*
X271000D01*
G01X286800Y1023700D02*
Y1031700D01*
X288800D01*
X289600Y1031300D01*
X290200Y1030767D01*
X290700Y1029967D01*
X291100Y1029033D01*
X291200Y1027700D01*
X291100Y1026367D01*
X290700Y1025433D01*
X290200Y1024633D01*
X289600Y1024100D01*
X288800Y1023700D01*
X286800D01*
G01X295000D02*
Y1031700D01*
X297500D01*
X298300Y1031300D01*
X298800Y1030767D01*
X299000Y1029700D01*
X298800Y1028633D01*
X298200Y1027967D01*
X297500Y1027567D01*
X295000D01*
G01X297500D02*
X299000Y1023700D01*
G01X303800Y1031700D02*
X306200D01*
G01X305000D02*
Y1023700D01*
G01X303800D02*
X306200D01*
G01X311000Y1031700D02*
Y1023700D01*
X315000D01*
G01X319000Y1031700D02*
Y1023700D01*
X323000D01*
G01X334900Y1024766D02*
X335700Y1024100D01*
X336600Y1023700D01*
X337400D01*
X338200Y1024100D01*
X338800Y1024766D01*
X339100Y1025700D01*
X338900Y1026633D01*
X338400Y1027433D01*
X337500Y1027967D01*
X336300Y1028233D01*
X335600Y1028767D01*
X335300Y1029700D01*
X335500Y1030633D01*
X336000Y1031300D01*
X336700Y1031700D01*
X337400D01*
X338100Y1031433D01*
X338700Y1030767D01*
G01X343800Y1031700D02*
X346200D01*
G01X345000D02*
Y1023700D01*
G01X343800D02*
X346200D01*
G01X351100Y1031700D02*
X354900D01*
X351100Y1023700D01*
X354900D01*
G01X363000D02*
X359000D01*
Y1031700D01*
X363000D01*
G01X361400Y1027833D02*
X359000D01*
G01X375900Y1026367D02*
X378300D01*
G01X377000Y1028100D02*
Y1024633D01*
G01X393000Y1023700D02*
Y1031700D01*
X391800Y1030100D01*
G01Y1023700D02*
X394200D01*
G01X401000Y1031700D02*
X400200Y1031433D01*
X399600Y1030767D01*
X399200Y1029967D01*
X398900Y1028900D01*
X398800Y1027700D01*
X398900Y1026500D01*
X399200Y1025433D01*
X399600Y1024633D01*
X400200Y1023967D01*
X401000Y1023700D01*
X401800Y1023967D01*
X402400Y1024633D01*
X402800Y1025433D01*
X403100Y1026500D01*
X403200Y1027700D01*
X403100Y1028900D01*
X402800Y1029967D01*
X402400Y1030767D01*
X401800Y1031433D01*
X401000Y1031700D01*
G01X406400Y1023700D02*
Y1031700D01*
X409000Y1025033D01*
X411600Y1031700D01*
Y1023700D01*
G01X415800Y1031700D02*
X418200D01*
G01X417000D02*
Y1023700D01*
G01X415800D02*
X418200D01*
G01X423000Y1031700D02*
Y1023700D01*
X427000D01*
G01X-321811Y847207D02*
Y900357D01*
G01X-276536Y765515D02*
G03I-2953J0D01*
G01Y785200D02*
G03I-2953J0D01*
G01X-282441Y827522D02*
X292362D01*
G01X-282441Y843270D02*
Y827522D01*
G01Y847207D02*
X292362D01*
G01Y843270D02*
X-282441D01*
G01Y862956D02*
Y847207D01*
G01X292362Y862956D02*
X-282441D01*
G01Y866893D02*
Y937759D01*
G01Y929885D02*
X12834D01*
G01X-237166Y695633D02*
X-268662D01*
G01D02*
X-227323D01*
G01X-256851Y765515D02*
G03I-2953J0D01*
G01Y785200D02*
G03I-2953J0D01*
G01X-244810Y676875D02*
X-243880Y675833D01*
X-242795Y675208D01*
X-241400Y675000D01*
X-240005Y675417D01*
X-238920Y676250D01*
X-238145Y677708D01*
X-237990Y679375D01*
X-238300Y681042D01*
X-239075Y682083D01*
X-240160Y682917D01*
X-241245Y683125D01*
X-242330Y682917D01*
X-243725Y682083D01*
X-243260Y687500D01*
X-239075D01*
G01X-233030Y675000D02*
Y687500D01*
X-229000Y677083D01*
X-224970Y687500D01*
Y675000D01*
G01X-220630D02*
Y687500D01*
X-216600Y677083D01*
X-212570Y687500D01*
Y675000D01*
G01X-237166Y758013D02*
Y687759D01*
G01Y765515D02*
G03I-2953J0D01*
G01Y785200D02*
G03I-2953J0D01*
G01X-185985Y695633D02*
X-227323D01*
G01X-185985Y668074D02*
X-217481D01*
G01D02*
X-176142D01*
G01X-217481Y758363D02*
Y687759D01*
G01Y695633D02*
X-185985D01*
G01X-211575Y762562D02*
X-217481D01*
G01X-211575Y768467D02*
Y762562D01*
G01X-217481D02*
Y768467D01*
G01D02*
X-211575D01*
G01X-217481Y788152D02*
X-211575D01*
G01Y782247D02*
X-217481D01*
G01X-211575Y788152D02*
Y782247D01*
G01X-217481D02*
Y788152D01*
G01X-191810Y645475D02*
X-190880Y644433D01*
X-189795Y643808D01*
X-188400Y643600D01*
X-187005Y644017D01*
X-185920Y644850D01*
X-185145Y646308D01*
X-184990Y647975D01*
X-185300Y649642D01*
X-186075Y650683D01*
X-187160Y651517D01*
X-188245Y651725D01*
X-189330Y651517D01*
X-190725Y650683D01*
X-190260Y656100D01*
X-186075D01*
G01X-180030Y643600D02*
Y656100D01*
X-176000Y645683D01*
X-171970Y656100D01*
Y643600D01*
G01X-167630D02*
Y656100D01*
X-163600Y645683D01*
X-159570Y656100D01*
Y643600D01*
G01X-166300Y719775D02*
X-197796D01*
G01D02*
X-163347D01*
G01X-185985Y762562D02*
X-191890D01*
G01D02*
Y768467D01*
G01D02*
X-185985D01*
G01X-191890Y788152D02*
X-185985D01*
G01Y782247D02*
X-191890D01*
G01D02*
Y788152D01*
G01X-134804Y668074D02*
X-176142D01*
G01X-185985Y758625D02*
Y660200D01*
G01Y768467D02*
Y762562D01*
G01Y788152D02*
Y782247D01*
G01X-166300Y758625D02*
Y660200D01*
G01Y668074D02*
X-134804D01*
G01X-166300Y754441D02*
Y711901D01*
G01X-93868Y719775D02*
X-163347D01*
G01X-160394Y762562D02*
X-166300D01*
G01D02*
Y768467D01*
G01D02*
X-160394D01*
G01X-166300Y788152D02*
X-160394D01*
G01Y782247D02*
X-166300D01*
G01D02*
Y788152D01*
G01X-160394Y757940D02*
Y711901D01*
G01Y719775D02*
X-93868D01*
G01X-160394Y768467D02*
Y762562D01*
G01Y788152D02*
Y782247D01*
G01X-156457D02*
X-36727D01*
G01X-156457Y788152D02*
X-36727D01*
G01X-136385Y722728D02*
Y735228D01*
X-138245Y732728D01*
G01Y722728D02*
X-134525D01*
G01X-123985Y722311D02*
X-124295Y722520D01*
Y722936D01*
X-123985Y723145D01*
X-123675Y722936D01*
Y722520D01*
X-123985Y722311D01*
G01X-114995Y724603D02*
X-114065Y723561D01*
X-112980Y722936D01*
X-111585Y722728D01*
X-110190Y723145D01*
X-109105Y723978D01*
X-108330Y725436D01*
X-108175Y727103D01*
X-108485Y728770D01*
X-109260Y729811D01*
X-110345Y730645D01*
X-111430Y730853D01*
X-112515Y730645D01*
X-113910Y729811D01*
X-113445Y735228D01*
X-109260D01*
G01X-103215Y722728D02*
Y735228D01*
X-99185Y724811D01*
X-95155Y735228D01*
Y722728D01*
G01X-90815D02*
Y735228D01*
X-86785Y724811D01*
X-82755Y735228D01*
Y722728D01*
G01X-108900Y83081D02*
X-113550D01*
Y95581D01*
X-108900D01*
G01X-107100Y1339766D02*
X-106300Y1339100D01*
X-105400Y1338700D01*
X-104600D01*
X-103800Y1339100D01*
X-103200Y1339766D01*
X-102900Y1340700D01*
X-103100Y1341633D01*
X-103600Y1342433D01*
X-104500Y1342967D01*
X-105700Y1343233D01*
X-106400Y1343767D01*
X-106700Y1344700D01*
X-106500Y1345633D01*
X-106000Y1346300D01*
X-105300Y1346700D01*
X-104600D01*
X-103900Y1346433D01*
X-103300Y1345767D01*
G01X-97000Y1338700D02*
X-97800Y1338833D01*
X-98500Y1339367D01*
X-99100Y1340167D01*
X-99500Y1341100D01*
X-99700Y1342167D01*
Y1343233D01*
X-99500Y1344300D01*
X-99100Y1345233D01*
X-98500Y1346033D01*
X-97800Y1346567D01*
X-97000Y1346700D01*
X-96200Y1346567D01*
X-95500Y1346033D01*
X-94900Y1345233D01*
X-94500Y1344300D01*
X-94300Y1343233D01*
Y1342167D01*
X-94500Y1341100D01*
X-94900Y1340167D01*
X-95500Y1339367D01*
X-96200Y1338833D01*
X-97000Y1338700D01*
G01X-91000Y1346700D02*
Y1338700D01*
X-87000D01*
G01X-83200D02*
Y1346700D01*
X-81200D01*
X-80400Y1346300D01*
X-79800Y1345767D01*
X-79300Y1344967D01*
X-78900Y1344033D01*
X-78800Y1342700D01*
X-78900Y1341367D01*
X-79300Y1340433D01*
X-79800Y1339633D01*
X-80400Y1339100D01*
X-81200Y1338700D01*
X-83200D01*
G01X-71000D02*
X-75000D01*
Y1346700D01*
X-71000D01*
G01X-72600Y1342833D02*
X-75000D01*
G01X-67000Y1338700D02*
Y1346700D01*
X-64500D01*
X-63700Y1346300D01*
X-63200Y1345767D01*
X-63000Y1344700D01*
X-63200Y1343633D01*
X-63800Y1342967D01*
X-64500Y1342567D01*
X-67000D01*
G01X-64500D02*
X-63000Y1338700D01*
G01X-59600D02*
Y1346700D01*
X-57000Y1340033D01*
X-54400Y1346700D01*
Y1338700D01*
G01X-51500D02*
X-49000Y1346700D01*
X-46500Y1338700D01*
G01X-47400Y1341500D02*
X-50600D01*
G01X-43100Y1339766D02*
X-42300Y1339100D01*
X-41400Y1338700D01*
X-40600D01*
X-39800Y1339100D01*
X-39200Y1339766D01*
X-38900Y1340700D01*
X-39100Y1341633D01*
X-39600Y1342433D01*
X-40500Y1342967D01*
X-41700Y1343233D01*
X-42400Y1343767D01*
X-42700Y1344700D01*
X-42500Y1345633D01*
X-42000Y1346300D01*
X-41300Y1346700D01*
X-40600D01*
X-39900Y1346433D01*
X-39300Y1345767D01*
G01X-35200Y1338700D02*
Y1346700D01*
G01X-31400D02*
X-35200Y1341766D01*
G01X-30800Y1338700D02*
X-33500Y1344033D01*
G01X-17000Y1338700D02*
X-17800Y1338833D01*
X-18500Y1339367D01*
X-19100Y1340167D01*
X-19500Y1341100D01*
X-19700Y1342167D01*
Y1343233D01*
X-19500Y1344300D01*
X-19100Y1345233D01*
X-18500Y1346033D01*
X-17800Y1346567D01*
X-17000Y1346700D01*
X-16200Y1346567D01*
X-15500Y1346033D01*
X-14900Y1345233D01*
X-14500Y1344300D01*
X-14300Y1343233D01*
Y1342167D01*
X-14500Y1341100D01*
X-14900Y1340167D01*
X-15500Y1339367D01*
X-16200Y1338833D01*
X-17000Y1338700D01*
G01X-11000D02*
Y1346700D01*
X-8600D01*
X-7800Y1346300D01*
X-7200Y1345367D01*
X-7000Y1344300D01*
X-7200Y1343233D01*
X-7700Y1342433D01*
X-8600Y1342033D01*
X-11000D01*
G01X1000Y1338700D02*
X-3000D01*
Y1346700D01*
X1000D01*
G01X-600Y1342833D02*
X-3000D01*
G01X4700Y1338700D02*
Y1346700D01*
X9300Y1338700D01*
Y1346700D01*
G01X23000Y1338700D02*
X22200Y1338833D01*
X21500Y1339367D01*
X20900Y1340167D01*
X20500Y1341100D01*
X20300Y1342167D01*
Y1343233D01*
X20500Y1344300D01*
X20900Y1345233D01*
X21500Y1346033D01*
X22200Y1346567D01*
X23000Y1346700D01*
X23800Y1346567D01*
X24500Y1346033D01*
X25100Y1345233D01*
X25500Y1344300D01*
X25700Y1343233D01*
Y1342167D01*
X25500Y1341100D01*
X25100Y1340167D01*
X24500Y1339367D01*
X23800Y1338833D01*
X23000Y1338700D01*
G01X28700D02*
Y1346700D01*
X33300Y1338700D01*
Y1346700D01*
G01X47800Y1342967D02*
X48200Y1343367D01*
X48500Y1344033D01*
X48700Y1344967D01*
X48500Y1345767D01*
X48100Y1346300D01*
X47400Y1346700D01*
X44700D01*
Y1338700D01*
X48000D01*
X48700Y1339233D01*
X49100Y1340033D01*
X49300Y1340967D01*
X49100Y1341900D01*
X48500Y1342700D01*
X47800Y1342967D01*
X44700D01*
G01X55000Y1338700D02*
X54200Y1338833D01*
X53500Y1339367D01*
X52900Y1340167D01*
X52500Y1341100D01*
X52300Y1342167D01*
Y1343233D01*
X52500Y1344300D01*
X52900Y1345233D01*
X53500Y1346033D01*
X54200Y1346567D01*
X55000Y1346700D01*
X55800Y1346567D01*
X56500Y1346033D01*
X57100Y1345233D01*
X57500Y1344300D01*
X57700Y1343233D01*
Y1342167D01*
X57500Y1341100D01*
X57100Y1340167D01*
X56500Y1339367D01*
X55800Y1338833D01*
X55000Y1338700D01*
G01X63000Y1346700D02*
Y1338700D01*
G01X60700Y1346700D02*
X65300D01*
G01X68900Y1338700D02*
Y1346700D01*
G01X73100D02*
Y1338700D01*
G01Y1342700D02*
X68900D01*
G01X84900Y1339766D02*
X85700Y1339100D01*
X86600Y1338700D01*
X87400D01*
X88200Y1339100D01*
X88800Y1339766D01*
X89100Y1340700D01*
X88900Y1341633D01*
X88400Y1342433D01*
X87500Y1342967D01*
X86300Y1343233D01*
X85600Y1343767D01*
X85300Y1344700D01*
X85500Y1345633D01*
X86000Y1346300D01*
X86700Y1346700D01*
X87400D01*
X88100Y1346433D01*
X88700Y1345767D01*
G01X93800Y1346700D02*
X96200D01*
G01X95000D02*
Y1338700D01*
G01X93800D02*
X96200D01*
G01X100800D02*
Y1346700D01*
X102800D01*
X103600Y1346300D01*
X104200Y1345767D01*
X104700Y1344967D01*
X105100Y1344033D01*
X105200Y1342700D01*
X105100Y1341367D01*
X104700Y1340433D01*
X104200Y1339633D01*
X103600Y1339100D01*
X102800Y1338700D01*
X100800D01*
G01X113000D02*
X109000D01*
Y1346700D01*
X113000D01*
G01X111400Y1342833D02*
X109000D01*
G01X119000Y1338433D02*
X118800Y1338567D01*
Y1338833D01*
X119000Y1338967D01*
X119200Y1338833D01*
Y1338567D01*
X119000Y1338433D01*
G01X-18819Y-517716D02*
X-77874D01*
G01D02*
Y-478346D01*
G01D02*
X-18819D01*
G01X-62272Y-394855D02*
Y-429245D01*
X-20408D01*
Y-394855D01*
X-62272D01*
G01X-56597Y-403541D02*
Y-400441D01*
X-55677D01*
X-55370Y-400596D01*
X-55140Y-400958D01*
X-55063Y-401371D01*
X-55140Y-401784D01*
X-55332Y-402094D01*
X-55677Y-402249D01*
X-56597D01*
G01X-51887Y-400699D02*
X-52117Y-400544D01*
X-52385Y-400441D01*
X-52692D01*
X-53037Y-400596D01*
X-53305Y-400854D01*
X-53497Y-401164D01*
X-53650Y-401681D01*
X-53688Y-402146D01*
X-53612Y-402611D01*
X-53497Y-402921D01*
X-53267Y-403231D01*
X-52998Y-403438D01*
X-52730Y-403541D01*
X-52462D01*
X-52193Y-403438D01*
X-51963Y-403283D01*
X-51772Y-403076D01*
G01X-49323Y-401888D02*
X-49170Y-401733D01*
X-49055Y-401474D01*
X-48978Y-401113D01*
X-49055Y-400803D01*
X-49208Y-400596D01*
X-49477Y-400441D01*
X-50512D01*
Y-403541D01*
X-49247D01*
X-48978Y-403334D01*
X-48825Y-403024D01*
X-48748Y-402663D01*
X-48825Y-402301D01*
X-49055Y-401991D01*
X-49323Y-401888D01*
X-50512D01*
G01X-44388Y-400441D02*
X-43430Y-403541D01*
X-42472Y-400441D01*
G01X-39563Y-403541D02*
X-41097D01*
Y-400441D01*
X-39563D01*
G01X-40177Y-401939D02*
X-41097D01*
G01X-38112Y-403541D02*
Y-400441D01*
X-36348Y-403541D01*
Y-400441D01*
G01X-34973Y-403541D02*
Y-400441D01*
X-34207D01*
X-33900Y-400596D01*
X-33670Y-400803D01*
X-33478Y-401113D01*
X-33325Y-401474D01*
X-33287Y-401991D01*
X-33325Y-402508D01*
X-33478Y-402869D01*
X-33670Y-403179D01*
X-33900Y-403386D01*
X-34207Y-403541D01*
X-34973D01*
G01X-31030D02*
X-31337Y-403489D01*
X-31605Y-403283D01*
X-31835Y-402973D01*
X-31988Y-402611D01*
X-32065Y-402198D01*
Y-401784D01*
X-31988Y-401371D01*
X-31835Y-401009D01*
X-31605Y-400699D01*
X-31337Y-400493D01*
X-31030Y-400441D01*
X-30723Y-400493D01*
X-30455Y-400699D01*
X-30225Y-401009D01*
X-30072Y-401371D01*
X-29995Y-401784D01*
Y-402198D01*
X-30072Y-402611D01*
X-30225Y-402973D01*
X-30455Y-403283D01*
X-30723Y-403489D01*
X-31030Y-403541D01*
G01X-28697D02*
Y-400441D01*
X-27738D01*
X-27432Y-400596D01*
X-27240Y-400803D01*
X-27163Y-401216D01*
X-27240Y-401629D01*
X-27470Y-401888D01*
X-27738Y-402043D01*
X-28697D01*
G01X-27738D02*
X-27163Y-403541D01*
G01X-53459Y673439D02*
X-65959D01*
X-63459Y671579D01*
G01X-53459D02*
Y675299D01*
G01X-53042Y685839D02*
X-53251Y685529D01*
X-53667D01*
X-53876Y685839D01*
X-53667Y686149D01*
X-53251D01*
X-53042Y685839D01*
G01X-55334Y694829D02*
X-54292Y695759D01*
X-53667Y696844D01*
X-53459Y698239D01*
X-53876Y699634D01*
X-54709Y700719D01*
X-56167Y701494D01*
X-57834Y701649D01*
X-59501Y701339D01*
X-60542Y700564D01*
X-61376Y699479D01*
X-61584Y698394D01*
X-61376Y697309D01*
X-60542Y695914D01*
X-65959Y696379D01*
Y700564D01*
G01X-53459Y706609D02*
X-65959D01*
X-55542Y710639D01*
X-65959Y714669D01*
X-53459D01*
G01Y719009D02*
X-65959D01*
X-55542Y723039D01*
X-65959Y727069D01*
X-53459D01*
G01X-53307Y-609436D02*
Y-684436D01*
X446693D01*
Y-609436D01*
X-53307D01*
G01X-41307Y-674436D02*
Y-679436D01*
G01X-42764Y-674436D02*
X-39850D01*
G01X-34940Y-679436D02*
X-37474D01*
Y-674436D01*
X-34940D01*
G01X-35954Y-676853D02*
X-37474D01*
G01X-32374Y-674436D02*
Y-679436D01*
X-29840D01*
G01X-26007Y-679603D02*
X-26134Y-679519D01*
Y-679353D01*
X-26007Y-679269D01*
X-25880Y-679353D01*
Y-679519D01*
X-26007Y-679603D01*
G01Y-677353D02*
X-26134Y-677269D01*
Y-677103D01*
X-26007Y-677019D01*
X-25880Y-677103D01*
Y-677269D01*
X-26007Y-677353D01*
G01X-21224Y-681103D02*
X-21857Y-680269D01*
X-22174Y-679436D01*
Y-676103D01*
X-21857Y-675269D01*
X-21224Y-674436D01*
G01X-15807D02*
X-16314Y-674603D01*
X-16694Y-675019D01*
X-16947Y-675519D01*
X-17137Y-676186D01*
X-17200Y-676936D01*
X-17137Y-677686D01*
X-16947Y-678353D01*
X-16694Y-678853D01*
X-16314Y-679269D01*
X-15807Y-679436D01*
X-15300Y-679269D01*
X-14920Y-678853D01*
X-14667Y-678353D01*
X-14477Y-677686D01*
X-14414Y-676936D01*
X-14477Y-676186D01*
X-14667Y-675519D01*
X-14920Y-675019D01*
X-15300Y-674603D01*
X-15807Y-674436D01*
G01X-12100Y-678436D02*
X-11720Y-679019D01*
X-11214Y-679353D01*
X-10644Y-679436D01*
X-10137Y-679353D01*
X-9630Y-678936D01*
X-9314Y-678436D01*
X-9250Y-677936D01*
X-9377Y-677353D01*
X-9820Y-676936D01*
X-10264Y-676769D01*
X-10834D01*
G01X-10264D02*
X-9884Y-676519D01*
X-9567Y-676103D01*
X-9440Y-675603D01*
X-9567Y-675103D01*
X-9884Y-674686D01*
X-10454Y-674436D01*
X-11024Y-674519D01*
X-11594Y-674853D01*
G01X-5290Y-681103D02*
X-4657Y-680269D01*
X-4340Y-679436D01*
Y-676103D01*
X-4657Y-675269D01*
X-5290Y-674436D01*
G01X-1900Y-678436D02*
X-1520Y-679019D01*
X-1014Y-679353D01*
X-444Y-679436D01*
X63Y-679353D01*
X570Y-678936D01*
X886Y-678436D01*
X950Y-677936D01*
X823Y-677353D01*
X380Y-676936D01*
X-64Y-676769D01*
X-634D01*
G01X-64D02*
X316Y-676519D01*
X633Y-676103D01*
X760Y-675603D01*
X633Y-675103D01*
X316Y-674686D01*
X-254Y-674436D01*
X-824Y-674519D01*
X-1394Y-674853D01*
G01X3390Y-675269D02*
X3770Y-674769D01*
X4213Y-674519D01*
X4720Y-674436D01*
X5353Y-674603D01*
X5796Y-675019D01*
X5923Y-675519D01*
X5860Y-676019D01*
X5606Y-676436D01*
X4340Y-677269D01*
X3770Y-677853D01*
X3390Y-678686D01*
X3263Y-679436D01*
X5923D01*
G01X9566D02*
X9693Y-678353D01*
X9883Y-677436D01*
X10136Y-676603D01*
X10453Y-675686D01*
X10960Y-674436D01*
X8426D01*
G01X13970Y-677769D02*
X15616D01*
G01X18690Y-675269D02*
X19070Y-674769D01*
X19513Y-674519D01*
X20020Y-674436D01*
X20653Y-674603D01*
X21096Y-675019D01*
X21223Y-675519D01*
X21160Y-676019D01*
X20906Y-676436D01*
X19640Y-677269D01*
X19070Y-677853D01*
X18690Y-678686D01*
X18563Y-679436D01*
X21223D01*
G01X23600Y-678436D02*
X23980Y-679019D01*
X24486Y-679353D01*
X25056Y-679436D01*
X25563Y-679353D01*
X26070Y-678936D01*
X26386Y-678436D01*
X26450Y-677936D01*
X26323Y-677353D01*
X25880Y-676936D01*
X25436Y-676769D01*
X24866D01*
G01X25436D02*
X25816Y-676519D01*
X26133Y-676103D01*
X26260Y-675603D01*
X26133Y-675103D01*
X25816Y-674686D01*
X25246Y-674436D01*
X24676Y-674519D01*
X24106Y-674853D01*
G01X30853Y-679436D02*
Y-674436D01*
X28510Y-678019D01*
X31676D01*
G01X33800Y-678686D02*
X34180Y-679103D01*
X34623Y-679353D01*
X35193Y-679436D01*
X35763Y-679269D01*
X36206Y-678936D01*
X36523Y-678353D01*
X36586Y-677686D01*
X36460Y-677019D01*
X36143Y-676603D01*
X35700Y-676269D01*
X35256Y-676186D01*
X34813Y-676269D01*
X34243Y-676603D01*
X34433Y-674436D01*
X36143D01*
G01X44190Y-679436D02*
Y-674436D01*
X46596D01*
G01X45710Y-676853D02*
X44190D01*
G01X48910Y-679436D02*
X50493Y-674436D01*
X52076Y-679436D01*
G01X51506Y-677686D02*
X49480D01*
G01X54263Y-679436D02*
X56923Y-674436D01*
G01X54263D02*
X56923Y-679436D01*
G01X60693Y-679603D02*
X60566Y-679519D01*
Y-679353D01*
X60693Y-679269D01*
X60820Y-679353D01*
Y-679519D01*
X60693Y-679603D01*
G01Y-677353D02*
X60566Y-677269D01*
Y-677103D01*
X60693Y-677019D01*
X60820Y-677103D01*
Y-677269D01*
X60693Y-677353D01*
G01X65476Y-681103D02*
X64843Y-680269D01*
X64526Y-679436D01*
Y-676103D01*
X64843Y-675269D01*
X65476Y-674436D01*
G01X70893D02*
X70386Y-674603D01*
X70006Y-675019D01*
X69753Y-675519D01*
X69563Y-676186D01*
X69500Y-676936D01*
X69563Y-677686D01*
X69753Y-678353D01*
X70006Y-678853D01*
X70386Y-679269D01*
X70893Y-679436D01*
X71400Y-679269D01*
X71780Y-678853D01*
X72033Y-678353D01*
X72223Y-677686D01*
X72286Y-676936D01*
X72223Y-676186D01*
X72033Y-675519D01*
X71780Y-675019D01*
X71400Y-674603D01*
X70893Y-674436D01*
G01X74600Y-678436D02*
X74980Y-679019D01*
X75486Y-679353D01*
X76056Y-679436D01*
X76563Y-679353D01*
X77070Y-678936D01*
X77386Y-678436D01*
X77450Y-677936D01*
X77323Y-677353D01*
X76880Y-676936D01*
X76436Y-676769D01*
X75866D01*
G01X76436D02*
X76816Y-676519D01*
X77133Y-676103D01*
X77260Y-675603D01*
X77133Y-675103D01*
X76816Y-674686D01*
X76246Y-674436D01*
X75676Y-674519D01*
X75106Y-674853D01*
G01X81410Y-681103D02*
X82043Y-680269D01*
X82360Y-679436D01*
Y-676103D01*
X82043Y-675269D01*
X81410Y-674436D01*
G01X84800Y-678436D02*
X85180Y-679019D01*
X85686Y-679353D01*
X86256Y-679436D01*
X86763Y-679353D01*
X87270Y-678936D01*
X87586Y-678436D01*
X87650Y-677936D01*
X87523Y-677353D01*
X87080Y-676936D01*
X86636Y-676769D01*
X86066D01*
G01X86636D02*
X87016Y-676519D01*
X87333Y-676103D01*
X87460Y-675603D01*
X87333Y-675103D01*
X87016Y-674686D01*
X86446Y-674436D01*
X85876Y-674519D01*
X85306Y-674853D01*
G01X90216Y-678853D02*
X90660Y-679269D01*
X91166Y-679436D01*
X91673Y-679269D01*
X92116Y-678769D01*
X92433Y-678019D01*
X92560Y-677269D01*
Y-676353D01*
X92433Y-675603D01*
X92116Y-674936D01*
X91736Y-674603D01*
X91293Y-674436D01*
X90786Y-674603D01*
X90406Y-674936D01*
X90153Y-675436D01*
X90026Y-676103D01*
X90153Y-676686D01*
X90470Y-677269D01*
X90850Y-677603D01*
X91293Y-677686D01*
X91800Y-677519D01*
X92180Y-677103D01*
X92560Y-676353D01*
G01X96266Y-679436D02*
X96393Y-678353D01*
X96583Y-677436D01*
X96836Y-676603D01*
X97153Y-675686D01*
X97660Y-674436D01*
X95126D01*
G01X100670Y-677769D02*
X102316D01*
G01X105200Y-678436D02*
X105580Y-679019D01*
X106086Y-679353D01*
X106656Y-679436D01*
X107163Y-679353D01*
X107670Y-678936D01*
X107986Y-678436D01*
X108050Y-677936D01*
X107923Y-677353D01*
X107480Y-676936D01*
X107036Y-676769D01*
X106466D01*
G01X107036D02*
X107416Y-676519D01*
X107733Y-676103D01*
X107860Y-675603D01*
X107733Y-675103D01*
X107416Y-674686D01*
X106846Y-674436D01*
X106276Y-674519D01*
X105706Y-674853D01*
G01X110490Y-677353D02*
X110933Y-676769D01*
X111313Y-676436D01*
X111820Y-676269D01*
X112263Y-676436D01*
X112580Y-676769D01*
X112833Y-677269D01*
X112896Y-677853D01*
X112833Y-678353D01*
X112580Y-678853D01*
X112200Y-679269D01*
X111756Y-679436D01*
X111250Y-679269D01*
X110806Y-678769D01*
X110553Y-678019D01*
X110490Y-677186D01*
X110616Y-676103D01*
X110806Y-675519D01*
X111123Y-674936D01*
X111566Y-674519D01*
X112010Y-674436D01*
X112453Y-674603D01*
X112770Y-675019D01*
G01X116793Y-679436D02*
Y-674436D01*
X116033Y-675436D01*
G01Y-679436D02*
X117553D01*
G01X122653D02*
Y-674436D01*
X120310Y-678019D01*
X123476D01*
G01X-44501Y-486254D02*
Y-489354D01*
X-42967D01*
G01X-40634D02*
X-40941Y-489302D01*
X-41209Y-489096D01*
X-41439Y-488786D01*
X-41592Y-488424D01*
X-41669Y-488011D01*
Y-487597D01*
X-41592Y-487184D01*
X-41439Y-486822D01*
X-41209Y-486512D01*
X-40941Y-486306D01*
X-40634Y-486254D01*
X-40327Y-486306D01*
X-40059Y-486512D01*
X-39829Y-486822D01*
X-39676Y-487184D01*
X-39599Y-487597D01*
Y-488011D01*
X-39676Y-488424D01*
X-39829Y-488786D01*
X-40059Y-489096D01*
X-40327Y-489302D01*
X-40634Y-489354D01*
G01X-37304Y-487804D02*
X-36537D01*
Y-488734D01*
X-36767Y-489044D01*
X-37036Y-489251D01*
X-37419Y-489354D01*
X-37802Y-489251D01*
X-38071Y-489044D01*
X-38301Y-488734D01*
X-38454Y-488372D01*
X-38531Y-487959D01*
Y-487597D01*
X-38454Y-487287D01*
X-38301Y-486926D01*
X-38071Y-486616D01*
X-37841Y-486409D01*
X-37534Y-486254D01*
X-37266D01*
X-36959Y-486357D01*
X-36729Y-486564D01*
G01X-34434Y-489354D02*
X-34741Y-489302D01*
X-35009Y-489096D01*
X-35239Y-488786D01*
X-35392Y-488424D01*
X-35469Y-488011D01*
Y-487597D01*
X-35392Y-487184D01*
X-35239Y-486822D01*
X-35009Y-486512D01*
X-34741Y-486306D01*
X-34434Y-486254D01*
X-34127Y-486306D01*
X-33859Y-486512D01*
X-33629Y-486822D01*
X-33476Y-487184D01*
X-33399Y-487597D01*
Y-488011D01*
X-33476Y-488424D01*
X-33629Y-488786D01*
X-33859Y-489096D01*
X-34127Y-489302D01*
X-34434Y-489354D01*
G01X-51801Y-484354D02*
Y-481254D01*
X-50881D01*
X-50574Y-481409D01*
X-50344Y-481771D01*
X-50267Y-482184D01*
X-50344Y-482597D01*
X-50536Y-482907D01*
X-50881Y-483062D01*
X-51801D01*
G01X-47091Y-481512D02*
X-47321Y-481357D01*
X-47589Y-481254D01*
X-47896D01*
X-48241Y-481409D01*
X-48509Y-481667D01*
X-48701Y-481977D01*
X-48854Y-482494D01*
X-48892Y-482959D01*
X-48816Y-483424D01*
X-48701Y-483734D01*
X-48471Y-484044D01*
X-48202Y-484251D01*
X-47934Y-484354D01*
X-47666D01*
X-47397Y-484251D01*
X-47167Y-484096D01*
X-46976Y-483889D01*
G01X-44527Y-482701D02*
X-44374Y-482546D01*
X-44259Y-482287D01*
X-44182Y-481926D01*
X-44259Y-481616D01*
X-44412Y-481409D01*
X-44681Y-481254D01*
X-45716D01*
Y-484354D01*
X-44451D01*
X-44182Y-484147D01*
X-44029Y-483837D01*
X-43952Y-483476D01*
X-44029Y-483114D01*
X-44259Y-482804D01*
X-44527Y-482701D01*
X-45716D01*
G01X-39592Y-481254D02*
X-38634Y-484354D01*
X-37676Y-481254D01*
G01X-34767Y-484354D02*
X-36301D01*
Y-481254D01*
X-34767D01*
G01X-35381Y-482752D02*
X-36301D01*
G01X-33316Y-484354D02*
Y-481254D01*
X-31552Y-484354D01*
Y-481254D01*
G01X-30177Y-484354D02*
Y-481254D01*
X-29411D01*
X-29104Y-481409D01*
X-28874Y-481616D01*
X-28682Y-481926D01*
X-28529Y-482287D01*
X-28491Y-482804D01*
X-28529Y-483321D01*
X-28682Y-483682D01*
X-28874Y-483992D01*
X-29104Y-484199D01*
X-29411Y-484354D01*
X-30177D01*
G01X-26234D02*
X-26541Y-484302D01*
X-26809Y-484096D01*
X-27039Y-483786D01*
X-27192Y-483424D01*
X-27269Y-483011D01*
Y-482597D01*
X-27192Y-482184D01*
X-27039Y-481822D01*
X-26809Y-481512D01*
X-26541Y-481306D01*
X-26234Y-481254D01*
X-25927Y-481306D01*
X-25659Y-481512D01*
X-25429Y-481822D01*
X-25276Y-482184D01*
X-25199Y-482597D01*
Y-483011D01*
X-25276Y-483424D01*
X-25429Y-483786D01*
X-25659Y-484096D01*
X-25927Y-484302D01*
X-26234Y-484354D01*
G01X-23901D02*
Y-481254D01*
X-22942D01*
X-22636Y-481409D01*
X-22444Y-481616D01*
X-22367Y-482029D01*
X-22444Y-482442D01*
X-22674Y-482701D01*
X-22942Y-482856D01*
X-23901D01*
G01X-22942D02*
X-22367Y-484354D01*
G01X-49297Y-405441D02*
Y-408541D01*
X-47763D01*
G01X-45430D02*
X-45737Y-408489D01*
X-46005Y-408283D01*
X-46235Y-407973D01*
X-46388Y-407611D01*
X-46465Y-407198D01*
Y-406784D01*
X-46388Y-406371D01*
X-46235Y-406009D01*
X-46005Y-405699D01*
X-45737Y-405493D01*
X-45430Y-405441D01*
X-45123Y-405493D01*
X-44855Y-405699D01*
X-44625Y-406009D01*
X-44472Y-406371D01*
X-44395Y-406784D01*
Y-407198D01*
X-44472Y-407611D01*
X-44625Y-407973D01*
X-44855Y-408283D01*
X-45123Y-408489D01*
X-45430Y-408541D01*
G01X-42100Y-406991D02*
X-41333D01*
Y-407921D01*
X-41563Y-408231D01*
X-41832Y-408438D01*
X-42215Y-408541D01*
X-42598Y-408438D01*
X-42867Y-408231D01*
X-43097Y-407921D01*
X-43250Y-407559D01*
X-43327Y-407146D01*
Y-406784D01*
X-43250Y-406474D01*
X-43097Y-406113D01*
X-42867Y-405803D01*
X-42637Y-405596D01*
X-42330Y-405441D01*
X-42062D01*
X-41755Y-405544D01*
X-41525Y-405751D01*
G01X-39230Y-408541D02*
X-39537Y-408489D01*
X-39805Y-408283D01*
X-40035Y-407973D01*
X-40188Y-407611D01*
X-40265Y-407198D01*
Y-406784D01*
X-40188Y-406371D01*
X-40035Y-406009D01*
X-39805Y-405699D01*
X-39537Y-405493D01*
X-39230Y-405441D01*
X-38923Y-405493D01*
X-38655Y-405699D01*
X-38425Y-406009D01*
X-38272Y-406371D01*
X-38195Y-406784D01*
Y-407198D01*
X-38272Y-407611D01*
X-38425Y-407973D01*
X-38655Y-408283D01*
X-38923Y-408489D01*
X-39230Y-408541D01*
G01X-49738Y474016D02*
Y439626D01*
X-7874D01*
Y474016D01*
X-49738D01*
G01X-44063Y465330D02*
Y468430D01*
X-43143D01*
X-42836Y468275D01*
X-42606Y467913D01*
X-42529Y467500D01*
X-42606Y467087D01*
X-42798Y466777D01*
X-43143Y466622D01*
X-44063D01*
G01X-39353Y468172D02*
X-39583Y468327D01*
X-39851Y468430D01*
X-40158D01*
X-40503Y468275D01*
X-40771Y468017D01*
X-40963Y467707D01*
X-41116Y467190D01*
X-41154Y466725D01*
X-41078Y466260D01*
X-40963Y465950D01*
X-40733Y465640D01*
X-40464Y465433D01*
X-40196Y465330D01*
X-39928D01*
X-39659Y465433D01*
X-39429Y465588D01*
X-39238Y465795D01*
G01X-36789Y466983D02*
X-36636Y467138D01*
X-36521Y467397D01*
X-36444Y467758D01*
X-36521Y468068D01*
X-36674Y468275D01*
X-36943Y468430D01*
X-37978D01*
Y465330D01*
X-36713D01*
X-36444Y465537D01*
X-36291Y465847D01*
X-36214Y466208D01*
X-36291Y466570D01*
X-36521Y466880D01*
X-36789Y466983D01*
X-37978D01*
G01X-31854Y468430D02*
X-30896Y465330D01*
X-29938Y468430D01*
G01X-27029Y465330D02*
X-28563D01*
Y468430D01*
X-27029D01*
G01X-27643Y466932D02*
X-28563D01*
G01X-25578Y465330D02*
Y468430D01*
X-23814Y465330D01*
Y468430D01*
G01X-22439Y465330D02*
Y468430D01*
X-21673D01*
X-21366Y468275D01*
X-21136Y468068D01*
X-20944Y467758D01*
X-20791Y467397D01*
X-20753Y466880D01*
X-20791Y466363D01*
X-20944Y466002D01*
X-21136Y465692D01*
X-21366Y465485D01*
X-21673Y465330D01*
X-22439D01*
G01X-18496D02*
X-18803Y465382D01*
X-19071Y465588D01*
X-19301Y465898D01*
X-19454Y466260D01*
X-19531Y466673D01*
Y467087D01*
X-19454Y467500D01*
X-19301Y467862D01*
X-19071Y468172D01*
X-18803Y468378D01*
X-18496Y468430D01*
X-18189Y468378D01*
X-17921Y468172D01*
X-17691Y467862D01*
X-17538Y467500D01*
X-17461Y467087D01*
Y466673D01*
X-17538Y466260D01*
X-17691Y465898D01*
X-17921Y465588D01*
X-18189Y465382D01*
X-18496Y465330D01*
G01X-16163D02*
Y468430D01*
X-15204D01*
X-14898Y468275D01*
X-14706Y468068D01*
X-14629Y467655D01*
X-14706Y467242D01*
X-14936Y466983D01*
X-15204Y466828D01*
X-16163D01*
G01X-15204D02*
X-14629Y465330D01*
G01X-44601Y782247D02*
Y686428D01*
G01D02*
Y785200D01*
G01Y788152D02*
Y819648D01*
G01D02*
Y785200D01*
G01X320315Y89331D02*
X-26675D01*
G01X-40700Y83081D02*
X-36050D01*
Y95581D01*
X-40700D01*
G01X-36763Y463430D02*
Y460330D01*
X-35229D01*
G01X-32896D02*
X-33203Y460382D01*
X-33471Y460588D01*
X-33701Y460898D01*
X-33854Y461260D01*
X-33931Y461673D01*
Y462087D01*
X-33854Y462500D01*
X-33701Y462862D01*
X-33471Y463172D01*
X-33203Y463378D01*
X-32896Y463430D01*
X-32589Y463378D01*
X-32321Y463172D01*
X-32091Y462862D01*
X-31938Y462500D01*
X-31861Y462087D01*
Y461673D01*
X-31938Y461260D01*
X-32091Y460898D01*
X-32321Y460588D01*
X-32589Y460382D01*
X-32896Y460330D01*
G01X-29566Y461880D02*
X-28799D01*
Y460950D01*
X-29029Y460640D01*
X-29298Y460433D01*
X-29681Y460330D01*
X-30064Y460433D01*
X-30333Y460640D01*
X-30563Y460950D01*
X-30716Y461312D01*
X-30793Y461725D01*
Y462087D01*
X-30716Y462397D01*
X-30563Y462758D01*
X-30333Y463068D01*
X-30103Y463275D01*
X-29796Y463430D01*
X-29528D01*
X-29221Y463327D01*
X-28991Y463120D01*
G01X-26696Y460330D02*
X-27003Y460382D01*
X-27271Y460588D01*
X-27501Y460898D01*
X-27654Y461260D01*
X-27731Y461673D01*
Y462087D01*
X-27654Y462500D01*
X-27501Y462862D01*
X-27271Y463172D01*
X-27003Y463378D01*
X-26696Y463430D01*
X-26389Y463378D01*
X-26121Y463172D01*
X-25891Y462862D01*
X-25738Y462500D01*
X-25661Y462087D01*
Y461673D01*
X-25738Y461260D01*
X-25891Y460898D01*
X-26121Y460588D01*
X-26389Y460382D01*
X-26696Y460330D01*
G01X-36766Y932837D02*
Y945337D01*
X-38626Y942837D01*
G01Y932837D02*
X-34906D01*
G01X-24366Y945337D02*
X-25606Y944920D01*
X-26536Y943879D01*
X-27156Y942629D01*
X-27621Y940962D01*
X-27776Y939087D01*
X-27621Y937212D01*
X-27156Y935545D01*
X-26536Y934295D01*
X-25606Y933254D01*
X-24366Y932837D01*
X-23126Y933254D01*
X-22196Y934295D01*
X-21576Y935545D01*
X-21111Y937212D01*
X-20956Y939087D01*
X-21111Y940962D01*
X-21576Y942629D01*
X-22196Y943879D01*
X-23126Y944920D01*
X-24366Y945337D01*
G01X-11966D02*
X-13206Y944920D01*
X-14136Y943879D01*
X-14756Y942629D01*
X-15221Y940962D01*
X-15376Y939087D01*
X-15221Y937212D01*
X-14756Y935545D01*
X-14136Y934295D01*
X-13206Y933254D01*
X-11966Y932837D01*
X-10726Y933254D01*
X-9796Y934295D01*
X-9176Y935545D01*
X-8711Y937212D01*
X-8556Y939087D01*
X-8711Y940962D01*
X-9176Y942629D01*
X-9796Y943879D01*
X-10726Y944920D01*
X-11966Y945337D01*
G01X-1581Y937004D02*
X2449D01*
G01X12834Y932837D02*
Y945337D01*
X10974Y942837D01*
G01Y932837D02*
X14694D01*
G01X21824Y934712D02*
X22754Y933670D01*
X23839Y933045D01*
X25234Y932837D01*
X26629Y933254D01*
X27714Y934087D01*
X28489Y935545D01*
X28644Y937212D01*
X28334Y938879D01*
X27559Y939920D01*
X26474Y940754D01*
X25389Y940962D01*
X24304Y940754D01*
X22909Y939920D01*
X23374Y945337D01*
X27559D01*
G01X37634D02*
X36394Y944920D01*
X35464Y943879D01*
X34844Y942629D01*
X34379Y940962D01*
X34224Y939087D01*
X34379Y937212D01*
X34844Y935545D01*
X35464Y934295D01*
X36394Y933254D01*
X37634Y932837D01*
X38874Y933254D01*
X39804Y934295D01*
X40424Y935545D01*
X40889Y937212D01*
X41044Y939087D01*
X40889Y940962D01*
X40424Y942629D01*
X39804Y943879D01*
X38874Y944920D01*
X37634Y945337D01*
G01X46004Y932837D02*
Y945337D01*
X50034Y934920D01*
X54064Y945337D01*
Y932837D01*
G01X58404D02*
Y945337D01*
X62434Y934920D01*
X66464Y945337D01*
Y932837D01*
G01X-18819Y-478346D02*
Y-517716D01*
G01X-3000Y0D02*
X-13235D01*
G01X0Y-3000D02*
Y-35155D01*
G01X7874Y450000D02*
G03X0Y442126I0J-7874D01*
G01Y335630D01*
G03X984Y334646I984J0D01*
G01X8858D01*
G02X10827Y332677I0J-1969D01*
G01Y322835D01*
G02X8858Y320866I-1969J0D01*
G01X984D01*
G03X0Y319882I0J-984D01*
G01Y7874D01*
G03X7874Y0I7874J0D01*
G01X346457D01*
G03X354331Y7874I0J7874D01*
G01Y319882D01*
G03X353346Y320866I-984J0D01*
G01X345472D01*
G02X343504Y322835I0J1968D01*
G01Y332677D01*
G02X345472Y334646I1968J0D01*
G01X353346D01*
G03X354331Y335630I1J984D01*
G01Y442126D01*
G03X346457Y450000I-7874J0D01*
G01X336614D01*
G02X334646Y451969I0J1969D01*
G01Y469024D01*
X331764Y474016D01*
X314921D01*
X311969Y471063D01*
Y451969D01*
G02X310000Y450000I-1969J0D01*
G01X304094D01*
G02X302126Y451969I1J1969D01*
G01Y471063D01*
X299173Y474016D01*
X265886D01*
X262933Y471063D01*
Y450886D01*
G02X254075I-4429J0D01*
G01Y471063D01*
X251122Y474016D01*
X184783D01*
X181831Y471063D01*
Y450098D01*
G02X174547I-3642J0D01*
G01Y471063D01*
X171594Y474016D01*
X138287D01*
X135335Y471063D01*
Y451870D01*
G02X124508I-5413J0D01*
G01Y471063D01*
X121555Y474016D01*
X55177D01*
X52224Y471063D01*
Y451969D01*
G02X50256Y450000I-1969J0D01*
G01X44350D01*
G02X42382Y451969I0J1969D01*
G01Y471063D01*
X39429Y474016D01*
X22567D01*
X19685Y469024D01*
Y451969D01*
G02X17717Y450000I-1969J0D01*
G01X7874D01*
G01X0Y484016D02*
Y761300D01*
G01X124875Y751300D02*
X0D01*
G01X7000Y752800D02*
X0Y751300D01*
X7000Y749800D01*
Y752800D01*
G01X28297Y-72000D02*
Y-76650D01*
X15797D01*
Y-72000D01*
G01X28297Y-28600D02*
Y-23950D01*
X15797D01*
Y-28600D01*
G01X28346Y46417D02*
G02X15748I-6299J0D01*
G02X28346I6299J0D01*
G01X15748D02*
G02X28346I6299J0D01*
G02X15748I-6299J0D01*
G01D02*
G02X28346I6299J0D01*
G02X15748I-6299J0D01*
G01X30177Y89331D02*
G02X17854I-6161J0D01*
G02X30177I6162J0D01*
G01X17854D02*
G02X30177I6162J0D01*
G02X17854I-6161J0D01*
G01D02*
G02X30177I6162J0D01*
G02X17854I-6161J0D01*
G01X16000Y775500D02*
X18000D01*
Y773100D01*
X17400Y772300D01*
X16700Y771767D01*
X15700Y771500D01*
X14700Y771767D01*
X14000Y772300D01*
X13400Y773100D01*
X13000Y774033D01*
X12800Y775100D01*
Y776033D01*
X13000Y776833D01*
X13400Y777767D01*
X14000Y778567D01*
X14600Y779100D01*
X15400Y779500D01*
X16100D01*
X16900Y779233D01*
X17500Y778700D01*
G01X21400Y771500D02*
Y779500D01*
X23900D01*
X24700Y779100D01*
X25200Y778567D01*
X25400Y777500D01*
X25200Y776433D01*
X24600Y775767D01*
X23900Y775367D01*
X21400D01*
G01X23900D02*
X25400Y771500D01*
G01X31400D02*
X30600Y771633D01*
X29900Y772167D01*
X29300Y772967D01*
X28900Y773900D01*
X28700Y774967D01*
Y776033D01*
X28900Y777100D01*
X29300Y778033D01*
X29900Y778833D01*
X30600Y779367D01*
X31400Y779500D01*
X32200Y779367D01*
X32900Y778833D01*
X33500Y778033D01*
X33900Y777100D01*
X34100Y776033D01*
Y774967D01*
X33900Y773900D01*
X33500Y772967D01*
X32900Y772167D01*
X32200Y771633D01*
X31400Y771500D01*
G01X37200Y779500D02*
Y773767D01*
X37600Y772566D01*
X38400Y771767D01*
X39400Y771500D01*
X40400Y771767D01*
X41200Y772566D01*
X41600Y773767D01*
Y779500D01*
G01X45400Y771500D02*
Y779500D01*
X47800D01*
X48600Y779100D01*
X49200Y778167D01*
X49400Y777100D01*
X49200Y776033D01*
X48700Y775233D01*
X47800Y774833D01*
X45400D01*
G01X53300Y772566D02*
X54100Y771900D01*
X55000Y771500D01*
X55800D01*
X56600Y771900D01*
X57200Y772566D01*
X57500Y773500D01*
X57300Y774433D01*
X56800Y775233D01*
X55900Y775767D01*
X54700Y776033D01*
X54000Y776567D01*
X53700Y777500D01*
X53900Y778433D01*
X54400Y779100D01*
X55100Y779500D01*
X55800D01*
X56500Y779233D01*
X57100Y778567D01*
G01X72200Y775767D02*
X72600Y776167D01*
X72900Y776833D01*
X73100Y777767D01*
X72900Y778567D01*
X72500Y779100D01*
X71800Y779500D01*
X69100D01*
Y771500D01*
X72400D01*
X73100Y772033D01*
X73500Y772833D01*
X73700Y773767D01*
X73500Y774700D01*
X72900Y775500D01*
X72200Y775767D01*
X69100D01*
G01X308110Y929885D02*
X12834D01*
G01X22047Y36417D02*
Y-14575D01*
G01X24016Y79331D02*
Y-14600D01*
X42600D01*
G01X48250Y-72000D02*
Y-76650D01*
X35750D01*
Y-72000D01*
G01X48250Y-28600D02*
Y-23950D01*
X35750D01*
Y-28600D01*
G01X56476Y476378D02*
Y492475D01*
G01X62726Y594100D02*
Y589450D01*
X50226D01*
Y594100D01*
G01X62726Y662300D02*
Y666950D01*
X50226D01*
Y662300D01*
G01X111614Y189721D02*
Y183422D01*
G02X99016I-6299J0D01*
G01Y189721D01*
G02X111614I6299J0D01*
G01X99016D02*
G02X111614I6299J0D01*
G01Y183422D01*
G02X99016I-6299J0D01*
G01Y189721D01*
G01D02*
Y183422D01*
G03X111614I6299J0D01*
G01Y189721D01*
G03X99016I-6299J0D01*
G01X97835Y213343D02*
G02X112795I7480J0D01*
G02X97835I-7480J0D01*
G01X112795D02*
G02X97835I-7480J0D01*
G02X112795I7480J0D01*
G01D02*
G03X97835I-7480J0D01*
G03X112795I7480J0D01*
G01X120256Y476378D02*
Y494800D01*
X113700Y494900D01*
G01X120550Y608500D02*
Y603850D01*
X108050D01*
Y608500D01*
G01X120550Y676700D02*
Y681350D01*
X108050D01*
Y676700D01*
G01X129922Y461870D02*
Y495575D01*
G01X136172Y609600D02*
Y604950D01*
X123672D01*
Y609600D01*
G01X136172Y640600D02*
Y645250D01*
X123672D01*
Y640600D01*
G01X141693Y-609436D02*
Y-684436D01*
G01Y-659436D02*
X244693D01*
Y-634436D01*
G01X141693D02*
X244693D01*
G01X139587Y476378D02*
Y495200D01*
X144900Y495100D01*
X144901Y495475D01*
G01X151450Y609500D02*
Y604850D01*
X138950D01*
Y609500D01*
G01X151450Y677700D02*
Y682350D01*
X138950D01*
Y677700D01*
G01X170295Y476378D02*
Y493400D01*
X163400D01*
X163383Y495275D01*
G01X168750Y609300D02*
Y604650D01*
X156250D01*
Y609300D01*
G01X168750Y677500D02*
Y682150D01*
X156250D01*
Y677500D01*
G01X161050Y732550D02*
X156400D01*
Y745050D01*
X161050D01*
G01X178189Y460098D02*
Y494175D01*
G01X184439Y608200D02*
Y603550D01*
X171939D01*
Y608200D01*
G01X184439Y676400D02*
Y681050D01*
X171939D01*
Y676400D01*
G01X186083Y476378D02*
Y493400D01*
X194200D01*
X194201Y493575D01*
G01X201150Y607600D02*
Y602950D01*
X188650D01*
Y607600D01*
G01X201150Y675800D02*
Y680450D01*
X188650D01*
Y675800D01*
G01X192050Y732550D02*
X196700D01*
Y745050D01*
X192050D01*
G01X242913Y424016D02*
G02X229528I-6693J0D01*
G02X242913I6692J0D01*
G01X229528D02*
G02X242913I6692J0D01*
G02X229528I-6693J0D01*
G01D02*
G02X242913I6692J0D01*
G02X229528I-6693J0D01*
G01X249450Y614400D02*
Y609750D01*
X236950D01*
Y614400D01*
G01X249450Y682600D02*
Y687250D01*
X236950D01*
Y682600D01*
G01X227925Y751300D02*
X354331D01*
G01X246693Y-609436D02*
Y-684436D01*
G01X244693Y-609436D02*
Y-684436D01*
G01X252200Y-669436D02*
Y-664436D01*
X253466D01*
X253973Y-664686D01*
X254353Y-665019D01*
X254670Y-665519D01*
X254923Y-666103D01*
X254986Y-666936D01*
X254923Y-667769D01*
X254670Y-668353D01*
X254353Y-668853D01*
X253973Y-669186D01*
X253466Y-669436D01*
X252200D01*
G01X257110D02*
X258693Y-664436D01*
X260276Y-669436D01*
G01X259706Y-667686D02*
X257680D01*
G01X263793Y-664436D02*
Y-669436D01*
G01X262336Y-664436D02*
X265250D01*
G01X270160Y-669436D02*
X267626D01*
Y-664436D01*
X270160D01*
G01X269146Y-666853D02*
X267626D01*
G01X273993Y-669603D02*
X273866Y-669519D01*
Y-669353D01*
X273993Y-669269D01*
X274120Y-669353D01*
Y-669519D01*
X273993Y-669603D01*
G01Y-667353D02*
X273866Y-667269D01*
Y-667103D01*
X273993Y-667019D01*
X274120Y-667103D01*
Y-667269D01*
X273993Y-667353D01*
G01X246693Y-659436D02*
X446693D01*
G01X252326Y-644436D02*
Y-639436D01*
X253846D01*
X254353Y-639686D01*
X254733Y-640269D01*
X254860Y-640936D01*
X254733Y-641603D01*
X254416Y-642103D01*
X253846Y-642353D01*
X252326D01*
G01X257553Y-644603D02*
X259833Y-639436D01*
G01X262336Y-644436D02*
Y-639436D01*
X265250Y-644436D01*
Y-639436D01*
G01X268893Y-644603D02*
X268766Y-644519D01*
Y-644353D01*
X268893Y-644269D01*
X269020Y-644353D01*
Y-644519D01*
X268893Y-644603D01*
G01Y-642353D02*
X268766Y-642269D01*
Y-642103D01*
X268893Y-642019D01*
X269020Y-642103D01*
Y-642269D01*
X268893Y-642353D01*
G01X246693Y-634436D02*
X446693D01*
G01X252326Y-619436D02*
Y-614436D01*
X253846D01*
X254353Y-614686D01*
X254733Y-615269D01*
X254860Y-615936D01*
X254733Y-616603D01*
X254416Y-617103D01*
X253846Y-617353D01*
X252326D01*
G01X257426Y-619436D02*
Y-614436D01*
X259010D01*
X259516Y-614686D01*
X259833Y-615019D01*
X259960Y-615686D01*
X259833Y-616353D01*
X259453Y-616769D01*
X259010Y-617019D01*
X257426D01*
G01X259010D02*
X259960Y-619436D01*
G01X263793D02*
X263286Y-619353D01*
X262843Y-619019D01*
X262463Y-618519D01*
X262210Y-617936D01*
X262083Y-617269D01*
Y-616603D01*
X262210Y-615936D01*
X262463Y-615353D01*
X262843Y-614853D01*
X263286Y-614519D01*
X263793Y-614436D01*
X264300Y-614519D01*
X264743Y-614853D01*
X265123Y-615353D01*
X265376Y-615936D01*
X265503Y-616603D01*
Y-617269D01*
X265376Y-617936D01*
X265123Y-618519D01*
X264743Y-619019D01*
X264300Y-619353D01*
X263793Y-619436D01*
G01X267626Y-618436D02*
X267943Y-618936D01*
X268323Y-619269D01*
X268766Y-619436D01*
X269273Y-619269D01*
X269653Y-618936D01*
X270033Y-618436D01*
X270160Y-617769D01*
Y-614436D01*
G01X275260Y-619436D02*
X272726D01*
Y-614436D01*
X275260D01*
G01X274246Y-616853D02*
X272726D01*
G01X280486Y-614853D02*
X280106Y-614603D01*
X279663Y-614436D01*
X279156D01*
X278586Y-614686D01*
X278143Y-615103D01*
X277826Y-615603D01*
X277573Y-616436D01*
X277510Y-617186D01*
X277636Y-617936D01*
X277826Y-618436D01*
X278206Y-618936D01*
X278650Y-619269D01*
X279093Y-619436D01*
X279536D01*
X279980Y-619269D01*
X280360Y-619019D01*
X280676Y-618686D01*
G01X284193Y-614436D02*
Y-619436D01*
G01X282736Y-614436D02*
X285650D01*
G01X289293Y-619603D02*
X289166Y-619519D01*
Y-619353D01*
X289293Y-619269D01*
X289420Y-619353D01*
Y-619519D01*
X289293Y-619603D01*
G01Y-617353D02*
X289166Y-617269D01*
Y-617103D01*
X289293Y-617019D01*
X289420Y-617103D01*
Y-617269D01*
X289293Y-617353D01*
G01X249862Y475590D02*
Y493900D01*
X243500Y493800D01*
X243481Y500375D01*
G01X264754Y615500D02*
Y610850D01*
X252254D01*
Y615500D01*
G01X264754Y683700D02*
Y688350D01*
X252254D01*
Y683700D01*
G01X255460Y908700D02*
Y921200D01*
X249725Y912242D01*
X257475D01*
G01X261970Y908700D02*
Y921200D01*
X266000Y910783D01*
X270030Y921200D01*
Y908700D01*
G01X274370D02*
Y921200D01*
X278400Y910783D01*
X282430Y921200D01*
Y908700D01*
G01X258504Y460886D02*
Y501475D01*
G01X267165Y476378D02*
Y493100D01*
X272200Y492900D01*
X272206Y499575D01*
G01X278550Y613600D02*
Y608950D01*
X266050D01*
Y613600D01*
G01X278550Y681800D02*
Y686450D01*
X266050D01*
Y681800D01*
G01X292362Y902326D02*
X260866D01*
G01D02*
X300236D01*
G01X297874Y476378D02*
Y493100D01*
X286000D01*
Y496300D01*
G01X292050Y608400D02*
Y603750D01*
X279550D01*
Y608400D01*
G01X292050Y676600D02*
Y681250D01*
X279550D01*
Y676600D01*
G01X307874Y424016D02*
G02X294488I-6693J0D01*
G02X307874I6693J0D01*
G01X294488D02*
G02X307874I6693J0D01*
G02X294488I-6693J0D01*
G01D02*
G02X307874I6693J0D01*
G02X294488I-6693J0D01*
G01X292362Y827522D02*
X308110Y835396D01*
G01X343543Y847207D02*
X300236D01*
G01X343543Y843270D02*
X300236D01*
G01X308110Y835396D02*
X292362Y843270D01*
G01Y847207D02*
X308110Y855082D01*
G01X292362Y866893D02*
Y910200D01*
G01X308110Y855082D02*
X292362Y862956D01*
G01X339606Y902326D02*
X300236D01*
G01X308110Y859018D02*
Y910200D01*
G01Y859018D02*
Y937759D01*
G01Y902326D02*
X339606D01*
G01X336565Y-93800D02*
Y-98450D01*
X324065D01*
Y-93800D01*
G01X336565Y-38000D02*
Y-33350D01*
X324065D01*
Y-38000D01*
G01X330315Y79331D02*
Y-23975D01*
G01X339764Y46417D02*
G02X327165I-6299J0D01*
G02X339764I6299J0D01*
G01X327165D02*
G02X339764I6299J0D01*
G02X327165I-6299J0D01*
G01D02*
G02X339764I6299J0D01*
G02X327165I-6299J0D01*
G01X336476Y89331D02*
G02X324154I-6161J0D01*
G02X336476I6161J0D01*
G01X324154D02*
G02X336476I6161J0D01*
G02X324154I-6161J0D01*
G01D02*
G02X336476I6161J0D01*
G02X324154I-6161J0D01*
G01X324162Y804093D02*
Y847400D01*
G01X353350Y-94100D02*
Y-98750D01*
X340850D01*
Y-94100D01*
G01X353350Y-38300D02*
Y-33650D01*
X340850D01*
Y-38300D01*
G01X333466Y36417D02*
Y-23900D01*
X347800D01*
X347797Y-24275D01*
G01X343466Y46417D02*
X471300D01*
G01X348100Y809500D02*
X335600D01*
X338100Y807640D01*
G01X348100D02*
Y811360D01*
G01Y817870D02*
X335600D01*
X346017Y821900D01*
X335600Y825930D01*
X348100D01*
G01Y830270D02*
X335600D01*
X346017Y834300D01*
X335600Y838330D01*
X348100D01*
G01X354331Y484016D02*
Y761300D01*
G01X347331Y749800D02*
X354331Y751300D01*
X347331Y752800D01*
Y749800D01*
G01X368100Y845300D02*
X370100D01*
Y842900D01*
X369500Y842100D01*
X368800Y841567D01*
X367800Y841300D01*
X366800Y841567D01*
X366100Y842100D01*
X365500Y842900D01*
X365100Y843833D01*
X364900Y844900D01*
Y845833D01*
X365100Y846633D01*
X365500Y847567D01*
X366100Y848367D01*
X366700Y848900D01*
X367500Y849300D01*
X368200D01*
X369000Y849033D01*
X369600Y848500D01*
G01X373500Y841300D02*
Y849300D01*
X376000D01*
X376800Y848900D01*
X377300Y848367D01*
X377500Y847300D01*
X377300Y846233D01*
X376700Y845567D01*
X376000Y845167D01*
X373500D01*
G01X376000D02*
X377500Y841300D01*
G01X383500D02*
X382700Y841433D01*
X382000Y841967D01*
X381400Y842767D01*
X381000Y843700D01*
X380800Y844767D01*
Y845833D01*
X381000Y846900D01*
X381400Y847833D01*
X382000Y848633D01*
X382700Y849167D01*
X383500Y849300D01*
X384300Y849167D01*
X385000Y848633D01*
X385600Y847833D01*
X386000Y846900D01*
X386200Y845833D01*
Y844767D01*
X386000Y843700D01*
X385600Y842767D01*
X385000Y841967D01*
X384300Y841433D01*
X383500Y841300D01*
G01X389300Y849300D02*
Y843567D01*
X389700Y842366D01*
X390500Y841567D01*
X391500Y841300D01*
X392500Y841567D01*
X393300Y842366D01*
X393700Y843567D01*
Y849300D01*
G01X397500Y841300D02*
Y849300D01*
X399900D01*
X400700Y848900D01*
X401300Y847967D01*
X401500Y846900D01*
X401300Y845833D01*
X400800Y845033D01*
X399900Y844633D01*
X397500D01*
G01X405400Y842366D02*
X406200Y841700D01*
X407100Y841300D01*
X407900D01*
X408700Y841700D01*
X409300Y842366D01*
X409600Y843300D01*
X409400Y844233D01*
X408900Y845033D01*
X408000Y845567D01*
X406800Y845833D01*
X406100Y846367D01*
X405800Y847300D01*
X406000Y848233D01*
X406500Y848900D01*
X407200Y849300D01*
X407900D01*
X408600Y849033D01*
X409200Y848367D01*
G01X421000Y841300D02*
X423500Y849300D01*
X426000Y841300D01*
G01X425100Y844100D02*
X421900D01*
G01X361693Y-659436D02*
Y-684436D01*
G01X364326Y-661936D02*
Y-666936D01*
X366860D01*
G01X369933Y-661936D02*
X371453D01*
G01X370693D02*
Y-666936D01*
G01X369933D02*
X371453D01*
G01X376300Y-664269D02*
X376553Y-664019D01*
X376743Y-663603D01*
X376870Y-663019D01*
X376743Y-662519D01*
X376490Y-662186D01*
X376046Y-661936D01*
X374336D01*
Y-666936D01*
X376426D01*
X376870Y-666603D01*
X377123Y-666103D01*
X377250Y-665519D01*
X377123Y-664936D01*
X376743Y-664436D01*
X376300Y-664269D01*
X374336D01*
G01X380893Y-667103D02*
X380766Y-667019D01*
Y-666853D01*
X380893Y-666769D01*
X381020Y-666853D01*
Y-667019D01*
X380893Y-667103D01*
G01Y-664853D02*
X380766Y-664769D01*
Y-664603D01*
X380893Y-664519D01*
X381020Y-664603D01*
Y-664769D01*
X380893Y-664853D01*
G01X364331Y0D02*
X579600D01*
G01X364331Y474016D02*
X579600D01*
G01X404693Y-659436D02*
Y-684436D01*
G01Y-634436D02*
Y-659436D01*
G01X412706Y-687603D02*
X412813Y-687478D01*
X412893Y-687269D01*
X412946Y-686978D01*
X412893Y-686728D01*
X412786Y-686561D01*
X412600Y-686436D01*
X411880D01*
Y-688936D01*
X412760D01*
X412946Y-688769D01*
X413053Y-688519D01*
X413106Y-688228D01*
X413053Y-687936D01*
X412893Y-687686D01*
X412706Y-687603D01*
X411880D01*
G01X415173Y-688936D02*
Y-687269D01*
G01Y-687561D02*
X415066Y-687394D01*
X414906Y-687311D01*
X414720Y-687269D01*
X414533Y-687353D01*
X414373Y-687519D01*
X414266Y-687769D01*
X414213Y-688103D01*
X414266Y-688436D01*
X414373Y-688686D01*
X414533Y-688853D01*
X414720Y-688936D01*
X414906Y-688894D01*
X415066Y-688769D01*
X415173Y-688603D01*
G01X416493Y-688644D02*
X416626Y-688811D01*
X416813Y-688936D01*
X416973D01*
X417133Y-688853D01*
X417240Y-688728D01*
X417293Y-688561D01*
X417266Y-688311D01*
X417160Y-688186D01*
X416680Y-687936D01*
X416573Y-687644D01*
X416626Y-687436D01*
X416733Y-687311D01*
X416893Y-687269D01*
X417053Y-687311D01*
X417213Y-687436D01*
G01X418693Y-687811D02*
X419546D01*
X419466Y-687519D01*
X419333Y-687353D01*
X419146Y-687269D01*
X418960Y-687311D01*
X418800Y-687436D01*
X418693Y-687728D01*
X418640Y-687978D01*
Y-688228D01*
X418693Y-688478D01*
X418826Y-688728D01*
X418986Y-688894D01*
X419173Y-688936D01*
X419360Y-688853D01*
X419546Y-688603D01*
G01X420813Y-688936D02*
Y-686436D01*
G01Y-687686D02*
X420946Y-687436D01*
X421106Y-687311D01*
X421266Y-687269D01*
X421506Y-687353D01*
X421666Y-687519D01*
X421773Y-687811D01*
Y-688144D01*
X421720Y-688478D01*
X421613Y-688728D01*
X421426Y-688894D01*
X421266Y-688936D01*
X421106Y-688894D01*
X420946Y-688769D01*
X420813Y-688561D01*
G01X423493Y-688936D02*
X423333Y-688894D01*
X423173Y-688728D01*
X423066Y-688436D01*
X423013Y-688103D01*
X423066Y-687769D01*
X423173Y-687478D01*
X423333Y-687311D01*
X423493Y-687269D01*
X423653Y-687311D01*
X423813Y-687478D01*
X423920Y-687769D01*
X423946Y-688103D01*
X423920Y-688436D01*
X423813Y-688728D01*
X423653Y-688894D01*
X423493Y-688936D01*
G01X426173D02*
Y-687269D01*
G01Y-687561D02*
X426066Y-687394D01*
X425906Y-687311D01*
X425720Y-687269D01*
X425533Y-687353D01*
X425373Y-687519D01*
X425266Y-687769D01*
X425213Y-688103D01*
X425266Y-688436D01*
X425373Y-688686D01*
X425533Y-688853D01*
X425720Y-688936D01*
X425906Y-688894D01*
X426066Y-688769D01*
X426173Y-688603D01*
G01X427520Y-688936D02*
Y-687269D01*
G01Y-687603D02*
X427653Y-687436D01*
X427786Y-687311D01*
X427973Y-687269D01*
X428106Y-687311D01*
X428266Y-687436D01*
G01X430573Y-686436D02*
Y-688936D01*
G01Y-688561D02*
X430466Y-688769D01*
X430306Y-688894D01*
X430120Y-688936D01*
X429906Y-688853D01*
X429746Y-688644D01*
X429640Y-688394D01*
X429613Y-688103D01*
X429640Y-687811D01*
X429746Y-687561D01*
X429906Y-687353D01*
X430120Y-687269D01*
X430306Y-687311D01*
X430440Y-687394D01*
X430573Y-687561D01*
G01X433960Y-688936D02*
Y-686436D01*
X434626D01*
X434840Y-686561D01*
X434973Y-686728D01*
X435026Y-687061D01*
X434973Y-687394D01*
X434813Y-687603D01*
X434626Y-687728D01*
X433960D01*
G01X434626D02*
X435026Y-688936D01*
G01X436293Y-687811D02*
X437146D01*
X437066Y-687519D01*
X436933Y-687353D01*
X436746Y-687269D01*
X436560Y-687311D01*
X436400Y-687436D01*
X436293Y-687728D01*
X436240Y-687978D01*
Y-688228D01*
X436293Y-688478D01*
X436426Y-688728D01*
X436586Y-688894D01*
X436773Y-688936D01*
X436960Y-688853D01*
X437146Y-688603D01*
G01X438413Y-687269D02*
X438893Y-688936D01*
X439373Y-687269D01*
G01X441093Y-689019D02*
X441040Y-688978D01*
Y-688894D01*
X441093Y-688853D01*
X441146Y-688894D01*
Y-688978D01*
X441093Y-689019D01*
G01X443613Y-688936D02*
Y-686436D01*
X442626Y-688228D01*
X443960D01*
G01X444826Y-688936D02*
X445493Y-686436D01*
X446160Y-688936D01*
G01X445920Y-688061D02*
X445066D01*
G01X408593Y-661936D02*
Y-666936D01*
G01X407136Y-661936D02*
X410050D01*
G01X413693Y-666936D02*
X413313Y-666853D01*
X412933Y-666519D01*
X412680Y-665936D01*
X412553Y-665269D01*
X412680Y-664603D01*
X412933Y-664019D01*
X413313Y-663686D01*
X413693Y-663603D01*
X414073Y-663686D01*
X414453Y-664019D01*
X414706Y-664603D01*
X414770Y-665269D01*
X414706Y-665936D01*
X414453Y-666519D01*
X414073Y-666853D01*
X413693Y-666936D01*
G01X418793D02*
X418413Y-666853D01*
X418033Y-666519D01*
X417780Y-665936D01*
X417653Y-665269D01*
X417780Y-664603D01*
X418033Y-664019D01*
X418413Y-663686D01*
X418793Y-663603D01*
X419173Y-663686D01*
X419553Y-664019D01*
X419806Y-664603D01*
X419870Y-665269D01*
X419806Y-665936D01*
X419553Y-666519D01*
X419173Y-666853D01*
X418793Y-666936D01*
G01X423893D02*
Y-661936D01*
G01X428993Y-667103D02*
X428866Y-667019D01*
Y-666853D01*
X428993Y-666769D01*
X429120Y-666853D01*
Y-667019D01*
X428993Y-667103D01*
G01Y-664853D02*
X428866Y-664769D01*
Y-664603D01*
X428993Y-664519D01*
X429120Y-664603D01*
Y-664769D01*
X428993Y-664853D01*
G01X407326Y-641936D02*
Y-636936D01*
X408910D01*
X409416Y-637186D01*
X409733Y-637519D01*
X409860Y-638186D01*
X409733Y-638853D01*
X409353Y-639269D01*
X408910Y-639519D01*
X407326D01*
G01X408910D02*
X409860Y-641936D01*
G01X414960D02*
X412426D01*
Y-636936D01*
X414960D01*
G01X413946Y-639353D02*
X412426D01*
G01X417210Y-636936D02*
X418793Y-641936D01*
X420376Y-636936D01*
G01X423893Y-642103D02*
X423766Y-642019D01*
Y-641853D01*
X423893Y-641769D01*
X424020Y-641853D01*
Y-642019D01*
X423893Y-642103D01*
G01Y-639853D02*
X423766Y-639769D01*
Y-639603D01*
X423893Y-639519D01*
X424020Y-639603D01*
Y-639769D01*
X423893Y-639853D01*
G01X452932Y415899D02*
X449832D01*
Y416819D01*
X449987Y417126D01*
X450349Y417356D01*
X450762Y417433D01*
X451175Y417356D01*
X451485Y417164D01*
X451640Y416819D01*
Y415899D01*
G01X450090Y420609D02*
X449935Y420379D01*
X449832Y420111D01*
Y419804D01*
X449987Y419459D01*
X450245Y419191D01*
X450555Y418999D01*
X451072Y418846D01*
X451537Y418808D01*
X452002Y418884D01*
X452312Y418999D01*
X452622Y419229D01*
X452829Y419498D01*
X452932Y419766D01*
Y420034D01*
X452829Y420303D01*
X452674Y420533D01*
X452467Y420724D01*
G01X451279Y423173D02*
X451124Y423326D01*
X450865Y423441D01*
X450504Y423518D01*
X450194Y423441D01*
X449987Y423288D01*
X449832Y423019D01*
Y421984D01*
X452932D01*
Y423249D01*
X452725Y423518D01*
X452415Y423671D01*
X452054Y423748D01*
X451692Y423671D01*
X451382Y423441D01*
X451279Y423173D01*
Y421984D01*
G01X449832Y428108D02*
X452932Y429066D01*
X449832Y430024D01*
G01X452932Y432933D02*
Y431399D01*
X449832D01*
Y432933D01*
G01X451330Y432319D02*
Y431399D01*
G01X452932Y434384D02*
X449832D01*
X452932Y436148D01*
X449832D01*
G01X452932Y437523D02*
X449832D01*
Y438289D01*
X449987Y438596D01*
X450194Y438826D01*
X450504Y439018D01*
X450865Y439171D01*
X451382Y439209D01*
X451899Y439171D01*
X452260Y439018D01*
X452570Y438826D01*
X452777Y438596D01*
X452932Y438289D01*
Y437523D01*
G01Y441466D02*
X452880Y441159D01*
X452674Y440891D01*
X452364Y440661D01*
X452002Y440508D01*
X451589Y440431D01*
X451175D01*
X450762Y440508D01*
X450400Y440661D01*
X450090Y440891D01*
X449884Y441159D01*
X449832Y441466D01*
X449884Y441773D01*
X450090Y442041D01*
X450400Y442271D01*
X450762Y442424D01*
X451175Y442501D01*
X451589D01*
X452002Y442424D01*
X452364Y442271D01*
X452674Y442041D01*
X452880Y441773D01*
X452932Y441466D01*
G01Y443799D02*
X449832D01*
Y444758D01*
X449987Y445064D01*
X450194Y445256D01*
X450607Y445333D01*
X451020Y445256D01*
X451279Y445026D01*
X451434Y444758D01*
Y443799D01*
G01Y444758D02*
X452932Y445333D01*
G01X444882Y414961D02*
Y474016D01*
X484252D01*
Y414961D01*
X444882D01*
G01X455232Y424299D02*
X458332D01*
Y425833D01*
G01Y428166D02*
X458280Y427859D01*
X458074Y427591D01*
X457764Y427361D01*
X457402Y427208D01*
X456989Y427131D01*
X456575D01*
X456162Y427208D01*
X455800Y427361D01*
X455490Y427591D01*
X455284Y427859D01*
X455232Y428166D01*
X455284Y428473D01*
X455490Y428741D01*
X455800Y428971D01*
X456162Y429124D01*
X456575Y429201D01*
X456989D01*
X457402Y429124D01*
X457764Y428971D01*
X458074Y428741D01*
X458280Y428473D01*
X458332Y428166D01*
G01X456782Y431496D02*
Y432263D01*
X457712D01*
X458022Y432033D01*
X458229Y431764D01*
X458332Y431381D01*
X458229Y430998D01*
X458022Y430729D01*
X457712Y430499D01*
X457350Y430346D01*
X456937Y430269D01*
X456575D01*
X456265Y430346D01*
X455904Y430499D01*
X455594Y430729D01*
X455387Y430959D01*
X455232Y431266D01*
Y431534D01*
X455335Y431841D01*
X455542Y432071D01*
G01X458332Y434366D02*
X458280Y434059D01*
X458074Y433791D01*
X457764Y433561D01*
X457402Y433408D01*
X456989Y433331D01*
X456575D01*
X456162Y433408D01*
X455800Y433561D01*
X455490Y433791D01*
X455284Y434059D01*
X455232Y434366D01*
X455284Y434673D01*
X455490Y434941D01*
X455800Y435171D01*
X456162Y435324D01*
X456575Y435401D01*
X456989D01*
X457402Y435324D01*
X457764Y435171D01*
X458074Y434941D01*
X458280Y434673D01*
X458332Y434366D01*
G01X481000Y28450D02*
X476350D01*
Y40950D01*
X481000D01*
G01X549200Y28450D02*
X553850D01*
Y40950D01*
X549200D01*
G01X568100Y7000D02*
X569600Y0D01*
X571100Y7000D01*
X568100D01*
G01X571100Y467016D02*
X569600Y474016D01*
X568100Y467016D01*
X571100D01*
G01X569600Y210875D02*
Y0D01*
G01X588350Y228450D02*
Y223800D01*
X575850D01*
Y228450D01*
G01X588350Y296650D02*
Y301300D01*
X575850D01*
Y296650D01*
G01X569600Y313925D02*
Y474016D01*
G01X723800Y-192850D02*
Y477500D01*
X1749900D01*
Y-192850D01*
X723800D01*
G01Y-164500D02*
X1749900D01*
G01X723800Y-136150D02*
X1749900D01*
G01X723800Y-107800D02*
X1749900D01*
G01X723800Y-79450D02*
X1749900D01*
G01X723800Y-51100D02*
X1749900D01*
G01X723800Y-22750D02*
X1749900D01*
G01X723800Y5600D02*
X1749900D01*
G01X723800Y33950D02*
X1749900D01*
G01X723800Y62300D02*
X1749900D01*
G01X723800Y90650D02*
X1749900D01*
G01X723800Y119000D02*
X1749900D01*
G01X723800Y147350D02*
X1749900D01*
G01X723800Y175700D02*
X1749900D01*
G01X723800Y204050D02*
X1749900D01*
G01X723800Y232400D02*
X1749900D01*
G01X723800Y260750D02*
X1749900D01*
G01X723800Y289100D02*
X1749900D01*
G01X723800Y317450D02*
X1749900D01*
G01X723800Y345800D02*
X1749900D01*
G01X723800Y374150D02*
X1749900D01*
G01X723800Y402500D02*
X1749900D01*
G01X723800Y427500D02*
X1749900D01*
G01X723800Y452500D02*
X1749900D01*
G01X813700Y427500D02*
Y-192850D01*
G01X1015200Y427500D02*
Y-192850D01*
G01X1142300Y427500D02*
Y-192850D01*
G01X1343800Y427500D02*
Y-192850D01*
G01X1545300Y427500D02*
Y-192850D01*
G01X1672400Y427500D02*
Y-192850D01*
G01X2010999Y-388000D02*
Y1475775D01*
X-407000D01*
Y-386798D01*
Y-755294D01*
Y-793716D01*
X-368578D01*
X1942346D01*
X2010999D01*
Y-725063D01*
Y-388000D01*
G01X-196200Y83081D02*
X-195115Y83289D01*
X-193875Y83914D01*
X-193100Y84956D01*
X-192790Y86414D01*
X-193100Y87872D01*
X-194030Y89123D01*
X-195425Y89748D01*
X-196975D01*
X-197905Y90164D01*
X-198680Y91206D01*
X-198990Y92664D01*
X-198525Y94123D01*
X-197440Y95164D01*
X-196200Y95581D01*
X-194960Y95164D01*
X-193875Y94123D01*
X-193410Y92664D01*
X-193720Y91206D01*
X-194495Y90164D01*
X-195425Y89748D01*
X-196975D01*
X-198370Y89123D01*
X-199300Y87872D01*
X-199610Y86414D01*
X-199300Y84956D01*
X-198525Y83914D01*
X-197285Y83289D01*
X-196200Y83081D01*
G01X-186435Y84539D02*
X-185350Y83498D01*
X-184110Y83081D01*
X-182870Y83498D01*
X-181785Y84747D01*
X-181010Y86623D01*
X-180700Y88498D01*
Y90789D01*
X-181010Y92664D01*
X-181785Y94331D01*
X-182715Y95164D01*
X-183800Y95581D01*
X-185040Y95164D01*
X-185970Y94331D01*
X-186590Y93081D01*
X-186900Y91414D01*
X-186590Y89956D01*
X-185815Y88498D01*
X-184885Y87664D01*
X-183800Y87456D01*
X-182560Y87872D01*
X-181630Y88914D01*
X-180700Y90789D01*
G01X-174810Y85581D02*
X-173880Y84122D01*
X-172640Y83289D01*
X-171245Y83081D01*
X-170005Y83289D01*
X-168765Y84331D01*
X-167990Y85581D01*
X-167835Y86831D01*
X-168145Y88289D01*
X-169230Y89331D01*
X-170315Y89748D01*
X-171710D01*
G01X-170315D02*
X-169385Y90373D01*
X-168610Y91414D01*
X-168300Y92664D01*
X-168610Y93914D01*
X-169385Y94956D01*
X-170780Y95581D01*
X-172175Y95373D01*
X-173570Y94539D01*
G01X-159000Y82664D02*
X-159310Y82873D01*
Y83289D01*
X-159000Y83498D01*
X-158690Y83289D01*
Y82873D01*
X-159000Y82664D01*
G01X-150010Y85581D02*
X-149080Y84122D01*
X-147840Y83289D01*
X-146445Y83081D01*
X-145205Y83289D01*
X-143965Y84331D01*
X-143190Y85581D01*
X-143035Y86831D01*
X-143345Y88289D01*
X-144430Y89331D01*
X-145515Y89748D01*
X-146910D01*
G01X-145515D02*
X-144585Y90373D01*
X-143810Y91414D01*
X-143500Y92664D01*
X-143810Y93914D01*
X-144585Y94956D01*
X-145980Y95581D01*
X-147375Y95373D01*
X-148770Y94539D01*
G01X-134200Y83081D02*
Y95581D01*
X-136060Y93081D01*
G01Y83081D02*
X-132340D01*
G01X-102545Y93498D02*
X-101615Y94747D01*
X-100530Y95373D01*
X-99290Y95581D01*
X-97740Y95164D01*
X-96655Y94123D01*
X-96345Y92873D01*
X-96500Y91622D01*
X-97120Y90581D01*
X-100220Y88498D01*
X-101615Y87039D01*
X-102545Y84956D01*
X-102855Y83081D01*
X-96345D01*
G01X-90145Y93498D02*
X-89215Y94747D01*
X-88130Y95373D01*
X-86890Y95581D01*
X-85340Y95164D01*
X-84255Y94123D01*
X-83945Y92873D01*
X-84100Y91622D01*
X-84720Y90581D01*
X-87820Y88498D01*
X-89215Y87039D01*
X-90145Y84956D01*
X-90455Y83081D01*
X-83945D01*
G01X-74800Y82664D02*
X-75110Y82873D01*
Y83289D01*
X-74800Y83498D01*
X-74490Y83289D01*
Y82873D01*
X-74800Y82664D01*
G01X-65345Y88289D02*
X-64260Y89748D01*
X-63330Y90581D01*
X-62090Y90998D01*
X-61005Y90581D01*
X-60230Y89748D01*
X-59610Y88498D01*
X-59455Y87039D01*
X-59610Y85789D01*
X-60230Y84539D01*
X-61160Y83498D01*
X-62245Y83081D01*
X-63485Y83498D01*
X-64570Y84747D01*
X-65190Y86623D01*
X-65345Y88706D01*
X-65035Y91414D01*
X-64570Y92873D01*
X-63795Y94331D01*
X-62710Y95373D01*
X-61625Y95581D01*
X-60540Y95164D01*
X-59765Y94123D01*
G01X-52635Y84539D02*
X-51550Y83498D01*
X-50310Y83081D01*
X-49070Y83498D01*
X-47985Y84747D01*
X-47210Y86623D01*
X-46900Y88498D01*
Y90789D01*
X-47210Y92664D01*
X-47985Y94331D01*
X-48915Y95164D01*
X-50000Y95581D01*
X-51240Y95164D01*
X-52170Y94331D01*
X-52790Y93081D01*
X-53100Y91414D01*
X-52790Y89956D01*
X-52015Y88498D01*
X-51085Y87664D01*
X-50000Y87456D01*
X-48760Y87872D01*
X-47830Y88914D01*
X-46900Y90789D01*
G01X-42602Y-671096D02*
X-41975Y-671621D01*
X-41270Y-671936D01*
X-40644D01*
X-40017Y-671621D01*
X-39547Y-671096D01*
X-39312Y-670361D01*
X-39469Y-669626D01*
X-39860Y-668996D01*
X-40565Y-668576D01*
X-41505Y-668366D01*
X-42054Y-667946D01*
X-42289Y-667211D01*
X-42132Y-666476D01*
X-41740Y-665951D01*
X-41192Y-665636D01*
X-40644D01*
X-40095Y-665846D01*
X-39625Y-666371D01*
G01X-36302Y-671936D02*
Y-665636D01*
G01X-33012D02*
Y-671936D01*
G01Y-668786D02*
X-36302D01*
G01X-29297Y-665636D02*
X-27417D01*
G01X-28357D02*
Y-671936D01*
G01X-29297D02*
X-27417D01*
G01X-20490D02*
X-23624D01*
Y-665636D01*
X-20490D01*
G01X-21744Y-668681D02*
X-23624D01*
G01X-17559Y-671936D02*
Y-665636D01*
X-13955Y-671936D01*
Y-665636D01*
G01X-9614Y-673091D02*
X-9300Y-671726D01*
G01X-3157Y-665636D02*
Y-671936D01*
G01X-4959Y-665636D02*
X-1355D01*
G01X1185Y-671936D02*
X3143Y-665636D01*
X5101Y-671936D01*
G01X4396Y-669731D02*
X1890D01*
G01X8503Y-665636D02*
X10383D01*
G01X9443D02*
Y-671936D01*
G01X8503D02*
X10383D01*
G01X13393Y-665636D02*
X14490Y-671936D01*
X15743Y-665636D01*
X16996Y-671936D01*
X18093Y-665636D01*
G01X20085Y-671936D02*
X22043Y-665636D01*
X24001Y-671936D01*
G01X23296Y-669731D02*
X20790D01*
G01X26541Y-671936D02*
Y-665636D01*
X30145Y-671936D01*
Y-665636D01*
G01X39376Y-671936D02*
Y-665636D01*
X41335D01*
X41961Y-665951D01*
X42353Y-666371D01*
X42510Y-667211D01*
X42353Y-668051D01*
X41883Y-668576D01*
X41335Y-668891D01*
X39376D01*
G01X41335D02*
X42510Y-671936D01*
G01X47243Y-672146D02*
X47086Y-672041D01*
Y-671831D01*
X47243Y-671726D01*
X47400Y-671831D01*
Y-672041D01*
X47243Y-672146D01*
G01X53543Y-671936D02*
X52916Y-671831D01*
X52368Y-671411D01*
X51898Y-670781D01*
X51585Y-670046D01*
X51428Y-669206D01*
Y-668366D01*
X51585Y-667526D01*
X51898Y-666791D01*
X52368Y-666161D01*
X52916Y-665741D01*
X53543Y-665636D01*
X54170Y-665741D01*
X54718Y-666161D01*
X55188Y-666791D01*
X55501Y-667526D01*
X55658Y-668366D01*
Y-669206D01*
X55501Y-670046D01*
X55188Y-670781D01*
X54718Y-671411D01*
X54170Y-671831D01*
X53543Y-671936D01*
G01X59843Y-672146D02*
X59686Y-672041D01*
Y-671831D01*
X59843Y-671726D01*
X60000Y-671831D01*
Y-672041D01*
X59843Y-672146D01*
G01X67866Y-666161D02*
X67396Y-665846D01*
X66848Y-665636D01*
X66221D01*
X65516Y-665951D01*
X64968Y-666476D01*
X64576Y-667106D01*
X64263Y-668156D01*
X64185Y-669101D01*
X64341Y-670046D01*
X64576Y-670676D01*
X65046Y-671306D01*
X65595Y-671726D01*
X66143Y-671936D01*
X66691D01*
X67240Y-671726D01*
X67710Y-671411D01*
X68101Y-670991D01*
G01X72443Y-672146D02*
X72286Y-672041D01*
Y-671831D01*
X72443Y-671726D01*
X72600Y-671831D01*
Y-672041D01*
X72443Y-672146D01*
G01X-42680Y-661936D02*
Y-655636D01*
G01X-39704D02*
X-42680Y-659521D01*
G01X-39234Y-661936D02*
X-41349Y-657736D01*
G01X-36380Y-655636D02*
Y-660151D01*
X-36067Y-661096D01*
X-35440Y-661726D01*
X-34657Y-661936D01*
X-33874Y-661726D01*
X-33247Y-661096D01*
X-32934Y-660151D01*
Y-655636D01*
G01X-26790Y-661936D02*
X-29924D01*
Y-655636D01*
X-26790D01*
G01X-28044Y-658681D02*
X-29924D01*
G01X-22997Y-655636D02*
X-21117D01*
G01X-22057D02*
Y-661936D01*
G01X-22997D02*
X-21117D01*
G01X-11102Y-661096D02*
X-10475Y-661621D01*
X-9770Y-661936D01*
X-9144D01*
X-8517Y-661621D01*
X-8047Y-661096D01*
X-7812Y-660361D01*
X-7969Y-659626D01*
X-8360Y-658996D01*
X-9065Y-658576D01*
X-10005Y-658366D01*
X-10554Y-657946D01*
X-10789Y-657211D01*
X-10632Y-656476D01*
X-10240Y-655951D01*
X-9692Y-655636D01*
X-9144D01*
X-8595Y-655846D01*
X-8125Y-656371D01*
G01X-4802Y-661936D02*
Y-655636D01*
G01X-1512D02*
Y-661936D01*
G01Y-658786D02*
X-4802D01*
G01X1185Y-661936D02*
X3143Y-655636D01*
X5101Y-661936D01*
G01X4396Y-659731D02*
X1890D01*
G01X7641Y-661936D02*
Y-655636D01*
X11245Y-661936D01*
Y-655636D01*
G01X20398Y-661936D02*
Y-655636D01*
G01X23688D02*
Y-661936D01*
G01Y-658786D02*
X20398D01*
G01X26698Y-661096D02*
X27325Y-661621D01*
X28030Y-661936D01*
X28656D01*
X29283Y-661621D01*
X29753Y-661096D01*
X29988Y-660361D01*
X29831Y-659626D01*
X29440Y-658996D01*
X28735Y-658576D01*
X27795Y-658366D01*
X27246Y-657946D01*
X27011Y-657211D01*
X27168Y-656476D01*
X27560Y-655951D01*
X28108Y-655636D01*
X28656D01*
X29205Y-655846D01*
X29675Y-656371D01*
G01X33703Y-655636D02*
X35583D01*
G01X34643D02*
Y-661936D01*
G01X33703D02*
X35583D01*
G01X38985D02*
X40943Y-655636D01*
X42901Y-661936D01*
G01X42196Y-659731D02*
X39690D01*
G01X45441Y-661936D02*
Y-655636D01*
X49045Y-661936D01*
Y-655636D01*
G01X54013Y-658786D02*
X55580D01*
Y-660676D01*
X55110Y-661306D01*
X54561Y-661726D01*
X53778Y-661936D01*
X52995Y-661726D01*
X52446Y-661306D01*
X51976Y-660676D01*
X51663Y-659941D01*
X51506Y-659101D01*
Y-658366D01*
X51663Y-657736D01*
X51976Y-657001D01*
X52446Y-656371D01*
X52916Y-655951D01*
X53543Y-655636D01*
X54091D01*
X54718Y-655846D01*
X55188Y-656266D01*
G01X59686Y-663091D02*
X60000Y-661726D01*
G01X66143Y-655636D02*
Y-661936D01*
G01X64341Y-655636D02*
X67945D01*
G01X70485Y-661936D02*
X72443Y-655636D01*
X74401Y-661936D01*
G01X73696Y-659731D02*
X71190D01*
G01X78743Y-661936D02*
X78116Y-661831D01*
X77568Y-661411D01*
X77098Y-660781D01*
X76785Y-660046D01*
X76628Y-659206D01*
Y-658366D01*
X76785Y-657526D01*
X77098Y-656791D01*
X77568Y-656161D01*
X78116Y-655741D01*
X78743Y-655636D01*
X79370Y-655741D01*
X79918Y-656161D01*
X80388Y-656791D01*
X80701Y-657526D01*
X80858Y-658366D01*
Y-659206D01*
X80701Y-660046D01*
X80388Y-660781D01*
X79918Y-661411D01*
X79370Y-661831D01*
X78743Y-661936D01*
G01X91343D02*
Y-659101D01*
X89776Y-655636D01*
G01X92910D02*
X91343Y-659101D01*
G01X95920Y-655636D02*
Y-660151D01*
X96233Y-661096D01*
X96860Y-661726D01*
X97643Y-661936D01*
X98426Y-661726D01*
X99053Y-661096D01*
X99366Y-660151D01*
Y-655636D01*
G01X101985Y-661936D02*
X103943Y-655636D01*
X105901Y-661936D01*
G01X105196Y-659731D02*
X102690D01*
G01X108441Y-661936D02*
Y-655636D01*
X112045Y-661936D01*
Y-655636D01*
G01X-42759Y-651936D02*
Y-645636D01*
X-39155Y-651936D01*
Y-645636D01*
G01X-34657Y-651936D02*
X-35284Y-651831D01*
X-35832Y-651411D01*
X-36302Y-650781D01*
X-36615Y-650046D01*
X-36772Y-649206D01*
Y-648366D01*
X-36615Y-647526D01*
X-36302Y-646791D01*
X-35832Y-646161D01*
X-35284Y-645741D01*
X-34657Y-645636D01*
X-34030Y-645741D01*
X-33482Y-646161D01*
X-33012Y-646791D01*
X-32699Y-647526D01*
X-32542Y-648366D01*
Y-649206D01*
X-32699Y-650046D01*
X-33012Y-650781D01*
X-33482Y-651411D01*
X-34030Y-651831D01*
X-34657Y-651936D01*
G01X-28357Y-652146D02*
X-28514Y-652041D01*
Y-651831D01*
X-28357Y-651726D01*
X-28200Y-651831D01*
Y-652041D01*
X-28357Y-652146D01*
G01X-22057Y-651936D02*
Y-645636D01*
X-22997Y-646896D01*
G01Y-651936D02*
X-21117D01*
G01X-15757D02*
X-15209Y-651831D01*
X-14582Y-651516D01*
X-14190Y-650991D01*
X-14034Y-650256D01*
X-14190Y-649521D01*
X-14660Y-648891D01*
X-15365Y-648576D01*
X-16149D01*
X-16619Y-648366D01*
X-17010Y-647841D01*
X-17167Y-647106D01*
X-16932Y-646371D01*
X-16384Y-645846D01*
X-15757Y-645636D01*
X-15130Y-645846D01*
X-14582Y-646371D01*
X-14347Y-647106D01*
X-14504Y-647841D01*
X-14895Y-648366D01*
X-15365Y-648576D01*
X-16149D01*
X-16854Y-648891D01*
X-17324Y-649521D01*
X-17480Y-650256D01*
X-17324Y-650991D01*
X-16932Y-651516D01*
X-16305Y-651831D01*
X-15757Y-651936D01*
G01X-9457D02*
X-8909Y-651831D01*
X-8282Y-651516D01*
X-7890Y-650991D01*
X-7734Y-650256D01*
X-7890Y-649521D01*
X-8360Y-648891D01*
X-9065Y-648576D01*
X-9849D01*
X-10319Y-648366D01*
X-10710Y-647841D01*
X-10867Y-647106D01*
X-10632Y-646371D01*
X-10084Y-645846D01*
X-9457Y-645636D01*
X-8830Y-645846D01*
X-8282Y-646371D01*
X-8047Y-647106D01*
X-8204Y-647841D01*
X-8595Y-648366D01*
X-9065Y-648576D01*
X-9849D01*
X-10554Y-648891D01*
X-11024Y-649521D01*
X-11180Y-650256D01*
X-11024Y-650991D01*
X-10632Y-651516D01*
X-10005Y-651831D01*
X-9457Y-651936D01*
G01X-3314Y-653091D02*
X-3000Y-651726D01*
G01X793Y-645636D02*
X1890Y-651936D01*
X3143Y-645636D01*
X4396Y-651936D01*
X5493Y-645636D01*
G01X11010Y-651936D02*
X7876D01*
Y-645636D01*
X11010D01*
G01X9756Y-648681D02*
X7876D01*
G01X13941Y-651936D02*
Y-645636D01*
X17545Y-651936D01*
Y-645636D01*
G01X26698Y-651936D02*
Y-645636D01*
G01X29988D02*
Y-651936D01*
G01Y-648786D02*
X26698D01*
G01X32293Y-645636D02*
X33390Y-651936D01*
X34643Y-645636D01*
X35896Y-651936D01*
X36993Y-645636D01*
G01X38985Y-651936D02*
X40943Y-645636D01*
X42901Y-651936D01*
G01X42196Y-649731D02*
X39690D01*
G01X52055Y-646686D02*
X52525Y-646056D01*
X53073Y-645741D01*
X53700Y-645636D01*
X54483Y-645846D01*
X55031Y-646371D01*
X55188Y-647001D01*
X55110Y-647631D01*
X54796Y-648156D01*
X53230Y-649206D01*
X52525Y-649941D01*
X52055Y-650991D01*
X51898Y-651936D01*
X55188D01*
G01X58041D02*
Y-645636D01*
X61645Y-651936D01*
Y-645636D01*
G01X64420Y-651936D02*
Y-645636D01*
X65986D01*
X66613Y-645951D01*
X67083Y-646371D01*
X67475Y-647001D01*
X67788Y-647736D01*
X67866Y-648786D01*
X67788Y-649836D01*
X67475Y-650571D01*
X67083Y-651201D01*
X66613Y-651621D01*
X65986Y-651936D01*
X64420D01*
G01X77176D02*
Y-645636D01*
X79135D01*
X79761Y-645951D01*
X80153Y-646371D01*
X80310Y-647211D01*
X80153Y-648051D01*
X79683Y-648576D01*
X79135Y-648891D01*
X77176D01*
G01X79135D02*
X80310Y-651936D01*
G01X83320D02*
Y-645636D01*
X84886D01*
X85513Y-645951D01*
X85983Y-646371D01*
X86375Y-647001D01*
X86688Y-647736D01*
X86766Y-648786D01*
X86688Y-649836D01*
X86375Y-650571D01*
X85983Y-651201D01*
X85513Y-651621D01*
X84886Y-651936D01*
X83320D01*
G01X91343Y-652146D02*
X91186Y-652041D01*
Y-651831D01*
X91343Y-651726D01*
X91500Y-651831D01*
Y-652041D01*
X91343Y-652146D01*
G01X-18657Y-639236D02*
X-21177Y-638819D01*
X-23382Y-637153D01*
X-25272Y-634653D01*
X-26532Y-631736D01*
X-27162Y-628403D01*
Y-625069D01*
X-26532Y-621736D01*
X-25272Y-618819D01*
X-23382Y-616320D01*
X-21177Y-614653D01*
X-18657Y-614236D01*
X-16137Y-614653D01*
X-13932Y-616320D01*
X-12042Y-618819D01*
X-10782Y-621736D01*
X-10152Y-625069D01*
Y-628403D01*
X-10782Y-631736D01*
X-12042Y-634653D01*
X-13932Y-637153D01*
X-16137Y-638819D01*
X-18657Y-639236D01*
G01X-16137Y-632569D02*
X-12357Y-639236D01*
G01X1188Y-622570D02*
Y-634236D01*
X2448Y-637153D01*
X4338Y-638819D01*
X6543Y-639236D01*
X8748Y-638819D01*
X10638Y-637153D01*
X11898Y-634236D01*
G01Y-639236D02*
Y-622570D01*
G01X37413Y-639236D02*
Y-622570D01*
G01Y-625486D02*
X36153Y-623820D01*
X34263Y-622986D01*
X32058Y-622570D01*
X29853Y-623403D01*
X27963Y-625069D01*
X26703Y-627570D01*
X26073Y-630903D01*
X26703Y-634236D01*
X27963Y-636737D01*
X29853Y-638403D01*
X32058Y-639236D01*
X34263Y-638819D01*
X36153Y-637570D01*
X37413Y-635903D01*
G01X51588Y-639236D02*
Y-622570D01*
G01Y-626736D02*
X52848Y-624653D01*
X54738Y-622986D01*
X57258Y-622570D01*
X59463Y-622986D01*
X61353Y-624653D01*
X62298Y-627570D01*
Y-639236D01*
G01X82143Y-614236D02*
Y-639236D01*
G01X77733Y-622570D02*
X86553D01*
G01X113013Y-639236D02*
Y-622570D01*
G01Y-625486D02*
X111753Y-623820D01*
X109863Y-622986D01*
X107658Y-622570D01*
X105453Y-623403D01*
X103563Y-625069D01*
X102303Y-627570D01*
X101673Y-630903D01*
X102303Y-634236D01*
X103563Y-636737D01*
X105453Y-638403D01*
X107658Y-639236D01*
X109863Y-638819D01*
X111753Y-637570D01*
X113013Y-635903D01*
G01X-20610Y3150D02*
X-21237Y2940D01*
X-21707Y2415D01*
X-22020Y1785D01*
X-22255Y945D01*
X-22333Y0D01*
X-22255Y-945D01*
X-22020Y-1785D01*
X-21707Y-2415D01*
X-21237Y-2940D01*
X-20610Y-3150D01*
X-19983Y-2940D01*
X-19513Y-2415D01*
X-19200Y-1785D01*
X-18965Y-945D01*
X-18887Y0D01*
X-18965Y945D01*
X-19200Y1785D01*
X-19513Y2415D01*
X-19983Y2940D01*
X-20610Y3150D01*
G01X-3150Y-42530D02*
X-2940Y-43157D01*
X-2415Y-43627D01*
X-1785Y-43940D01*
X-945Y-44175D01*
X0Y-44253D01*
X945Y-44175D01*
X1785Y-43940D01*
X2415Y-43627D01*
X2940Y-43157D01*
X3150Y-42530D01*
X2940Y-41903D01*
X2415Y-41433D01*
X1785Y-41120D01*
X945Y-40885D01*
X0Y-40807D01*
X-945Y-40885D01*
X-1785Y-41120D01*
X-2415Y-41433D01*
X-2940Y-41903D01*
X-3150Y-42530D01*
G01X17880Y-162245D02*
X16631Y-161315D01*
X16005Y-160230D01*
X15797Y-158990D01*
X16214Y-157440D01*
X17255Y-156355D01*
X18505Y-156045D01*
X19756Y-156200D01*
X20797Y-156820D01*
X22880Y-159920D01*
X24339Y-161315D01*
X26422Y-162245D01*
X28297Y-162555D01*
Y-156045D01*
G01X17880Y-149845D02*
X16631Y-148915D01*
X16005Y-147830D01*
X15797Y-146590D01*
X16214Y-145040D01*
X17255Y-143955D01*
X18505Y-143645D01*
X19756Y-143800D01*
X20797Y-144420D01*
X22880Y-147520D01*
X24339Y-148915D01*
X26422Y-149845D01*
X28297Y-150155D01*
Y-143645D01*
G01X15797Y-134500D02*
X16214Y-135740D01*
X17255Y-136670D01*
X18505Y-137290D01*
X20172Y-137755D01*
X22047Y-137910D01*
X23922Y-137755D01*
X25589Y-137290D01*
X26839Y-136670D01*
X27880Y-135740D01*
X28297Y-134500D01*
X27880Y-133260D01*
X26839Y-132330D01*
X25589Y-131710D01*
X23922Y-131245D01*
X22047Y-131090D01*
X20172Y-131245D01*
X18505Y-131710D01*
X17255Y-132330D01*
X16214Y-133260D01*
X15797Y-134500D01*
G01X28714Y-122100D02*
X28505Y-122410D01*
X28089D01*
X27880Y-122100D01*
X28089Y-121790D01*
X28505D01*
X28714Y-122100D01*
G01X28297Y-107840D02*
X15797D01*
X24755Y-113575D01*
Y-105825D01*
G01X28297Y-97610D02*
X25589Y-97300D01*
X23297Y-96835D01*
X21214Y-96215D01*
X18922Y-95440D01*
X15797Y-94200D01*
Y-100400D01*
G01X26422Y-66110D02*
X27464Y-65180D01*
X28089Y-64095D01*
X28297Y-62700D01*
X27880Y-61305D01*
X27047Y-60220D01*
X25589Y-59445D01*
X23922Y-59290D01*
X22255Y-59600D01*
X21214Y-60375D01*
X20380Y-61460D01*
X20172Y-62545D01*
X20380Y-63630D01*
X21214Y-65025D01*
X15797Y-64560D01*
Y-60375D01*
G01X28714Y-50300D02*
X28505Y-50610D01*
X28089D01*
X27880Y-50300D01*
X28089Y-49990D01*
X28505D01*
X28714Y-50300D01*
G01X23089Y-40845D02*
X21630Y-39760D01*
X20797Y-38830D01*
X20380Y-37590D01*
X20797Y-36505D01*
X21630Y-35730D01*
X22880Y-35110D01*
X24339Y-34955D01*
X25589Y-35110D01*
X26839Y-35730D01*
X27880Y-36660D01*
X28297Y-37745D01*
X27880Y-38985D01*
X26631Y-40070D01*
X24755Y-40690D01*
X22672Y-40845D01*
X19964Y-40535D01*
X18505Y-40070D01*
X17047Y-39295D01*
X16005Y-38210D01*
X15797Y-37125D01*
X16214Y-36040D01*
X17255Y-35265D01*
G01X37833Y-162245D02*
X36584Y-161315D01*
X35958Y-160230D01*
X35750Y-158990D01*
X36167Y-157440D01*
X37208Y-156355D01*
X38458Y-156045D01*
X39709Y-156200D01*
X40750Y-156820D01*
X42833Y-159920D01*
X44292Y-161315D01*
X46375Y-162245D01*
X48250Y-162555D01*
Y-156045D01*
G01Y-145040D02*
X35750D01*
X44708Y-150775D01*
Y-143025D01*
G01X35750Y-134500D02*
X36167Y-135740D01*
X37208Y-136670D01*
X38458Y-137290D01*
X40125Y-137755D01*
X42000Y-137910D01*
X43875Y-137755D01*
X45542Y-137290D01*
X46792Y-136670D01*
X47833Y-135740D01*
X48250Y-134500D01*
X47833Y-133260D01*
X46792Y-132330D01*
X45542Y-131710D01*
X43875Y-131245D01*
X42000Y-131090D01*
X40125Y-131245D01*
X38458Y-131710D01*
X37208Y-132330D01*
X36167Y-133260D01*
X35750Y-134500D01*
G01X48667Y-122100D02*
X48458Y-122410D01*
X48042D01*
X47833Y-122100D01*
X48042Y-121790D01*
X48458D01*
X48667Y-122100D01*
G01X48250Y-109700D02*
X35750D01*
X38250Y-111560D01*
G01X48250D02*
Y-107840D01*
G01X43042Y-100245D02*
X41583Y-99160D01*
X40750Y-98230D01*
X40333Y-96990D01*
X40750Y-95905D01*
X41583Y-95130D01*
X42833Y-94510D01*
X44292Y-94355D01*
X45542Y-94510D01*
X46792Y-95130D01*
X47833Y-96060D01*
X48250Y-97145D01*
X47833Y-98385D01*
X46584Y-99470D01*
X44708Y-100090D01*
X42625Y-100245D01*
X39917Y-99935D01*
X38458Y-99470D01*
X37000Y-98695D01*
X35958Y-97610D01*
X35750Y-96525D01*
X36167Y-95440D01*
X37208Y-94665D01*
G01X43042Y-65645D02*
X41583Y-64560D01*
X40750Y-63630D01*
X40333Y-62390D01*
X40750Y-61305D01*
X41583Y-60530D01*
X42833Y-59910D01*
X44292Y-59755D01*
X45542Y-59910D01*
X46792Y-60530D01*
X47833Y-61460D01*
X48250Y-62545D01*
X47833Y-63785D01*
X46584Y-64870D01*
X44708Y-65490D01*
X42625Y-65645D01*
X39917Y-65335D01*
X38458Y-64870D01*
X37000Y-64095D01*
X35958Y-63010D01*
X35750Y-61925D01*
X36167Y-60840D01*
X37208Y-60065D01*
G01X48667Y-50300D02*
X48458Y-50610D01*
X48042D01*
X47833Y-50300D01*
X48042Y-49990D01*
X48458D01*
X48667Y-50300D01*
G01X48250Y-37900D02*
X35750D01*
X38250Y-39760D01*
G01X48250D02*
Y-36040D01*
G01X60851Y503390D02*
X61893Y504320D01*
X62518Y505405D01*
X62726Y506800D01*
X62309Y508195D01*
X61476Y509280D01*
X60018Y510055D01*
X58351Y510210D01*
X56684Y509900D01*
X55643Y509125D01*
X54809Y508040D01*
X54601Y506955D01*
X54809Y505870D01*
X55643Y504475D01*
X50226Y504940D01*
Y509125D01*
G01X57518Y516255D02*
X56059Y517340D01*
X55226Y518270D01*
X54809Y519510D01*
X55226Y520595D01*
X56059Y521370D01*
X57309Y521990D01*
X58768Y522145D01*
X60018Y521990D01*
X61268Y521370D01*
X62309Y520440D01*
X62726Y519355D01*
X62309Y518115D01*
X61060Y517030D01*
X59184Y516410D01*
X57101Y516255D01*
X54393Y516565D01*
X52934Y517030D01*
X51476Y517805D01*
X50434Y518890D01*
X50226Y519975D01*
X50643Y521060D01*
X51684Y521835D01*
G01X62726Y533460D02*
X50226D01*
X59184Y527725D01*
Y535475D01*
G01X63143Y544000D02*
X62934Y543690D01*
X62518D01*
X62309Y544000D01*
X62518Y544310D01*
X62934D01*
X63143Y544000D01*
G01X62726Y556090D02*
X60018Y556400D01*
X57726Y556865D01*
X55643Y557485D01*
X53351Y558260D01*
X50226Y559500D01*
Y553300D01*
G01X57518Y565855D02*
X56059Y566940D01*
X55226Y567870D01*
X54809Y569110D01*
X55226Y570195D01*
X56059Y570970D01*
X57309Y571590D01*
X58768Y571745D01*
X60018Y571590D01*
X61268Y570970D01*
X62309Y570040D01*
X62726Y568955D01*
X62309Y567715D01*
X61060Y566630D01*
X59184Y566010D01*
X57101Y565855D01*
X54393Y566165D01*
X52934Y566630D01*
X51476Y567405D01*
X50434Y568490D01*
X50226Y569575D01*
X50643Y570660D01*
X51684Y571435D01*
G01X62726Y603400D02*
X50226D01*
X52726Y601540D01*
G01X62726D02*
Y605260D01*
G01Y617660D02*
X50226D01*
X59184Y611925D01*
Y619675D01*
G01X63143Y628200D02*
X62934Y627890D01*
X62518D01*
X62309Y628200D01*
X62518Y628510D01*
X62934D01*
X63143Y628200D01*
G01X60226Y637190D02*
X61685Y638120D01*
X62518Y639360D01*
X62726Y640755D01*
X62518Y641995D01*
X61476Y643235D01*
X60226Y644010D01*
X58976Y644165D01*
X57518Y643855D01*
X56476Y642770D01*
X56059Y641685D01*
Y640290D01*
G01Y641685D02*
X55434Y642615D01*
X54393Y643390D01*
X53143Y643700D01*
X51893Y643390D01*
X50851Y642615D01*
X50226Y641220D01*
X50434Y639825D01*
X51268Y638430D01*
G01X62726Y654860D02*
X50226D01*
X59184Y649125D01*
Y656875D01*
G01X120550Y508800D02*
X108050D01*
X110550Y506940D01*
G01X120550D02*
Y510660D01*
G01X110133Y518255D02*
X108884Y519185D01*
X108258Y520270D01*
X108050Y521510D01*
X108467Y523060D01*
X109508Y524145D01*
X110758Y524455D01*
X112009Y524300D01*
X113050Y523680D01*
X115133Y520580D01*
X116592Y519185D01*
X118675Y518255D01*
X120550Y517945D01*
Y524455D01*
G01X108050Y533600D02*
X108467Y532360D01*
X109508Y531430D01*
X110758Y530810D01*
X112425Y530345D01*
X114300Y530190D01*
X116175Y530345D01*
X117842Y530810D01*
X119092Y531430D01*
X120133Y532360D01*
X120550Y533600D01*
X120133Y534840D01*
X119092Y535770D01*
X117842Y536390D01*
X116175Y536855D01*
X114300Y537010D01*
X112425Y536855D01*
X110758Y536390D01*
X109508Y535770D01*
X108467Y534840D01*
X108050Y533600D01*
G01X110133Y543055D02*
X108884Y543985D01*
X108258Y545070D01*
X108050Y546310D01*
X108467Y547860D01*
X109508Y548945D01*
X110758Y549255D01*
X112009Y549100D01*
X113050Y548480D01*
X115133Y545380D01*
X116592Y543985D01*
X118675Y543055D01*
X120550Y542745D01*
Y549255D01*
G01X120967Y558400D02*
X120758Y558090D01*
X120342D01*
X120133Y558400D01*
X120342Y558710D01*
X120758D01*
X120967Y558400D01*
G01X118675Y567390D02*
X119717Y568320D01*
X120342Y569405D01*
X120550Y570800D01*
X120133Y572195D01*
X119300Y573280D01*
X117842Y574055D01*
X116175Y574210D01*
X114508Y573900D01*
X113467Y573125D01*
X112633Y572040D01*
X112425Y570955D01*
X112633Y569870D01*
X113467Y568475D01*
X108050Y568940D01*
Y573125D01*
G01X115342Y580255D02*
X113883Y581340D01*
X113050Y582270D01*
X112633Y583510D01*
X113050Y584595D01*
X113883Y585370D01*
X115133Y585990D01*
X116592Y586145D01*
X117842Y585990D01*
X119092Y585370D01*
X120133Y584440D01*
X120550Y583355D01*
X120133Y582115D01*
X118884Y581030D01*
X117008Y580410D01*
X114925Y580255D01*
X112217Y580565D01*
X110758Y581030D01*
X109300Y581805D01*
X108258Y582890D01*
X108050Y583975D01*
X108467Y585060D01*
X109508Y585835D01*
G01X118050Y614390D02*
X119509Y615320D01*
X120342Y616560D01*
X120550Y617955D01*
X120342Y619195D01*
X119300Y620435D01*
X118050Y621210D01*
X116800Y621365D01*
X115342Y621055D01*
X114300Y619970D01*
X113883Y618885D01*
Y617490D01*
G01Y618885D02*
X113258Y619815D01*
X112217Y620590D01*
X110967Y620900D01*
X109717Y620590D01*
X108675Y619815D01*
X108050Y618420D01*
X108258Y617025D01*
X109092Y615630D01*
G01X108050Y630200D02*
X108467Y628960D01*
X109508Y628030D01*
X110758Y627410D01*
X112425Y626945D01*
X114300Y626790D01*
X116175Y626945D01*
X117842Y627410D01*
X119092Y628030D01*
X120133Y628960D01*
X120550Y630200D01*
X120133Y631440D01*
X119092Y632370D01*
X117842Y632990D01*
X116175Y633455D01*
X114300Y633610D01*
X112425Y633455D01*
X110758Y632990D01*
X109508Y632370D01*
X108467Y631440D01*
X108050Y630200D01*
G01X120967Y642600D02*
X120758Y642290D01*
X120342D01*
X120133Y642600D01*
X120342Y642910D01*
X120758D01*
X120967Y642600D01*
G01X118675Y651590D02*
X119717Y652520D01*
X120342Y653605D01*
X120550Y655000D01*
X120133Y656395D01*
X119300Y657480D01*
X117842Y658255D01*
X116175Y658410D01*
X114508Y658100D01*
X113467Y657325D01*
X112633Y656240D01*
X112425Y655155D01*
X112633Y654070D01*
X113467Y652675D01*
X108050Y653140D01*
Y657325D01*
G01X118675Y663990D02*
X119717Y664920D01*
X120342Y666005D01*
X120550Y667400D01*
X120133Y668795D01*
X119300Y669880D01*
X117842Y670655D01*
X116175Y670810D01*
X114508Y670500D01*
X113467Y669725D01*
X112633Y668640D01*
X112425Y667555D01*
X112633Y666470D01*
X113467Y665075D01*
X108050Y665540D01*
Y669725D01*
G01X136172Y509900D02*
X123672D01*
X126172Y508040D01*
G01X136172D02*
Y511760D01*
G01X125755Y519355D02*
X124506Y520285D01*
X123880Y521370D01*
X123672Y522610D01*
X124089Y524160D01*
X125130Y525245D01*
X126380Y525555D01*
X127631Y525400D01*
X128672Y524780D01*
X130755Y521680D01*
X132214Y520285D01*
X134297Y519355D01*
X136172Y519045D01*
Y525555D01*
G01X134714Y532065D02*
X135755Y533150D01*
X136172Y534390D01*
X135755Y535630D01*
X134506Y536715D01*
X132630Y537490D01*
X130755Y537800D01*
X128464D01*
X126589Y537490D01*
X124922Y536715D01*
X124089Y535785D01*
X123672Y534700D01*
X124089Y533460D01*
X124922Y532530D01*
X126172Y531910D01*
X127839Y531600D01*
X129297Y531910D01*
X130755Y532685D01*
X131589Y533615D01*
X131797Y534700D01*
X131381Y535940D01*
X130339Y536870D01*
X128464Y537800D01*
G01X134714Y544465D02*
X135755Y545550D01*
X136172Y546790D01*
X135755Y548030D01*
X134506Y549115D01*
X132630Y549890D01*
X130755Y550200D01*
X128464D01*
X126589Y549890D01*
X124922Y549115D01*
X124089Y548185D01*
X123672Y547100D01*
X124089Y545860D01*
X124922Y544930D01*
X126172Y544310D01*
X127839Y544000D01*
X129297Y544310D01*
X130755Y545085D01*
X131589Y546015D01*
X131797Y547100D01*
X131381Y548340D01*
X130339Y549270D01*
X128464Y550200D01*
G01X136589Y559500D02*
X136380Y559190D01*
X135964D01*
X135755Y559500D01*
X135964Y559810D01*
X136380D01*
X136589Y559500D01*
G01X125755Y568955D02*
X124506Y569885D01*
X123880Y570970D01*
X123672Y572210D01*
X124089Y573760D01*
X125130Y574845D01*
X126380Y575155D01*
X127631Y575000D01*
X128672Y574380D01*
X130755Y571280D01*
X132214Y569885D01*
X134297Y568955D01*
X136172Y568645D01*
Y575155D01*
G01X125755Y581355D02*
X124506Y582285D01*
X123880Y583370D01*
X123672Y584610D01*
X124089Y586160D01*
X125130Y587245D01*
X126380Y587555D01*
X127631Y587400D01*
X128672Y586780D01*
X130755Y583680D01*
X132214Y582285D01*
X134297Y581355D01*
X136172Y581045D01*
Y587555D01*
G01X133672Y615490D02*
X135131Y616420D01*
X135964Y617660D01*
X136172Y619055D01*
X135964Y620295D01*
X134922Y621535D01*
X133672Y622310D01*
X132422Y622465D01*
X130964Y622155D01*
X129922Y621070D01*
X129505Y619985D01*
Y618590D01*
G01Y619985D02*
X128880Y620915D01*
X127839Y621690D01*
X126589Y622000D01*
X125339Y621690D01*
X124297Y620915D01*
X123672Y619520D01*
X123880Y618125D01*
X124714Y616730D01*
G01X133672Y627890D02*
X135131Y628820D01*
X135964Y630060D01*
X136172Y631455D01*
X135964Y632695D01*
X134922Y633935D01*
X133672Y634710D01*
X132422Y634865D01*
X130964Y634555D01*
X129922Y633470D01*
X129505Y632385D01*
Y630990D01*
G01Y632385D02*
X128880Y633315D01*
X127839Y634090D01*
X126589Y634400D01*
X125339Y634090D01*
X124297Y633315D01*
X123672Y631920D01*
X123880Y630525D01*
X124714Y629130D01*
G01X135790Y760050D02*
X136720Y758591D01*
X137960Y757758D01*
X139355Y757550D01*
X140595Y757758D01*
X141835Y758800D01*
X142610Y760050D01*
X142765Y761300D01*
X142455Y762758D01*
X141370Y763800D01*
X140285Y764217D01*
X138890D01*
G01X140285D02*
X141215Y764842D01*
X141990Y765883D01*
X142300Y767133D01*
X141990Y768383D01*
X141215Y769425D01*
X139820Y770050D01*
X138425Y769842D01*
X137030Y769008D01*
G01X148190Y759425D02*
X149120Y758383D01*
X150205Y757758D01*
X151600Y757550D01*
X152995Y757967D01*
X154080Y758800D01*
X154855Y760258D01*
X155010Y761925D01*
X154700Y763592D01*
X153925Y764633D01*
X152840Y765467D01*
X151755Y765675D01*
X150670Y765467D01*
X149275Y764633D01*
X149740Y770050D01*
X153925D01*
G01X165860Y757550D02*
Y770050D01*
X160125Y761092D01*
X167875D01*
G01X172990Y760050D02*
X173920Y758591D01*
X175160Y757758D01*
X176555Y757550D01*
X177795Y757758D01*
X179035Y758800D01*
X179810Y760050D01*
X179965Y761300D01*
X179655Y762758D01*
X178570Y763800D01*
X177485Y764217D01*
X176090D01*
G01X177485D02*
X178415Y764842D01*
X179190Y765883D01*
X179500Y767133D01*
X179190Y768383D01*
X178415Y769425D01*
X177020Y770050D01*
X175625Y769842D01*
X174230Y769008D01*
G01X188800Y757133D02*
X188490Y757342D01*
Y757758D01*
X188800Y757967D01*
X189110Y757758D01*
Y757342D01*
X188800Y757133D01*
G01X197790Y760050D02*
X198720Y758591D01*
X199960Y757758D01*
X201355Y757550D01*
X202595Y757758D01*
X203835Y758800D01*
X204610Y760050D01*
X204765Y761300D01*
X204455Y762758D01*
X203370Y763800D01*
X202285Y764217D01*
X200890D01*
G01X202285D02*
X203215Y764842D01*
X203990Y765883D01*
X204300Y767133D01*
X203990Y768383D01*
X203215Y769425D01*
X201820Y770050D01*
X200425Y769842D01*
X199030Y769008D01*
G01X213600Y757550D02*
Y770050D01*
X211740Y767550D01*
G01Y757550D02*
X215460D01*
G01X152693Y-618936D02*
Y-626936D01*
X156693D01*
G01X164493D02*
Y-621603D01*
G01Y-622536D02*
X164093Y-622003D01*
X163493Y-621736D01*
X162793Y-621603D01*
X162093Y-621869D01*
X161493Y-622403D01*
X161093Y-623203D01*
X160893Y-624269D01*
X161093Y-625336D01*
X161493Y-626136D01*
X162093Y-626669D01*
X162793Y-626936D01*
X163493Y-626803D01*
X164093Y-626403D01*
X164493Y-625870D01*
G01X168593Y-629336D02*
X169193Y-629603D01*
X169993Y-629336D01*
X170493Y-628803D01*
X170893Y-628136D01*
X171493Y-626003D01*
X172793Y-621603D01*
G01X169593D02*
X171493Y-626003D01*
G01X177193Y-623336D02*
X180393D01*
X180093Y-622403D01*
X179593Y-621869D01*
X178893Y-621603D01*
X178193Y-621736D01*
X177593Y-622136D01*
X177193Y-623069D01*
X176993Y-623870D01*
Y-624669D01*
X177193Y-625469D01*
X177693Y-626269D01*
X178293Y-626803D01*
X178993Y-626936D01*
X179693Y-626669D01*
X180393Y-625870D01*
G01X185293Y-626936D02*
Y-621603D01*
G01Y-622669D02*
X185793Y-622136D01*
X186293Y-621736D01*
X186993Y-621603D01*
X187493Y-621736D01*
X188093Y-622136D01*
G01X151450Y509800D02*
X138950D01*
X141450Y507940D01*
G01X151450D02*
Y511660D01*
G01X148950Y518790D02*
X150409Y519720D01*
X151242Y520960D01*
X151450Y522355D01*
X151242Y523595D01*
X150200Y524835D01*
X148950Y525610D01*
X147700Y525765D01*
X146242Y525455D01*
X145200Y524370D01*
X144783Y523285D01*
Y521890D01*
G01Y523285D02*
X144158Y524215D01*
X143117Y524990D01*
X141867Y525300D01*
X140617Y524990D01*
X139575Y524215D01*
X138950Y522820D01*
X139158Y521425D01*
X139992Y520030D01*
G01X149992Y531965D02*
X151033Y533050D01*
X151450Y534290D01*
X151033Y535530D01*
X149784Y536615D01*
X147908Y537390D01*
X146033Y537700D01*
X143742D01*
X141867Y537390D01*
X140200Y536615D01*
X139367Y535685D01*
X138950Y534600D01*
X139367Y533360D01*
X140200Y532430D01*
X141450Y531810D01*
X143117Y531500D01*
X144575Y531810D01*
X146033Y532585D01*
X146867Y533515D01*
X147075Y534600D01*
X146659Y535840D01*
X145617Y536770D01*
X143742Y537700D01*
G01X149575Y543590D02*
X150617Y544520D01*
X151242Y545605D01*
X151450Y547000D01*
X151033Y548395D01*
X150200Y549480D01*
X148742Y550255D01*
X147075Y550410D01*
X145408Y550100D01*
X144367Y549325D01*
X143533Y548240D01*
X143325Y547155D01*
X143533Y546070D01*
X144367Y544675D01*
X138950Y545140D01*
Y549325D01*
G01X151867Y559400D02*
X151658Y559090D01*
X151242D01*
X151033Y559400D01*
X151242Y559710D01*
X151658D01*
X151867Y559400D01*
G01X151450Y571800D02*
X151242Y572885D01*
X150617Y574125D01*
X149575Y574900D01*
X148117Y575210D01*
X146659Y574900D01*
X145408Y573970D01*
X144783Y572575D01*
Y571025D01*
X144367Y570095D01*
X143325Y569320D01*
X141867Y569010D01*
X140408Y569475D01*
X139367Y570560D01*
X138950Y571800D01*
X139367Y573040D01*
X140408Y574125D01*
X141867Y574590D01*
X143325Y574280D01*
X144367Y573505D01*
X144783Y572575D01*
Y571025D01*
X145408Y569630D01*
X146659Y568700D01*
X148117Y568390D01*
X149575Y568700D01*
X150617Y569475D01*
X151242Y570715D01*
X151450Y571800D01*
G01Y583890D02*
X148742Y584200D01*
X146450Y584665D01*
X144367Y585285D01*
X142075Y586060D01*
X138950Y587300D01*
Y581100D01*
G01X148950Y615390D02*
X150409Y616320D01*
X151242Y617560D01*
X151450Y618955D01*
X151242Y620195D01*
X150200Y621435D01*
X148950Y622210D01*
X147700Y622365D01*
X146242Y622055D01*
X145200Y620970D01*
X144783Y619885D01*
Y618490D01*
G01Y619885D02*
X144158Y620815D01*
X143117Y621590D01*
X141867Y621900D01*
X140617Y621590D01*
X139575Y620815D01*
X138950Y619420D01*
X139158Y618025D01*
X139992Y616630D01*
G01X149575Y627790D02*
X150617Y628720D01*
X151242Y629805D01*
X151450Y631200D01*
X151033Y632595D01*
X150200Y633680D01*
X148742Y634455D01*
X147075Y634610D01*
X145408Y634300D01*
X144367Y633525D01*
X143533Y632440D01*
X143325Y631355D01*
X143533Y630270D01*
X144367Y628875D01*
X138950Y629340D01*
Y633525D01*
G01X151867Y643600D02*
X151658Y643290D01*
X151242D01*
X151033Y643600D01*
X151242Y643910D01*
X151658D01*
X151867Y643600D01*
G01X151450Y657860D02*
X138950D01*
X147908Y652125D01*
Y659875D01*
G01X146242Y665455D02*
X144783Y666540D01*
X143950Y667470D01*
X143533Y668710D01*
X143950Y669795D01*
X144783Y670570D01*
X146033Y671190D01*
X147492Y671345D01*
X148742Y671190D01*
X149992Y670570D01*
X151033Y669640D01*
X151450Y668555D01*
X151033Y667315D01*
X149784Y666230D01*
X147908Y665610D01*
X145825Y665455D01*
X143117Y665765D01*
X141658Y666230D01*
X140200Y667005D01*
X139158Y668090D01*
X138950Y669175D01*
X139367Y670260D01*
X140408Y671035D01*
G01X168750Y509600D02*
X156250D01*
X158750Y507740D01*
G01X168750D02*
Y511460D01*
G01Y521690D02*
X166042Y522000D01*
X163750Y522465D01*
X161667Y523085D01*
X159375Y523860D01*
X156250Y525100D01*
Y518900D01*
G01Y534400D02*
X156667Y533160D01*
X157708Y532230D01*
X158958Y531610D01*
X160625Y531145D01*
X162500Y530990D01*
X164375Y531145D01*
X166042Y531610D01*
X167292Y532230D01*
X168333Y533160D01*
X168750Y534400D01*
X168333Y535640D01*
X167292Y536570D01*
X166042Y537190D01*
X164375Y537655D01*
X162500Y537810D01*
X160625Y537655D01*
X158958Y537190D01*
X157708Y536570D01*
X156667Y535640D01*
X156250Y534400D01*
G01X158333Y543855D02*
X157084Y544785D01*
X156458Y545870D01*
X156250Y547110D01*
X156667Y548660D01*
X157708Y549745D01*
X158958Y550055D01*
X160209Y549900D01*
X161250Y549280D01*
X163333Y546180D01*
X164792Y544785D01*
X166875Y543855D01*
X168750Y543545D01*
Y550055D01*
G01X169167Y559200D02*
X168958Y558890D01*
X168542D01*
X168333Y559200D01*
X168542Y559510D01*
X168958D01*
X169167Y559200D01*
G01X167292Y568965D02*
X168333Y570050D01*
X168750Y571290D01*
X168333Y572530D01*
X167084Y573615D01*
X165208Y574390D01*
X163333Y574700D01*
X161042D01*
X159167Y574390D01*
X157500Y573615D01*
X156667Y572685D01*
X156250Y571600D01*
X156667Y570360D01*
X157500Y569430D01*
X158750Y568810D01*
X160417Y568500D01*
X161875Y568810D01*
X163333Y569585D01*
X164167Y570515D01*
X164375Y571600D01*
X163959Y572840D01*
X162917Y573770D01*
X161042Y574700D01*
G01X166875Y580590D02*
X167917Y581520D01*
X168542Y582605D01*
X168750Y584000D01*
X168333Y585395D01*
X167500Y586480D01*
X166042Y587255D01*
X164375Y587410D01*
X162708Y587100D01*
X161667Y586325D01*
X160833Y585240D01*
X160625Y584155D01*
X160833Y583070D01*
X161667Y581675D01*
X156250Y582140D01*
Y586325D01*
G01X168750Y620460D02*
X156250D01*
X165208Y614725D01*
Y622475D01*
G01X166250Y627590D02*
X167709Y628520D01*
X168542Y629760D01*
X168750Y631155D01*
X168542Y632395D01*
X167500Y633635D01*
X166250Y634410D01*
X165000Y634565D01*
X163542Y634255D01*
X162500Y633170D01*
X162083Y632085D01*
Y630690D01*
G01Y632085D02*
X161458Y633015D01*
X160417Y633790D01*
X159167Y634100D01*
X157917Y633790D01*
X156875Y633015D01*
X156250Y631620D01*
X156458Y630225D01*
X157292Y628830D01*
G01X169167Y643400D02*
X168958Y643090D01*
X168542D01*
X168333Y643400D01*
X168542Y643710D01*
X168958D01*
X169167Y643400D01*
G01X158333Y652855D02*
X157084Y653785D01*
X156458Y654870D01*
X156250Y656110D01*
X156667Y657660D01*
X157708Y658745D01*
X158958Y659055D01*
X160209Y658900D01*
X161250Y658280D01*
X163333Y655180D01*
X164792Y653785D01*
X166875Y652855D01*
X168750Y652545D01*
Y659055D01*
G01X166875Y664790D02*
X167917Y665720D01*
X168542Y666805D01*
X168750Y668200D01*
X168333Y669595D01*
X167500Y670680D01*
X166042Y671455D01*
X164375Y671610D01*
X162708Y671300D01*
X161667Y670525D01*
X160833Y669440D01*
X160625Y668355D01*
X160833Y667270D01*
X161667Y665875D01*
X156250Y666340D01*
Y670525D01*
G01X167715Y734008D02*
X168800Y732967D01*
X170040Y732550D01*
X171280Y732967D01*
X172365Y734216D01*
X173140Y736092D01*
X173450Y737967D01*
Y740258D01*
X173140Y742133D01*
X172365Y743800D01*
X171435Y744633D01*
X170350Y745050D01*
X169110Y744633D01*
X168180Y743800D01*
X167560Y742550D01*
X167250Y740883D01*
X167560Y739425D01*
X168335Y737967D01*
X169265Y737133D01*
X170350Y736925D01*
X171590Y737341D01*
X172520Y738383D01*
X173450Y740258D01*
G01X182750Y745050D02*
X181510Y744633D01*
X180580Y743592D01*
X179960Y742342D01*
X179495Y740675D01*
X179340Y738800D01*
X179495Y736925D01*
X179960Y735258D01*
X180580Y734008D01*
X181510Y732967D01*
X182750Y732550D01*
X183990Y732967D01*
X184920Y734008D01*
X185540Y735258D01*
X186005Y736925D01*
X186160Y738800D01*
X186005Y740675D01*
X185540Y742342D01*
X184920Y743592D01*
X183990Y744633D01*
X182750Y745050D01*
G01X173993Y-676936D02*
Y-668936D01*
G01X177793D02*
X173993Y-673870D01*
G01X178393Y-676936D02*
X175693Y-671603D01*
G01X185993Y-676936D02*
Y-671603D01*
G01Y-672536D02*
X185593Y-672003D01*
X184993Y-671736D01*
X184293Y-671603D01*
X183593Y-671869D01*
X182993Y-672403D01*
X182593Y-673203D01*
X182393Y-674269D01*
X182593Y-675336D01*
X182993Y-676136D01*
X183593Y-676669D01*
X184293Y-676936D01*
X184993Y-676803D01*
X185593Y-676403D01*
X185993Y-675870D01*
G01X192193Y-671603D02*
Y-676936D01*
G01Y-669469D02*
X191993Y-669336D01*
Y-669069D01*
X192193Y-668936D01*
X192393Y-669069D01*
Y-669336D01*
X192193Y-669469D01*
G01X176793Y-651936D02*
Y-643936D01*
X180593D01*
G01X179193Y-647803D02*
X176793D01*
G01X184193Y-651936D02*
X186693Y-643936D01*
X189193Y-651936D01*
G01X188293Y-649136D02*
X185093D01*
G01X195493Y-647669D02*
X195893Y-647269D01*
X196193Y-646603D01*
X196393Y-645669D01*
X196193Y-644869D01*
X195793Y-644336D01*
X195093Y-643936D01*
X192393D01*
Y-651936D01*
X195693D01*
X196393Y-651403D01*
X196793Y-650603D01*
X196993Y-649669D01*
X196793Y-648736D01*
X196193Y-647936D01*
X195493Y-647669D01*
X192393D01*
G01X184439Y508500D02*
X171939D01*
X174439Y506640D01*
G01X184439D02*
Y510360D01*
G01Y520590D02*
X181731Y520900D01*
X179439Y521365D01*
X177356Y521985D01*
X175064Y522760D01*
X171939Y524000D01*
Y517800D01*
G01X184439Y533300D02*
X184231Y534385D01*
X183606Y535625D01*
X182564Y536400D01*
X181106Y536710D01*
X179648Y536400D01*
X178397Y535470D01*
X177772Y534075D01*
Y532525D01*
X177356Y531595D01*
X176314Y530820D01*
X174856Y530510D01*
X173397Y530975D01*
X172356Y532060D01*
X171939Y533300D01*
X172356Y534540D01*
X173397Y535625D01*
X174856Y536090D01*
X176314Y535780D01*
X177356Y535005D01*
X177772Y534075D01*
Y532525D01*
X178397Y531130D01*
X179648Y530200D01*
X181106Y529890D01*
X182564Y530200D01*
X183606Y530975D01*
X184231Y532215D01*
X184439Y533300D01*
G01Y545700D02*
X171939D01*
X174439Y543840D01*
G01X184439D02*
Y547560D01*
G01X184856Y558100D02*
X184647Y557790D01*
X184231D01*
X184022Y558100D01*
X184231Y558410D01*
X184647D01*
X184856Y558100D01*
G01X184439Y570500D02*
X184231Y571585D01*
X183606Y572825D01*
X182564Y573600D01*
X181106Y573910D01*
X179648Y573600D01*
X178397Y572670D01*
X177772Y571275D01*
Y569725D01*
X177356Y568795D01*
X176314Y568020D01*
X174856Y567710D01*
X173397Y568175D01*
X172356Y569260D01*
X171939Y570500D01*
X172356Y571740D01*
X173397Y572825D01*
X174856Y573290D01*
X176314Y572980D01*
X177356Y572205D01*
X177772Y571275D01*
Y569725D01*
X178397Y568330D01*
X179648Y567400D01*
X181106Y567090D01*
X182564Y567400D01*
X183606Y568175D01*
X184231Y569415D01*
X184439Y570500D01*
G01X182981Y580265D02*
X184022Y581350D01*
X184439Y582590D01*
X184022Y583830D01*
X182773Y584915D01*
X180897Y585690D01*
X179022Y586000D01*
X176731D01*
X174856Y585690D01*
X173189Y584915D01*
X172356Y583985D01*
X171939Y582900D01*
X172356Y581660D01*
X173189Y580730D01*
X174439Y580110D01*
X176106Y579800D01*
X177564Y580110D01*
X179022Y580885D01*
X179856Y581815D01*
X180064Y582900D01*
X179648Y584140D01*
X178606Y585070D01*
X176731Y586000D01*
G01X184439Y619360D02*
X171939D01*
X180897Y613625D01*
Y621375D01*
G01X182564Y626490D02*
X183606Y627420D01*
X184231Y628505D01*
X184439Y629900D01*
X184022Y631295D01*
X183189Y632380D01*
X181731Y633155D01*
X180064Y633310D01*
X178397Y633000D01*
X177356Y632225D01*
X176522Y631140D01*
X176314Y630055D01*
X176522Y628970D01*
X177356Y627575D01*
X171939Y628040D01*
Y632225D01*
G01X184856Y642300D02*
X184647Y641990D01*
X184231D01*
X184022Y642300D01*
X184231Y642610D01*
X184647D01*
X184856Y642300D01*
G01X174022Y651755D02*
X172773Y652685D01*
X172147Y653770D01*
X171939Y655010D01*
X172356Y656560D01*
X173397Y657645D01*
X174647Y657955D01*
X175898Y657800D01*
X176939Y657180D01*
X179022Y654080D01*
X180481Y652685D01*
X182564Y651755D01*
X184439Y651445D01*
Y657955D01*
G01X179231Y664155D02*
X177772Y665240D01*
X176939Y666170D01*
X176522Y667410D01*
X176939Y668495D01*
X177772Y669270D01*
X179022Y669890D01*
X180481Y670045D01*
X181731Y669890D01*
X182981Y669270D01*
X184022Y668340D01*
X184439Y667255D01*
X184022Y666015D01*
X182773Y664930D01*
X180897Y664310D01*
X178814Y664155D01*
X176106Y664465D01*
X174647Y664930D01*
X173189Y665705D01*
X172147Y666790D01*
X171939Y667875D01*
X172356Y668960D01*
X173397Y669735D01*
G01X201150Y507900D02*
X188650D01*
X191150Y506040D01*
G01X201150D02*
Y509760D01*
G01Y520300D02*
X200942Y521385D01*
X200317Y522625D01*
X199275Y523400D01*
X197817Y523710D01*
X196359Y523400D01*
X195108Y522470D01*
X194483Y521075D01*
Y519525D01*
X194067Y518595D01*
X193025Y517820D01*
X191567Y517510D01*
X190108Y517975D01*
X189067Y519060D01*
X188650Y520300D01*
X189067Y521540D01*
X190108Y522625D01*
X191567Y523090D01*
X193025Y522780D01*
X194067Y522005D01*
X194483Y521075D01*
Y519525D01*
X195108Y518130D01*
X196359Y517200D01*
X197817Y516890D01*
X199275Y517200D01*
X200317Y517975D01*
X200942Y519215D01*
X201150Y520300D01*
G01X195942Y529755D02*
X194483Y530840D01*
X193650Y531770D01*
X193233Y533010D01*
X193650Y534095D01*
X194483Y534870D01*
X195733Y535490D01*
X197192Y535645D01*
X198442Y535490D01*
X199692Y534870D01*
X200733Y533940D01*
X201150Y532855D01*
X200733Y531615D01*
X199484Y530530D01*
X197608Y529910D01*
X195525Y529755D01*
X192817Y530065D01*
X191358Y530530D01*
X189900Y531305D01*
X188858Y532390D01*
X188650Y533475D01*
X189067Y534560D01*
X190108Y535335D01*
G01X188650Y545100D02*
X189067Y543860D01*
X190108Y542930D01*
X191358Y542310D01*
X193025Y541845D01*
X194900Y541690D01*
X196775Y541845D01*
X198442Y542310D01*
X199692Y542930D01*
X200733Y543860D01*
X201150Y545100D01*
X200733Y546340D01*
X199692Y547270D01*
X198442Y547890D01*
X196775Y548355D01*
X194900Y548510D01*
X193025Y548355D01*
X191358Y547890D01*
X190108Y547270D01*
X189067Y546340D01*
X188650Y545100D01*
G01X201567Y557500D02*
X201358Y557190D01*
X200942D01*
X200733Y557500D01*
X200942Y557810D01*
X201358D01*
X201567Y557500D01*
G01X201150Y569900D02*
X200942Y570985D01*
X200317Y572225D01*
X199275Y573000D01*
X197817Y573310D01*
X196359Y573000D01*
X195108Y572070D01*
X194483Y570675D01*
Y569125D01*
X194067Y568195D01*
X193025Y567420D01*
X191567Y567110D01*
X190108Y567575D01*
X189067Y568660D01*
X188650Y569900D01*
X189067Y571140D01*
X190108Y572225D01*
X191567Y572690D01*
X193025Y572380D01*
X194067Y571605D01*
X194483Y570675D01*
Y569125D01*
X195108Y567730D01*
X196359Y566800D01*
X197817Y566490D01*
X199275Y566800D01*
X200317Y567575D01*
X200942Y568815D01*
X201150Y569900D01*
G01X198650Y578890D02*
X200109Y579820D01*
X200942Y581060D01*
X201150Y582455D01*
X200942Y583695D01*
X199900Y584935D01*
X198650Y585710D01*
X197400Y585865D01*
X195942Y585555D01*
X194900Y584470D01*
X194483Y583385D01*
Y581990D01*
G01Y583385D02*
X193858Y584315D01*
X192817Y585090D01*
X191567Y585400D01*
X190317Y585090D01*
X189275Y584315D01*
X188650Y582920D01*
X188858Y581525D01*
X189692Y580130D01*
G01X201150Y618760D02*
X188650D01*
X197608Y613025D01*
Y620775D01*
G01X201150Y628990D02*
X198442Y629300D01*
X196150Y629765D01*
X194067Y630385D01*
X191775Y631160D01*
X188650Y632400D01*
Y626200D01*
G01X201567Y641700D02*
X201358Y641390D01*
X200942D01*
X200733Y641700D01*
X200942Y642010D01*
X201358D01*
X201567Y641700D01*
G01X190733Y651155D02*
X189484Y652085D01*
X188858Y653170D01*
X188650Y654410D01*
X189067Y655960D01*
X190108Y657045D01*
X191358Y657355D01*
X192609Y657200D01*
X193650Y656580D01*
X195733Y653480D01*
X197192Y652085D01*
X199275Y651155D01*
X201150Y650845D01*
Y657355D01*
G01Y666190D02*
X198442Y666500D01*
X196150Y666965D01*
X194067Y667585D01*
X191775Y668360D01*
X188650Y669600D01*
Y663400D01*
G01X239033Y511755D02*
X237784Y512685D01*
X237158Y513770D01*
X236950Y515010D01*
X237367Y516560D01*
X238408Y517645D01*
X239658Y517955D01*
X240909Y517800D01*
X241950Y517180D01*
X244033Y514080D01*
X245492Y512685D01*
X247575Y511755D01*
X249450Y511445D01*
Y517955D01*
G01Y528960D02*
X236950D01*
X245908Y523225D01*
Y530975D01*
G01X247992Y536865D02*
X249033Y537950D01*
X249450Y539190D01*
X249033Y540430D01*
X247784Y541515D01*
X245908Y542290D01*
X244033Y542600D01*
X241742D01*
X239867Y542290D01*
X238200Y541515D01*
X237367Y540585D01*
X236950Y539500D01*
X237367Y538260D01*
X238200Y537330D01*
X239450Y536710D01*
X241117Y536400D01*
X242575Y536710D01*
X244033Y537485D01*
X244867Y538415D01*
X245075Y539500D01*
X244659Y540740D01*
X243617Y541670D01*
X241742Y542600D01*
G01X249450Y551900D02*
X249242Y552985D01*
X248617Y554225D01*
X247575Y555000D01*
X246117Y555310D01*
X244659Y555000D01*
X243408Y554070D01*
X242783Y552675D01*
Y551125D01*
X242367Y550195D01*
X241325Y549420D01*
X239867Y549110D01*
X238408Y549575D01*
X237367Y550660D01*
X236950Y551900D01*
X237367Y553140D01*
X238408Y554225D01*
X239867Y554690D01*
X241325Y554380D01*
X242367Y553605D01*
X242783Y552675D01*
Y551125D01*
X243408Y549730D01*
X244659Y548800D01*
X246117Y548490D01*
X247575Y548800D01*
X248617Y549575D01*
X249242Y550815D01*
X249450Y551900D01*
G01X249867Y564300D02*
X249658Y563990D01*
X249242D01*
X249033Y564300D01*
X249242Y564610D01*
X249658D01*
X249867Y564300D01*
G01X244242Y573755D02*
X242783Y574840D01*
X241950Y575770D01*
X241533Y577010D01*
X241950Y578095D01*
X242783Y578870D01*
X244033Y579490D01*
X245492Y579645D01*
X246742Y579490D01*
X247992Y578870D01*
X249033Y577940D01*
X249450Y576855D01*
X249033Y575615D01*
X247784Y574530D01*
X245908Y573910D01*
X243825Y573755D01*
X241117Y574065D01*
X239658Y574530D01*
X238200Y575305D01*
X237158Y576390D01*
X236950Y577475D01*
X237367Y578560D01*
X238408Y579335D01*
G01X239033Y586155D02*
X237784Y587085D01*
X237158Y588170D01*
X236950Y589410D01*
X237367Y590960D01*
X238408Y592045D01*
X239658Y592355D01*
X240909Y592200D01*
X241950Y591580D01*
X244033Y588480D01*
X245492Y587085D01*
X247575Y586155D01*
X249450Y585845D01*
Y592355D01*
G01X244242Y620755D02*
X242783Y621840D01*
X241950Y622770D01*
X241533Y624010D01*
X241950Y625095D01*
X242783Y625870D01*
X244033Y626490D01*
X245492Y626645D01*
X246742Y626490D01*
X247992Y625870D01*
X249033Y624940D01*
X249450Y623855D01*
X249033Y622615D01*
X247784Y621530D01*
X245908Y620910D01*
X243825Y620755D01*
X241117Y621065D01*
X239658Y621530D01*
X238200Y622305D01*
X237158Y623390D01*
X236950Y624475D01*
X237367Y625560D01*
X238408Y626335D01*
G01X246950Y632690D02*
X248409Y633620D01*
X249242Y634860D01*
X249450Y636255D01*
X249242Y637495D01*
X248200Y638735D01*
X246950Y639510D01*
X245700Y639665D01*
X244242Y639355D01*
X243200Y638270D01*
X242783Y637185D01*
Y635790D01*
G01Y637185D02*
X242158Y638115D01*
X241117Y638890D01*
X239867Y639200D01*
X238617Y638890D01*
X237575Y638115D01*
X236950Y636720D01*
X237158Y635325D01*
X237992Y633930D01*
G01X249867Y648500D02*
X249658Y648190D01*
X249242D01*
X249033Y648500D01*
X249242Y648810D01*
X249658D01*
X249867Y648500D01*
G01X249450Y662760D02*
X236950D01*
X245908Y657025D01*
Y664775D01*
G01X244242Y670355D02*
X242783Y671440D01*
X241950Y672370D01*
X241533Y673610D01*
X241950Y674695D01*
X242783Y675470D01*
X244033Y676090D01*
X245492Y676245D01*
X246742Y676090D01*
X247992Y675470D01*
X249033Y674540D01*
X249450Y673455D01*
X249033Y672215D01*
X247784Y671130D01*
X245908Y670510D01*
X243825Y670355D01*
X241117Y670665D01*
X239658Y671130D01*
X238200Y671905D01*
X237158Y672990D01*
X236950Y674075D01*
X237367Y675160D01*
X238408Y675935D01*
G01X254337Y512855D02*
X253088Y513785D01*
X252462Y514870D01*
X252254Y516110D01*
X252671Y517660D01*
X253712Y518745D01*
X254962Y519055D01*
X256213Y518900D01*
X257254Y518280D01*
X259337Y515180D01*
X260796Y513785D01*
X262879Y512855D01*
X264754Y512545D01*
Y519055D01*
G01X262879Y524790D02*
X263921Y525720D01*
X264546Y526805D01*
X264754Y528200D01*
X264337Y529595D01*
X263504Y530680D01*
X262046Y531455D01*
X260379Y531610D01*
X258712Y531300D01*
X257671Y530525D01*
X256837Y529440D01*
X256629Y528355D01*
X256837Y527270D01*
X257671Y525875D01*
X252254Y526340D01*
Y530525D01*
G01X264754Y540600D02*
X264546Y541685D01*
X263921Y542925D01*
X262879Y543700D01*
X261421Y544010D01*
X259963Y543700D01*
X258712Y542770D01*
X258087Y541375D01*
Y539825D01*
X257671Y538895D01*
X256629Y538120D01*
X255171Y537810D01*
X253712Y538275D01*
X252671Y539360D01*
X252254Y540600D01*
X252671Y541840D01*
X253712Y542925D01*
X255171Y543390D01*
X256629Y543080D01*
X257671Y542305D01*
X258087Y541375D01*
Y539825D01*
X258712Y538430D01*
X259963Y537500D01*
X261421Y537190D01*
X262879Y537500D01*
X263921Y538275D01*
X264546Y539515D01*
X264754Y540600D01*
G01X262879Y549590D02*
X263921Y550520D01*
X264546Y551605D01*
X264754Y553000D01*
X264337Y554395D01*
X263504Y555480D01*
X262046Y556255D01*
X260379Y556410D01*
X258712Y556100D01*
X257671Y555325D01*
X256837Y554240D01*
X256629Y553155D01*
X256837Y552070D01*
X257671Y550675D01*
X252254Y551140D01*
Y555325D01*
G01X265171Y565400D02*
X264962Y565090D01*
X264546D01*
X264337Y565400D01*
X264546Y565710D01*
X264962D01*
X265171Y565400D01*
G01X252254Y577800D02*
X252671Y576560D01*
X253712Y575630D01*
X254962Y575010D01*
X256629Y574545D01*
X258504Y574390D01*
X260379Y574545D01*
X262046Y575010D01*
X263296Y575630D01*
X264337Y576560D01*
X264754Y577800D01*
X264337Y579040D01*
X263296Y579970D01*
X262046Y580590D01*
X260379Y581055D01*
X258504Y581210D01*
X256629Y581055D01*
X254962Y580590D01*
X253712Y579970D01*
X252671Y579040D01*
X252254Y577800D01*
G01X264754Y592060D02*
X252254D01*
X261212Y586325D01*
Y594075D01*
G01X259546Y621855D02*
X258087Y622940D01*
X257254Y623870D01*
X256837Y625110D01*
X257254Y626195D01*
X258087Y626970D01*
X259337Y627590D01*
X260796Y627745D01*
X262046Y627590D01*
X263296Y626970D01*
X264337Y626040D01*
X264754Y624955D01*
X264337Y623715D01*
X263088Y622630D01*
X261212Y622010D01*
X259129Y621855D01*
X256421Y622165D01*
X254962Y622630D01*
X253504Y623405D01*
X252462Y624490D01*
X252254Y625575D01*
X252671Y626660D01*
X253712Y627435D01*
G01X262879Y633790D02*
X263921Y634720D01*
X264546Y635805D01*
X264754Y637200D01*
X264337Y638595D01*
X263504Y639680D01*
X262046Y640455D01*
X260379Y640610D01*
X258712Y640300D01*
X257671Y639525D01*
X256837Y638440D01*
X256629Y637355D01*
X256837Y636270D01*
X257671Y634875D01*
X252254Y635340D01*
Y639525D01*
G01X265171Y649600D02*
X264962Y649290D01*
X264546D01*
X264337Y649600D01*
X264546Y649910D01*
X264962D01*
X265171Y649600D01*
G01X259546Y659055D02*
X258087Y660140D01*
X257254Y661070D01*
X256837Y662310D01*
X257254Y663395D01*
X258087Y664170D01*
X259337Y664790D01*
X260796Y664945D01*
X262046Y664790D01*
X263296Y664170D01*
X264337Y663240D01*
X264754Y662155D01*
X264337Y660915D01*
X263088Y659830D01*
X261212Y659210D01*
X259129Y659055D01*
X256421Y659365D01*
X254962Y659830D01*
X253504Y660605D01*
X252462Y661690D01*
X252254Y662775D01*
X252671Y663860D01*
X253712Y664635D01*
G01X259546Y671455D02*
X258087Y672540D01*
X257254Y673470D01*
X256837Y674710D01*
X257254Y675795D01*
X258087Y676570D01*
X259337Y677190D01*
X260796Y677345D01*
X262046Y677190D01*
X263296Y676570D01*
X264337Y675640D01*
X264754Y674555D01*
X264337Y673315D01*
X263088Y672230D01*
X261212Y671610D01*
X259129Y671455D01*
X256421Y671765D01*
X254962Y672230D01*
X253504Y673005D01*
X252462Y674090D01*
X252254Y675175D01*
X252671Y676260D01*
X253712Y677035D01*
G01X268133Y510955D02*
X266884Y511885D01*
X266258Y512970D01*
X266050Y514210D01*
X266467Y515760D01*
X267508Y516845D01*
X268758Y517155D01*
X270009Y517000D01*
X271050Y516380D01*
X273133Y513280D01*
X274592Y511885D01*
X276675Y510955D01*
X278550Y510645D01*
Y517155D01*
G01X273342Y523355D02*
X271883Y524440D01*
X271050Y525370D01*
X270633Y526610D01*
X271050Y527695D01*
X271883Y528470D01*
X273133Y529090D01*
X274592Y529245D01*
X275842Y529090D01*
X277092Y528470D01*
X278133Y527540D01*
X278550Y526455D01*
X278133Y525215D01*
X276884Y524130D01*
X275008Y523510D01*
X272925Y523355D01*
X270217Y523665D01*
X268758Y524130D01*
X267300Y524905D01*
X266258Y525990D01*
X266050Y527075D01*
X266467Y528160D01*
X267508Y528935D01*
G01X278550Y538390D02*
X275842Y538700D01*
X273550Y539165D01*
X271467Y539785D01*
X269175Y540560D01*
X266050Y541800D01*
Y535600D01*
G01X278550Y551100D02*
X266050D01*
X268550Y549240D01*
G01X278550D02*
Y552960D01*
G01X278967Y563500D02*
X278758Y563190D01*
X278342D01*
X278133Y563500D01*
X278342Y563810D01*
X278758D01*
X278967Y563500D01*
G01X273342Y572955D02*
X271883Y574040D01*
X271050Y574970D01*
X270633Y576210D01*
X271050Y577295D01*
X271883Y578070D01*
X273133Y578690D01*
X274592Y578845D01*
X275842Y578690D01*
X277092Y578070D01*
X278133Y577140D01*
X278550Y576055D01*
X278133Y574815D01*
X276884Y573730D01*
X275008Y573110D01*
X272925Y572955D01*
X270217Y573265D01*
X268758Y573730D01*
X267300Y574505D01*
X266258Y575590D01*
X266050Y576675D01*
X266467Y577760D01*
X267508Y578535D01*
G01X276675Y584890D02*
X277717Y585820D01*
X278342Y586905D01*
X278550Y588300D01*
X278133Y589695D01*
X277300Y590780D01*
X275842Y591555D01*
X274175Y591710D01*
X272508Y591400D01*
X271467Y590625D01*
X270633Y589540D01*
X270425Y588455D01*
X270633Y587370D01*
X271467Y585975D01*
X266050Y586440D01*
Y590625D01*
G01X273342Y619955D02*
X271883Y621040D01*
X271050Y621970D01*
X270633Y623210D01*
X271050Y624295D01*
X271883Y625070D01*
X273133Y625690D01*
X274592Y625845D01*
X275842Y625690D01*
X277092Y625070D01*
X278133Y624140D01*
X278550Y623055D01*
X278133Y621815D01*
X276884Y620730D01*
X275008Y620110D01*
X272925Y619955D01*
X270217Y620265D01*
X268758Y620730D01*
X267300Y621505D01*
X266258Y622590D01*
X266050Y623675D01*
X266467Y624760D01*
X267508Y625535D01*
G01X278550Y634990D02*
X275842Y635300D01*
X273550Y635765D01*
X271467Y636385D01*
X269175Y637160D01*
X266050Y638400D01*
Y632200D01*
G01X278967Y647700D02*
X278758Y647390D01*
X278342D01*
X278133Y647700D01*
X278342Y648010D01*
X278758D01*
X278967Y647700D01*
G01X278550Y660100D02*
X278342Y661185D01*
X277717Y662425D01*
X276675Y663200D01*
X275217Y663510D01*
X273759Y663200D01*
X272508Y662270D01*
X271883Y660875D01*
Y659325D01*
X271467Y658395D01*
X270425Y657620D01*
X268967Y657310D01*
X267508Y657775D01*
X266467Y658860D01*
X266050Y660100D01*
X266467Y661340D01*
X267508Y662425D01*
X268967Y662890D01*
X270425Y662580D01*
X271467Y661805D01*
X271883Y660875D01*
Y659325D01*
X272508Y657930D01*
X273759Y657000D01*
X275217Y656690D01*
X276675Y657000D01*
X277717Y657775D01*
X278342Y659015D01*
X278550Y660100D01*
G01X273342Y669555D02*
X271883Y670640D01*
X271050Y671570D01*
X270633Y672810D01*
X271050Y673895D01*
X271883Y674670D01*
X273133Y675290D01*
X274592Y675445D01*
X275842Y675290D01*
X277092Y674670D01*
X278133Y673740D01*
X278550Y672655D01*
X278133Y671415D01*
X276884Y670330D01*
X275008Y669710D01*
X272925Y669555D01*
X270217Y669865D01*
X268758Y670330D01*
X267300Y671105D01*
X266258Y672190D01*
X266050Y673275D01*
X266467Y674360D01*
X267508Y675135D01*
G01X279293Y-670269D02*
X279893Y-669469D01*
X280593Y-669069D01*
X281393Y-668936D01*
X282393Y-669203D01*
X283093Y-669869D01*
X283293Y-670669D01*
X283193Y-671470D01*
X282793Y-672136D01*
X280793Y-673469D01*
X279893Y-674403D01*
X279293Y-675736D01*
X279093Y-676936D01*
X283293D01*
G01X289193Y-668936D02*
X288393Y-669203D01*
X287793Y-669869D01*
X287393Y-670669D01*
X287093Y-671736D01*
X286993Y-672936D01*
X287093Y-674136D01*
X287393Y-675203D01*
X287793Y-676003D01*
X288393Y-676669D01*
X289193Y-676936D01*
X289993Y-676669D01*
X290593Y-676003D01*
X290993Y-675203D01*
X291293Y-674136D01*
X291393Y-672936D01*
X291293Y-671736D01*
X290993Y-670669D01*
X290593Y-669869D01*
X289993Y-669203D01*
X289193Y-668936D01*
G01X295293Y-670269D02*
X295893Y-669469D01*
X296593Y-669069D01*
X297393Y-668936D01*
X298393Y-669203D01*
X299093Y-669869D01*
X299293Y-670669D01*
X299193Y-671470D01*
X298793Y-672136D01*
X296793Y-673469D01*
X295893Y-674403D01*
X295293Y-675736D01*
X295093Y-676936D01*
X299293D01*
G01X303293Y-670269D02*
X303893Y-669469D01*
X304593Y-669069D01*
X305393Y-668936D01*
X306393Y-669203D01*
X307093Y-669869D01*
X307293Y-670669D01*
X307193Y-671470D01*
X306793Y-672136D01*
X304793Y-673469D01*
X303893Y-674403D01*
X303293Y-675736D01*
X303093Y-676936D01*
X307293D01*
G01X311393Y-677203D02*
X314993Y-668936D01*
G01X321193Y-676936D02*
Y-668936D01*
X319993Y-670536D01*
G01Y-676936D02*
X322393D01*
G01X327293Y-670269D02*
X327893Y-669469D01*
X328593Y-669069D01*
X329393Y-668936D01*
X330393Y-669203D01*
X331093Y-669869D01*
X331293Y-670669D01*
X331193Y-671470D01*
X330793Y-672136D01*
X328793Y-673469D01*
X327893Y-674403D01*
X327293Y-675736D01*
X327093Y-676936D01*
X331293D01*
G01X335393Y-677203D02*
X338993Y-668936D01*
G01X345193D02*
X344393Y-669203D01*
X343793Y-669869D01*
X343393Y-670669D01*
X343093Y-671736D01*
X342993Y-672936D01*
X343093Y-674136D01*
X343393Y-675203D01*
X343793Y-676003D01*
X344393Y-676669D01*
X345193Y-676936D01*
X345993Y-676669D01*
X346593Y-676003D01*
X346993Y-675203D01*
X347293Y-674136D01*
X347393Y-672936D01*
X347293Y-671736D01*
X346993Y-670669D01*
X346593Y-669869D01*
X345993Y-669203D01*
X345193Y-668936D01*
G01X351493Y-676003D02*
X352193Y-676669D01*
X352993Y-676936D01*
X353793Y-676669D01*
X354493Y-675870D01*
X354993Y-674669D01*
X355193Y-673469D01*
Y-672003D01*
X354993Y-670803D01*
X354493Y-669736D01*
X353893Y-669203D01*
X353193Y-668936D01*
X352393Y-669203D01*
X351793Y-669736D01*
X351393Y-670536D01*
X351193Y-671603D01*
X351393Y-672536D01*
X351893Y-673469D01*
X352493Y-674003D01*
X353193Y-674136D01*
X353993Y-673870D01*
X354593Y-673203D01*
X355193Y-672003D01*
G01X278993Y-651936D02*
Y-643936D01*
X280993D01*
X281793Y-644336D01*
X282393Y-644869D01*
X282893Y-645669D01*
X283293Y-646603D01*
X283393Y-647936D01*
X283293Y-649269D01*
X282893Y-650203D01*
X282393Y-651003D01*
X281793Y-651536D01*
X280993Y-651936D01*
X278993D01*
G01X286693D02*
X289193Y-643936D01*
X291693Y-651936D01*
G01X290793Y-649136D02*
X287593D01*
G01X297193Y-643936D02*
X296393Y-644203D01*
X295793Y-644869D01*
X295393Y-645669D01*
X295093Y-646736D01*
X294993Y-647936D01*
X295093Y-649136D01*
X295393Y-650203D01*
X295793Y-651003D01*
X296393Y-651669D01*
X297193Y-651936D01*
X297993Y-651669D01*
X298593Y-651003D01*
X298993Y-650203D01*
X299293Y-649136D01*
X299393Y-647936D01*
X299293Y-646736D01*
X298993Y-645669D01*
X298593Y-644869D01*
X297993Y-644203D01*
X297193Y-643936D01*
G01X303293Y-651936D02*
Y-643936D01*
X307093D01*
G01X305693Y-647803D02*
X303293D01*
G01X313193Y-643936D02*
X312393Y-644203D01*
X311793Y-644869D01*
X311393Y-645669D01*
X311093Y-646736D01*
X310993Y-647936D01*
X311093Y-649136D01*
X311393Y-650203D01*
X311793Y-651003D01*
X312393Y-651669D01*
X313193Y-651936D01*
X313993Y-651669D01*
X314593Y-651003D01*
X314993Y-650203D01*
X315293Y-649136D01*
X315393Y-647936D01*
X315293Y-646736D01*
X314993Y-645669D01*
X314593Y-644869D01*
X313993Y-644203D01*
X313193Y-643936D01*
G01X321193D02*
Y-651936D01*
G01X318893Y-643936D02*
X323493D01*
G01X326593Y-651936D02*
Y-643936D01*
X329193Y-650603D01*
X331793Y-643936D01*
Y-651936D01*
G01X334993D02*
Y-643936D01*
X336993D01*
X337793Y-644336D01*
X338393Y-644869D01*
X338893Y-645669D01*
X339293Y-646603D01*
X339393Y-647936D01*
X339293Y-649269D01*
X338893Y-650203D01*
X338393Y-651003D01*
X337793Y-651536D01*
X336993Y-651936D01*
X334993D01*
G01X347393Y-644603D02*
X346793Y-644203D01*
X346093Y-643936D01*
X345293D01*
X344393Y-644336D01*
X343693Y-645003D01*
X343193Y-645803D01*
X342793Y-647136D01*
X342693Y-648336D01*
X342893Y-649536D01*
X343193Y-650336D01*
X343793Y-651136D01*
X344493Y-651669D01*
X345193Y-651936D01*
X345893D01*
X346593Y-651669D01*
X347193Y-651269D01*
X347693Y-650736D01*
G01X350993Y-651936D02*
Y-643936D01*
X352993D01*
X353793Y-644336D01*
X354393Y-644869D01*
X354893Y-645669D01*
X355293Y-646603D01*
X355393Y-647936D01*
X355293Y-649269D01*
X354893Y-650203D01*
X354393Y-651003D01*
X353793Y-651536D01*
X352993Y-651936D01*
X350993D01*
G01X361193Y-643936D02*
X360393Y-644203D01*
X359793Y-644869D01*
X359393Y-645669D01*
X359093Y-646736D01*
X358993Y-647936D01*
X359093Y-649136D01*
X359393Y-650203D01*
X359793Y-651003D01*
X360393Y-651669D01*
X361193Y-651936D01*
X361993Y-651669D01*
X362593Y-651003D01*
X362993Y-650203D01*
X363293Y-649136D01*
X363393Y-647936D01*
X363293Y-646736D01*
X362993Y-645669D01*
X362593Y-644869D01*
X361993Y-644203D01*
X361193Y-643936D01*
G01X281633Y505755D02*
X280384Y506685D01*
X279758Y507770D01*
X279550Y509010D01*
X279967Y510560D01*
X281008Y511645D01*
X282258Y511955D01*
X283509Y511800D01*
X284550Y511180D01*
X286633Y508080D01*
X288092Y506685D01*
X290175Y505755D01*
X292050Y505445D01*
Y511955D01*
G01X290592Y518465D02*
X291633Y519550D01*
X292050Y520790D01*
X291633Y522030D01*
X290384Y523115D01*
X288508Y523890D01*
X286633Y524200D01*
X284342D01*
X282467Y523890D01*
X280800Y523115D01*
X279967Y522185D01*
X279550Y521100D01*
X279967Y519860D01*
X280800Y518930D01*
X282050Y518310D01*
X283717Y518000D01*
X285175Y518310D01*
X286633Y519085D01*
X287467Y520015D01*
X287675Y521100D01*
X287259Y522340D01*
X286217Y523270D01*
X284342Y524200D01*
G01X292050Y533190D02*
X289342Y533500D01*
X287050Y533965D01*
X284967Y534585D01*
X282675Y535360D01*
X279550Y536600D01*
Y530400D01*
G01X292050Y545900D02*
X291842Y546985D01*
X291217Y548225D01*
X290175Y549000D01*
X288717Y549310D01*
X287259Y549000D01*
X286008Y548070D01*
X285383Y546675D01*
Y545125D01*
X284967Y544195D01*
X283925Y543420D01*
X282467Y543110D01*
X281008Y543575D01*
X279967Y544660D01*
X279550Y545900D01*
X279967Y547140D01*
X281008Y548225D01*
X282467Y548690D01*
X283925Y548380D01*
X284967Y547605D01*
X285383Y546675D01*
Y545125D01*
X286008Y543730D01*
X287259Y542800D01*
X288717Y542490D01*
X290175Y542800D01*
X291217Y543575D01*
X291842Y544815D01*
X292050Y545900D01*
G01X292467Y558300D02*
X292258Y557990D01*
X291842D01*
X291633Y558300D01*
X291842Y558610D01*
X292258D01*
X292467Y558300D01*
G01X292050Y570390D02*
X289342Y570700D01*
X287050Y571165D01*
X284967Y571785D01*
X282675Y572560D01*
X279550Y573800D01*
Y567600D01*
G01X292050Y584960D02*
X279550D01*
X288508Y579225D01*
Y586975D01*
G01X292050Y617390D02*
X289342Y617700D01*
X287050Y618165D01*
X284967Y618785D01*
X282675Y619560D01*
X279550Y620800D01*
Y614600D01*
G01X290175Y626690D02*
X291217Y627620D01*
X291842Y628705D01*
X292050Y630100D01*
X291633Y631495D01*
X290800Y632580D01*
X289342Y633355D01*
X287675Y633510D01*
X286008Y633200D01*
X284967Y632425D01*
X284133Y631340D01*
X283925Y630255D01*
X284133Y629170D01*
X284967Y627775D01*
X279550Y628240D01*
Y632425D01*
G01X292467Y642500D02*
X292258Y642190D01*
X291842D01*
X291633Y642500D01*
X291842Y642810D01*
X292258D01*
X292467Y642500D01*
G01X286842Y651955D02*
X285383Y653040D01*
X284550Y653970D01*
X284133Y655210D01*
X284550Y656295D01*
X285383Y657070D01*
X286633Y657690D01*
X288092Y657845D01*
X289342Y657690D01*
X290592Y657070D01*
X291633Y656140D01*
X292050Y655055D01*
X291633Y653815D01*
X290384Y652730D01*
X288508Y652110D01*
X286425Y651955D01*
X283717Y652265D01*
X282258Y652730D01*
X280800Y653505D01*
X279758Y654590D01*
X279550Y655675D01*
X279967Y656760D01*
X281008Y657535D01*
G01X286842Y664355D02*
X285383Y665440D01*
X284550Y666370D01*
X284133Y667610D01*
X284550Y668695D01*
X285383Y669470D01*
X286633Y670090D01*
X288092Y670245D01*
X289342Y670090D01*
X290592Y669470D01*
X291633Y668540D01*
X292050Y667455D01*
X291633Y666215D01*
X290384Y665130D01*
X288508Y664510D01*
X286425Y664355D01*
X283717Y664665D01*
X282258Y665130D01*
X280800Y665905D01*
X279758Y666990D01*
X279550Y668075D01*
X279967Y669160D01*
X281008Y669935D01*
G01X298418Y-624819D02*
Y-618519D01*
X301394D01*
G01X300298Y-621564D02*
X298418D01*
G01X306206Y-618519D02*
X305579Y-618729D01*
X305109Y-619254D01*
X304796Y-619884D01*
X304561Y-620724D01*
X304483Y-621669D01*
X304561Y-622614D01*
X304796Y-623454D01*
X305109Y-624084D01*
X305579Y-624609D01*
X306206Y-624819D01*
X306833Y-624609D01*
X307303Y-624084D01*
X307616Y-623454D01*
X307851Y-622614D01*
X307929Y-621669D01*
X307851Y-620724D01*
X307616Y-619884D01*
X307303Y-619254D01*
X306833Y-618729D01*
X306206Y-618519D01*
G01X312506D02*
Y-624819D01*
G01X310704Y-618519D02*
X314308D01*
G01X316456Y-626919D02*
X321156D01*
G01X323069Y-624819D02*
Y-618519D01*
X325106Y-623769D01*
X327143Y-618519D01*
Y-624819D01*
G01X332816D02*
Y-620619D01*
G01Y-621354D02*
X332503Y-620934D01*
X332033Y-620724D01*
X331484Y-620619D01*
X330936Y-620829D01*
X330466Y-621249D01*
X330153Y-621879D01*
X329996Y-622719D01*
X330153Y-623559D01*
X330466Y-624189D01*
X330936Y-624609D01*
X331484Y-624819D01*
X332033Y-624714D01*
X332503Y-624399D01*
X332816Y-623979D01*
G01X336374Y-624819D02*
Y-620619D01*
G01Y-621669D02*
X336688Y-621144D01*
X337158Y-620724D01*
X337784Y-620619D01*
X338333Y-620724D01*
X338803Y-621144D01*
X339038Y-621879D01*
Y-624819D01*
G01X345416D02*
Y-620619D01*
G01Y-621354D02*
X345103Y-620934D01*
X344633Y-620724D01*
X344084Y-620619D01*
X343536Y-620829D01*
X343066Y-621249D01*
X342753Y-621879D01*
X342596Y-622719D01*
X342753Y-623559D01*
X343066Y-624189D01*
X343536Y-624609D01*
X344084Y-624819D01*
X344633Y-624714D01*
X345103Y-624399D01*
X345416Y-623979D01*
G01X349209Y-626394D02*
X349758Y-626814D01*
X350384Y-626919D01*
X350933Y-626814D01*
X351403Y-626289D01*
X351716Y-625554D01*
Y-620619D01*
G01Y-621459D02*
X351403Y-621039D01*
X350933Y-620724D01*
X350384Y-620619D01*
X349758Y-620829D01*
X349366Y-621249D01*
X349053Y-621984D01*
X348896Y-622719D01*
X348974Y-623349D01*
X349288Y-624084D01*
X349758Y-624609D01*
X350384Y-624819D01*
X350854Y-624714D01*
X351403Y-624294D01*
X351716Y-623874D01*
G01X355431Y-621984D02*
X357938D01*
X357703Y-621249D01*
X357311Y-620829D01*
X356763Y-620619D01*
X356214Y-620724D01*
X355744Y-621039D01*
X355431Y-621774D01*
X355274Y-622404D01*
Y-623034D01*
X355431Y-623664D01*
X355823Y-624294D01*
X356293Y-624714D01*
X356841Y-624819D01*
X357389Y-624609D01*
X357938Y-623979D01*
G01X360556Y-624819D02*
Y-620619D01*
G01Y-621774D02*
X360791Y-621249D01*
X361183Y-620829D01*
X361731Y-620619D01*
X362279Y-620829D01*
X362671Y-621249D01*
X362906Y-621774D01*
Y-624819D01*
G01Y-621774D02*
X363141Y-621249D01*
X363533Y-620829D01*
X364081Y-620619D01*
X364629Y-620829D01*
X365021Y-621249D01*
X365256Y-621879D01*
Y-624819D01*
G01X368031Y-621984D02*
X370538D01*
X370303Y-621249D01*
X369911Y-620829D01*
X369363Y-620619D01*
X368814Y-620724D01*
X368344Y-621039D01*
X368031Y-621774D01*
X367874Y-622404D01*
Y-623034D01*
X368031Y-623664D01*
X368423Y-624294D01*
X368893Y-624714D01*
X369441Y-624819D01*
X369989Y-624609D01*
X370538Y-623979D01*
G01X374174Y-624819D02*
Y-620619D01*
G01Y-621669D02*
X374488Y-621144D01*
X374958Y-620724D01*
X375584Y-620619D01*
X376133Y-620724D01*
X376603Y-621144D01*
X376838Y-621879D01*
Y-624819D01*
G01X381806Y-618519D02*
Y-624819D01*
G01X380709Y-620619D02*
X382903D01*
G01X385756Y-626919D02*
X390456D01*
G01X395033Y-621459D02*
X395346Y-621144D01*
X395581Y-620619D01*
X395738Y-619884D01*
X395581Y-619254D01*
X395268Y-618834D01*
X394719Y-618519D01*
X392604D01*
Y-624819D01*
X395189D01*
X395738Y-624399D01*
X396051Y-623769D01*
X396208Y-623034D01*
X396051Y-622299D01*
X395581Y-621669D01*
X395033Y-621459D01*
X392604D01*
G01X398983Y-624819D02*
Y-618519D01*
X400549D01*
X401176Y-618834D01*
X401646Y-619254D01*
X402038Y-619884D01*
X402351Y-620619D01*
X402429Y-621669D01*
X402351Y-622719D01*
X402038Y-623454D01*
X401646Y-624084D01*
X401176Y-624504D01*
X400549Y-624819D01*
X398983D01*
G01X334065Y-196910D02*
X335524Y-195980D01*
X336357Y-194740D01*
X336565Y-193345D01*
X336357Y-192105D01*
X335315Y-190865D01*
X334065Y-190090D01*
X332815Y-189935D01*
X331357Y-190245D01*
X330315Y-191330D01*
X329898Y-192415D01*
Y-193810D01*
G01Y-192415D02*
X329273Y-191485D01*
X328232Y-190710D01*
X326982Y-190400D01*
X325732Y-190710D01*
X324690Y-191485D01*
X324065Y-192880D01*
X324273Y-194275D01*
X325107Y-195670D01*
G01X334065Y-184510D02*
X335524Y-183580D01*
X336357Y-182340D01*
X336565Y-180945D01*
X336357Y-179705D01*
X335315Y-178465D01*
X334065Y-177690D01*
X332815Y-177535D01*
X331357Y-177845D01*
X330315Y-178930D01*
X329898Y-180015D01*
Y-181410D01*
G01Y-180015D02*
X329273Y-179085D01*
X328232Y-178310D01*
X326982Y-178000D01*
X325732Y-178310D01*
X324690Y-179085D01*
X324065Y-180480D01*
X324273Y-181875D01*
X325107Y-183270D01*
G01X324065Y-168700D02*
X324482Y-169940D01*
X325523Y-170870D01*
X326773Y-171490D01*
X328440Y-171955D01*
X330315Y-172110D01*
X332190Y-171955D01*
X333857Y-171490D01*
X335107Y-170870D01*
X336148Y-169940D01*
X336565Y-168700D01*
X336148Y-167460D01*
X335107Y-166530D01*
X333857Y-165910D01*
X332190Y-165445D01*
X330315Y-165290D01*
X328440Y-165445D01*
X326773Y-165910D01*
X325523Y-166530D01*
X324482Y-167460D01*
X324065Y-168700D01*
G01X334065Y-159710D02*
X335524Y-158780D01*
X336357Y-157540D01*
X336565Y-156145D01*
X336357Y-154905D01*
X335315Y-153665D01*
X334065Y-152890D01*
X332815Y-152735D01*
X331357Y-153045D01*
X330315Y-154130D01*
X329898Y-155215D01*
Y-156610D01*
G01Y-155215D02*
X329273Y-154285D01*
X328232Y-153510D01*
X326982Y-153200D01*
X325732Y-153510D01*
X324690Y-154285D01*
X324065Y-155680D01*
X324273Y-157075D01*
X325107Y-158470D01*
G01X336982Y-143900D02*
X336773Y-144210D01*
X336357D01*
X336148Y-143900D01*
X336357Y-143590D01*
X336773D01*
X336982Y-143900D01*
G01X336565Y-131500D02*
X324065D01*
X326565Y-133360D01*
G01X336565D02*
Y-129640D01*
G01X334690Y-122510D02*
X335732Y-121580D01*
X336357Y-120495D01*
X336565Y-119100D01*
X336148Y-117705D01*
X335315Y-116620D01*
X333857Y-115845D01*
X332190Y-115690D01*
X330523Y-116000D01*
X329482Y-116775D01*
X328648Y-117860D01*
X328440Y-118945D01*
X328648Y-120030D01*
X329482Y-121425D01*
X324065Y-120960D01*
Y-116775D01*
G01X336565Y-84500D02*
X336357Y-83415D01*
X335732Y-82175D01*
X334690Y-81400D01*
X333232Y-81090D01*
X331774Y-81400D01*
X330523Y-82330D01*
X329898Y-83725D01*
Y-85275D01*
X329482Y-86205D01*
X328440Y-86980D01*
X326982Y-87290D01*
X325523Y-86825D01*
X324482Y-85740D01*
X324065Y-84500D01*
X324482Y-83260D01*
X325523Y-82175D01*
X326982Y-81710D01*
X328440Y-82020D01*
X329482Y-82795D01*
X329898Y-83725D01*
Y-85275D01*
X330523Y-86670D01*
X331774Y-87600D01*
X333232Y-87910D01*
X334690Y-87600D01*
X335732Y-86825D01*
X336357Y-85585D01*
X336565Y-84500D01*
G01X334065Y-75510D02*
X335524Y-74580D01*
X336357Y-73340D01*
X336565Y-71945D01*
X336357Y-70705D01*
X335315Y-69465D01*
X334065Y-68690D01*
X332815Y-68535D01*
X331357Y-68845D01*
X330315Y-69930D01*
X329898Y-71015D01*
Y-72410D01*
G01Y-71015D02*
X329273Y-70085D01*
X328232Y-69310D01*
X326982Y-69000D01*
X325732Y-69310D01*
X324690Y-70085D01*
X324065Y-71480D01*
X324273Y-72875D01*
X325107Y-74270D01*
G01X336982Y-59700D02*
X336773Y-60010D01*
X336357D01*
X336148Y-59700D01*
X336357Y-59390D01*
X336773D01*
X336982Y-59700D01*
G01X335107Y-49935D02*
X336148Y-48850D01*
X336565Y-47610D01*
X336148Y-46370D01*
X334899Y-45285D01*
X333023Y-44510D01*
X331148Y-44200D01*
X328857D01*
X326982Y-44510D01*
X325315Y-45285D01*
X324482Y-46215D01*
X324065Y-47300D01*
X324482Y-48540D01*
X325315Y-49470D01*
X326565Y-50090D01*
X328232Y-50400D01*
X329690Y-50090D01*
X331148Y-49315D01*
X331982Y-48385D01*
X332190Y-47300D01*
X331774Y-46060D01*
X330732Y-45130D01*
X328857Y-44200D01*
G01X350850Y-197210D02*
X352309Y-196280D01*
X353142Y-195040D01*
X353350Y-193645D01*
X353142Y-192405D01*
X352100Y-191165D01*
X350850Y-190390D01*
X349600Y-190235D01*
X348142Y-190545D01*
X347100Y-191630D01*
X346683Y-192715D01*
Y-194110D01*
G01Y-192715D02*
X346058Y-191785D01*
X345017Y-191010D01*
X343767Y-190700D01*
X342517Y-191010D01*
X341475Y-191785D01*
X340850Y-193180D01*
X341058Y-194575D01*
X341892Y-195970D01*
G01X350850Y-184810D02*
X352309Y-183880D01*
X353142Y-182640D01*
X353350Y-181245D01*
X353142Y-180005D01*
X352100Y-178765D01*
X350850Y-177990D01*
X349600Y-177835D01*
X348142Y-178145D01*
X347100Y-179230D01*
X346683Y-180315D01*
Y-181710D01*
G01Y-180315D02*
X346058Y-179385D01*
X345017Y-178610D01*
X343767Y-178300D01*
X342517Y-178610D01*
X341475Y-179385D01*
X340850Y-180780D01*
X341058Y-182175D01*
X341892Y-183570D01*
G01X350850Y-172410D02*
X352309Y-171480D01*
X353142Y-170240D01*
X353350Y-168845D01*
X353142Y-167605D01*
X352100Y-166365D01*
X350850Y-165590D01*
X349600Y-165435D01*
X348142Y-165745D01*
X347100Y-166830D01*
X346683Y-167915D01*
Y-169310D01*
G01Y-167915D02*
X346058Y-166985D01*
X345017Y-166210D01*
X343767Y-165900D01*
X342517Y-166210D01*
X341475Y-166985D01*
X340850Y-168380D01*
X341058Y-169775D01*
X341892Y-171170D01*
G01X353350Y-154740D02*
X340850D01*
X349808Y-160475D01*
Y-152725D01*
G01X353767Y-144200D02*
X353558Y-144510D01*
X353142D01*
X352933Y-144200D01*
X353142Y-143890D01*
X353558D01*
X353767Y-144200D01*
G01X348142Y-134745D02*
X346683Y-133660D01*
X345850Y-132730D01*
X345433Y-131490D01*
X345850Y-130405D01*
X346683Y-129630D01*
X347933Y-129010D01*
X349392Y-128855D01*
X350642Y-129010D01*
X351892Y-129630D01*
X352933Y-130560D01*
X353350Y-131645D01*
X352933Y-132885D01*
X351684Y-133970D01*
X349808Y-134590D01*
X347725Y-134745D01*
X345017Y-134435D01*
X343558Y-133970D01*
X342100Y-133195D01*
X341058Y-132110D01*
X340850Y-131025D01*
X341267Y-129940D01*
X342308Y-129165D01*
G01X348142Y-122345D02*
X346683Y-121260D01*
X345850Y-120330D01*
X345433Y-119090D01*
X345850Y-118005D01*
X346683Y-117230D01*
X347933Y-116610D01*
X349392Y-116455D01*
X350642Y-116610D01*
X351892Y-117230D01*
X352933Y-118160D01*
X353350Y-119245D01*
X352933Y-120485D01*
X351684Y-121570D01*
X349808Y-122190D01*
X347725Y-122345D01*
X345017Y-122035D01*
X343558Y-121570D01*
X342100Y-120795D01*
X341058Y-119710D01*
X340850Y-118625D01*
X341267Y-117540D01*
X342308Y-116765D01*
G01X353350Y-84800D02*
X353142Y-83715D01*
X352517Y-82475D01*
X351475Y-81700D01*
X350017Y-81390D01*
X348559Y-81700D01*
X347308Y-82630D01*
X346683Y-84025D01*
Y-85575D01*
X346267Y-86505D01*
X345225Y-87280D01*
X343767Y-87590D01*
X342308Y-87125D01*
X341267Y-86040D01*
X340850Y-84800D01*
X341267Y-83560D01*
X342308Y-82475D01*
X343767Y-82010D01*
X345225Y-82320D01*
X346267Y-83095D01*
X346683Y-84025D01*
Y-85575D01*
X347308Y-86970D01*
X348559Y-87900D01*
X350017Y-88210D01*
X351475Y-87900D01*
X352517Y-87125D01*
X353142Y-85885D01*
X353350Y-84800D01*
G01Y-70540D02*
X340850D01*
X349808Y-76275D01*
Y-68525D01*
G01X353767Y-60000D02*
X353558Y-60310D01*
X353142D01*
X352933Y-60000D01*
X353142Y-59690D01*
X353558D01*
X353767Y-60000D01*
G01X353350Y-47910D02*
X350642Y-47600D01*
X348350Y-47135D01*
X346267Y-46515D01*
X343975Y-45740D01*
X340850Y-44500D01*
Y-50700D01*
G01X367693Y-679936D02*
Y-671936D01*
X366493Y-673536D01*
G01Y-679936D02*
X368893D01*
G01X373793Y-676603D02*
X374493Y-675669D01*
X375093Y-675136D01*
X375893Y-674869D01*
X376593Y-675136D01*
X377093Y-675669D01*
X377493Y-676469D01*
X377593Y-677403D01*
X377493Y-678203D01*
X377093Y-679003D01*
X376493Y-679669D01*
X375793Y-679936D01*
X374993Y-679669D01*
X374293Y-678870D01*
X373893Y-677669D01*
X373793Y-676336D01*
X373993Y-674603D01*
X374293Y-673669D01*
X374793Y-672736D01*
X375493Y-672069D01*
X376193Y-671936D01*
X376893Y-672203D01*
X377393Y-672869D01*
G01X383693Y-680203D02*
X383493Y-680069D01*
Y-679803D01*
X383693Y-679669D01*
X383893Y-679803D01*
Y-680069D01*
X383693Y-680203D01*
G01X389793Y-676603D02*
X390493Y-675669D01*
X391093Y-675136D01*
X391893Y-674869D01*
X392593Y-675136D01*
X393093Y-675669D01*
X393493Y-676469D01*
X393593Y-677403D01*
X393493Y-678203D01*
X393093Y-679003D01*
X392493Y-679669D01*
X391793Y-679936D01*
X390993Y-679669D01*
X390293Y-678870D01*
X389893Y-677669D01*
X389793Y-676336D01*
X389993Y-674603D01*
X390293Y-673669D01*
X390793Y-672736D01*
X391493Y-672069D01*
X392193Y-671936D01*
X392893Y-672203D01*
X393393Y-672869D01*
G01X395560Y28450D02*
Y40950D01*
X389825Y31992D01*
X397575D01*
G01X403155Y33658D02*
X404240Y35117D01*
X405170Y35950D01*
X406410Y36367D01*
X407495Y35950D01*
X408270Y35117D01*
X408890Y33867D01*
X409045Y32408D01*
X408890Y31158D01*
X408270Y29908D01*
X407340Y28867D01*
X406255Y28450D01*
X405015Y28867D01*
X403930Y30116D01*
X403310Y31992D01*
X403155Y34075D01*
X403465Y36783D01*
X403930Y38242D01*
X404705Y39700D01*
X405790Y40742D01*
X406875Y40950D01*
X407960Y40533D01*
X408735Y39492D01*
G01X420360Y28450D02*
Y40950D01*
X414625Y31992D01*
X422375D01*
G01X430900Y28033D02*
X430590Y28242D01*
Y28658D01*
X430900Y28867D01*
X431210Y28658D01*
Y28242D01*
X430900Y28033D01*
G01X443300Y28450D02*
Y40950D01*
X441440Y38450D01*
G01Y28450D02*
X445160D01*
G01X455390D02*
X455700Y31158D01*
X456165Y33450D01*
X456785Y35533D01*
X457560Y37825D01*
X458800Y40950D01*
X452600D01*
G01X412693Y-679936D02*
Y-671936D01*
X411493Y-673536D01*
G01Y-679936D02*
X413893D01*
G01X420493D02*
X420693Y-678203D01*
X420993Y-676736D01*
X421393Y-675403D01*
X421893Y-673936D01*
X422693Y-671936D01*
X418693D01*
G01X428693Y-680203D02*
X428493Y-680069D01*
Y-679803D01*
X428693Y-679669D01*
X428893Y-679803D01*
Y-680069D01*
X428693Y-680203D01*
G01X434793Y-673269D02*
X435393Y-672469D01*
X436093Y-672069D01*
X436893Y-671936D01*
X437893Y-672203D01*
X438593Y-672869D01*
X438793Y-673669D01*
X438693Y-674470D01*
X438293Y-675136D01*
X436293Y-676469D01*
X435393Y-677403D01*
X434793Y-678736D01*
X434593Y-679936D01*
X438793D01*
G01X432493Y-654936D02*
Y-646936D01*
X434493D01*
X435293Y-647336D01*
X435893Y-647869D01*
X436393Y-648669D01*
X436793Y-649603D01*
X436893Y-650936D01*
X436793Y-652269D01*
X436393Y-653203D01*
X435893Y-654003D01*
X435293Y-654536D01*
X434493Y-654936D01*
X432493D01*
G01X490300Y28450D02*
Y40950D01*
X488440Y38450D01*
G01Y28450D02*
X492160D01*
G01X502700D02*
Y40950D01*
X500840Y38450D01*
G01Y28450D02*
X504560D01*
G01X515100Y28033D02*
X514790Y28242D01*
Y28658D01*
X515100Y28867D01*
X515410Y28658D01*
Y28242D01*
X515100Y28033D01*
G01X527190Y28450D02*
X527500Y31158D01*
X527965Y33450D01*
X528585Y35533D01*
X529360Y37825D01*
X530600Y40950D01*
X524400D01*
G01X537265Y29908D02*
X538350Y28867D01*
X539590Y28450D01*
X540830Y28867D01*
X541915Y30116D01*
X542690Y31992D01*
X543000Y33867D01*
Y36158D01*
X542690Y38033D01*
X541915Y39700D01*
X540985Y40533D01*
X539900Y40950D01*
X538660Y40533D01*
X537730Y39700D01*
X537110Y38450D01*
X536800Y36783D01*
X537110Y35325D01*
X537885Y33867D01*
X538815Y33033D01*
X539900Y32825D01*
X541140Y33241D01*
X542070Y34283D01*
X543000Y36158D01*
G01X563350Y227060D02*
X550850D01*
X559808Y221325D01*
Y229075D01*
G01X563350Y237290D02*
X560642Y237600D01*
X558350Y238065D01*
X556267Y238685D01*
X553975Y239460D01*
X550850Y240700D01*
Y234500D01*
G01X563350Y251860D02*
X550850D01*
X559808Y246125D01*
Y253875D01*
G01X550850Y262400D02*
X551267Y261160D01*
X552308Y260230D01*
X553558Y259610D01*
X555225Y259145D01*
X557100Y258990D01*
X558975Y259145D01*
X560642Y259610D01*
X561892Y260230D01*
X562933Y261160D01*
X563350Y262400D01*
X562933Y263640D01*
X561892Y264570D01*
X560642Y265190D01*
X558975Y265655D01*
X557100Y265810D01*
X555225Y265655D01*
X553558Y265190D01*
X552308Y264570D01*
X551267Y263640D01*
X550850Y262400D01*
G01X563767Y274800D02*
X563558Y274490D01*
X563142D01*
X562933Y274800D01*
X563142Y275110D01*
X563558D01*
X563767Y274800D01*
G01X563350Y287200D02*
X550850D01*
X553350Y285340D01*
G01X563350D02*
Y289060D01*
G01X558142Y296655D02*
X556683Y297740D01*
X555850Y298670D01*
X555433Y299910D01*
X555850Y300995D01*
X556683Y301770D01*
X557933Y302390D01*
X559392Y302545D01*
X560642Y302390D01*
X561892Y301770D01*
X562933Y300840D01*
X563350Y299755D01*
X562933Y298515D01*
X561684Y297430D01*
X559808Y296810D01*
X557725Y296655D01*
X555017Y296965D01*
X553558Y297430D01*
X552100Y298205D01*
X551058Y299290D01*
X550850Y300375D01*
X551267Y301460D01*
X552308Y302235D01*
G01X588350Y237750D02*
X575850D01*
X578350Y235890D01*
G01X588350D02*
Y239610D01*
G01X577933Y247205D02*
X576684Y248135D01*
X576058Y249220D01*
X575850Y250460D01*
X576267Y252010D01*
X577308Y253095D01*
X578558Y253405D01*
X579809Y253250D01*
X580850Y252630D01*
X582933Y249530D01*
X584392Y248135D01*
X586475Y247205D01*
X588350Y246895D01*
Y253405D01*
G01X575850Y262550D02*
X576267Y261310D01*
X577308Y260380D01*
X578558Y259760D01*
X580225Y259295D01*
X582100Y259140D01*
X583975Y259295D01*
X585642Y259760D01*
X586892Y260380D01*
X587933Y261310D01*
X588350Y262550D01*
X587933Y263790D01*
X586892Y264720D01*
X585642Y265340D01*
X583975Y265805D01*
X582100Y265960D01*
X580225Y265805D01*
X578558Y265340D01*
X577308Y264720D01*
X576267Y263790D01*
X575850Y262550D01*
G01X588767Y274950D02*
X588558Y274640D01*
X588142D01*
X587933Y274950D01*
X588142Y275260D01*
X588558D01*
X588767Y274950D01*
G01X588350Y289210D02*
X575850D01*
X584808Y283475D01*
Y291225D01*
G01X734805Y408750D02*
Y421250D01*
X740695D01*
G01X738525Y415208D02*
X734805D01*
G01X748290Y421250D02*
X752010D01*
G01X750150D02*
Y408750D01*
G01X748290D02*
X752010D01*
G01X763480Y415000D02*
X766580D01*
Y411250D01*
X765650Y410000D01*
X764565Y409167D01*
X763015Y408750D01*
X761465Y409167D01*
X760380Y410000D01*
X759450Y411250D01*
X758830Y412708D01*
X758520Y414375D01*
Y415833D01*
X758830Y417083D01*
X759450Y418542D01*
X760380Y419792D01*
X761310Y420625D01*
X762550Y421250D01*
X763635D01*
X764875Y420833D01*
X765805Y420000D01*
G01X771540Y421250D02*
Y412292D01*
X772160Y410416D01*
X773400Y409167D01*
X774950Y408750D01*
X776500Y409167D01*
X777740Y410416D01*
X778360Y412292D01*
Y421250D01*
G01X784250Y408750D02*
Y421250D01*
X788125D01*
X789365Y420625D01*
X790140Y419792D01*
X790450Y418125D01*
X790140Y416458D01*
X789210Y415417D01*
X788125Y414792D01*
X784250D01*
G01X788125D02*
X790450Y408750D01*
G01X802850D02*
X796650D01*
Y421250D01*
X802850D01*
G01X800370Y415208D02*
X796650D01*
G01X837105Y408750D02*
Y421250D01*
X842995D01*
G01X840825Y415208D02*
X837105D01*
G01X850590Y421250D02*
X854310D01*
G01X852450D02*
Y408750D01*
G01X850590D02*
X854310D01*
G01X861285D02*
Y421250D01*
X868415Y408750D01*
Y421250D01*
G01X875390D02*
X879110D01*
G01X877250D02*
Y408750D01*
G01X875390D02*
X879110D01*
G01X886395Y410416D02*
X887635Y409375D01*
X889030Y408750D01*
X890270D01*
X891510Y409375D01*
X892440Y410416D01*
X892905Y411875D01*
X892595Y413333D01*
X891820Y414583D01*
X890425Y415417D01*
X888565Y415833D01*
X887480Y416667D01*
X887015Y418125D01*
X887325Y419583D01*
X888100Y420625D01*
X889185Y421250D01*
X890270D01*
X891355Y420833D01*
X892285Y419792D01*
G01X898795Y408750D02*
Y421250D01*
G01X905305D02*
Y408750D01*
G01Y415000D02*
X898795D01*
G01X917550Y408750D02*
X911350D01*
Y421250D01*
X917550D01*
G01X915070Y415208D02*
X911350D01*
G01X923440Y408750D02*
Y421250D01*
X926540D01*
X927780Y420625D01*
X928710Y419792D01*
X929485Y418542D01*
X930105Y417083D01*
X930260Y415000D01*
X930105Y412917D01*
X929485Y411458D01*
X928710Y410208D01*
X927780Y409375D01*
X926540Y408750D01*
X923440D01*
G01X934600Y404583D02*
X943900D01*
G01X948395Y410416D02*
X949635Y409375D01*
X951030Y408750D01*
X952270D01*
X953510Y409375D01*
X954440Y410416D01*
X954905Y411875D01*
X954595Y413333D01*
X953820Y414583D01*
X952425Y415417D01*
X950565Y415833D01*
X949480Y416667D01*
X949015Y418125D01*
X949325Y419583D01*
X950100Y420625D01*
X951185Y421250D01*
X952270D01*
X953355Y420833D01*
X954285Y419792D01*
G01X962190Y421250D02*
X965910D01*
G01X964050D02*
Y408750D01*
G01X962190D02*
X965910D01*
G01X973505Y421250D02*
X979395D01*
X973505Y408750D01*
X979395D01*
G01X991950D02*
X985750D01*
Y421250D01*
X991950D01*
G01X989470Y415208D02*
X985750D01*
G01X852450Y-184925D02*
Y-172425D01*
X850590Y-174925D01*
G01Y-184925D02*
X854310D01*
G01X864850D02*
X865935Y-184717D01*
X867175Y-184092D01*
X867950Y-183050D01*
X868260Y-181592D01*
X867950Y-180134D01*
X867020Y-178883D01*
X865625Y-178258D01*
X864075D01*
X863145Y-177842D01*
X862370Y-176800D01*
X862060Y-175342D01*
X862525Y-173883D01*
X863610Y-172842D01*
X864850Y-172425D01*
X866090Y-172842D01*
X867175Y-173883D01*
X867640Y-175342D01*
X867330Y-176800D01*
X866555Y-177842D01*
X865625Y-178258D01*
X864075D01*
X862680Y-178883D01*
X861750Y-180134D01*
X861440Y-181592D01*
X861750Y-183050D01*
X862525Y-184092D01*
X863765Y-184717D01*
X864850Y-184925D01*
G01X874615Y-183467D02*
X875700Y-184508D01*
X876940Y-184925D01*
X878180Y-184508D01*
X879265Y-183259D01*
X880040Y-181383D01*
X880350Y-179508D01*
Y-177217D01*
X880040Y-175342D01*
X879265Y-173675D01*
X878335Y-172842D01*
X877250Y-172425D01*
X876010Y-172842D01*
X875080Y-173675D01*
X874460Y-174925D01*
X874150Y-176592D01*
X874460Y-178050D01*
X875235Y-179508D01*
X876165Y-180342D01*
X877250Y-180550D01*
X878490Y-180134D01*
X879420Y-179092D01*
X880350Y-177217D01*
G01X889650Y-185342D02*
X889340Y-185133D01*
Y-184717D01*
X889650Y-184508D01*
X889960Y-184717D01*
Y-185133D01*
X889650Y-185342D01*
G01X902050Y-172425D02*
X900810Y-172842D01*
X899880Y-173883D01*
X899260Y-175133D01*
X898795Y-176800D01*
X898640Y-178675D01*
X898795Y-180550D01*
X899260Y-182217D01*
X899880Y-183467D01*
X900810Y-184508D01*
X902050Y-184925D01*
X903290Y-184508D01*
X904220Y-183467D01*
X904840Y-182217D01*
X905305Y-180550D01*
X905460Y-178675D01*
X905305Y-176800D01*
X904840Y-175133D01*
X904220Y-173883D01*
X903290Y-172842D01*
X902050Y-172425D01*
G01X912125Y-176592D02*
X916775Y-184925D01*
G01Y-176592D02*
X912125Y-184925D01*
G01X926850D02*
Y-172425D01*
X924990Y-174925D01*
G01Y-184925D02*
X928710D01*
G01X936305Y-174508D02*
X937235Y-173259D01*
X938320Y-172633D01*
X939560Y-172425D01*
X941110Y-172842D01*
X942195Y-173883D01*
X942505Y-175133D01*
X942350Y-176384D01*
X941730Y-177425D01*
X938630Y-179508D01*
X937235Y-180967D01*
X936305Y-183050D01*
X935995Y-184925D01*
X942505D01*
G01X948705Y-179717D02*
X949790Y-178258D01*
X950720Y-177425D01*
X951960Y-177008D01*
X953045Y-177425D01*
X953820Y-178258D01*
X954440Y-179508D01*
X954595Y-180967D01*
X954440Y-182217D01*
X953820Y-183467D01*
X952890Y-184508D01*
X951805Y-184925D01*
X950565Y-184508D01*
X949480Y-183259D01*
X948860Y-181383D01*
X948705Y-179300D01*
X949015Y-176592D01*
X949480Y-175133D01*
X950255Y-173675D01*
X951340Y-172633D01*
X952425Y-172425D01*
X953510Y-172842D01*
X954285Y-173883D01*
G01X964050Y-185342D02*
X963740Y-185133D01*
Y-184717D01*
X964050Y-184508D01*
X964360Y-184717D01*
Y-185133D01*
X964050Y-185342D01*
G01X976450Y-172425D02*
X975210Y-172842D01*
X974280Y-173883D01*
X973660Y-175133D01*
X973195Y-176800D01*
X973040Y-178675D01*
X973195Y-180550D01*
X973660Y-182217D01*
X974280Y-183467D01*
X975210Y-184508D01*
X976450Y-184925D01*
X977690Y-184508D01*
X978620Y-183467D01*
X979240Y-182217D01*
X979705Y-180550D01*
X979860Y-178675D01*
X979705Y-176800D01*
X979240Y-175133D01*
X978620Y-173883D01*
X977690Y-172842D01*
X976450Y-172425D01*
G01X889650Y-156575D02*
Y-144075D01*
X887790Y-146575D01*
G01Y-156575D02*
X891510D01*
G01X899105Y-146158D02*
X900035Y-144909D01*
X901120Y-144283D01*
X902360Y-144075D01*
X903910Y-144492D01*
X904995Y-145533D01*
X905305Y-146783D01*
X905150Y-148034D01*
X904530Y-149075D01*
X901430Y-151158D01*
X900035Y-152617D01*
X899105Y-154700D01*
X898795Y-156575D01*
X905305D01*
G01X911040Y-154700D02*
X911970Y-155742D01*
X913055Y-156367D01*
X914450Y-156575D01*
X915845Y-156158D01*
X916930Y-155325D01*
X917705Y-153867D01*
X917860Y-152200D01*
X917550Y-150533D01*
X916775Y-149492D01*
X915690Y-148658D01*
X914605Y-148450D01*
X913520Y-148658D01*
X912125Y-149492D01*
X912590Y-144075D01*
X916775D01*
G01X926850Y-156992D02*
X926540Y-156783D01*
Y-156367D01*
X926850Y-156158D01*
X927160Y-156367D01*
Y-156783D01*
X926850Y-156992D01*
G01X939250Y-144075D02*
X938010Y-144492D01*
X937080Y-145533D01*
X936460Y-146783D01*
X935995Y-148450D01*
X935840Y-150325D01*
X935995Y-152200D01*
X936460Y-153867D01*
X937080Y-155117D01*
X938010Y-156158D01*
X939250Y-156575D01*
X940490Y-156158D01*
X941420Y-155117D01*
X942040Y-153867D01*
X942505Y-152200D01*
X942660Y-150325D01*
X942505Y-148450D01*
X942040Y-146783D01*
X941420Y-145533D01*
X940490Y-144492D01*
X939250Y-144075D01*
G01X892905Y-123017D02*
X893990Y-121558D01*
X894920Y-120725D01*
X896160Y-120308D01*
X897245Y-120725D01*
X898020Y-121558D01*
X898640Y-122808D01*
X898795Y-124267D01*
X898640Y-125517D01*
X898020Y-126767D01*
X897090Y-127808D01*
X896005Y-128225D01*
X894765Y-127808D01*
X893680Y-126559D01*
X893060Y-124683D01*
X892905Y-122600D01*
X893215Y-119892D01*
X893680Y-118433D01*
X894455Y-116975D01*
X895540Y-115933D01*
X896625Y-115725D01*
X897710Y-116142D01*
X898485Y-117183D01*
G01X907940Y-128225D02*
X908250Y-125517D01*
X908715Y-123225D01*
X909335Y-121142D01*
X910110Y-118850D01*
X911350Y-115725D01*
X905150D01*
G01X920650Y-128642D02*
X920340Y-128433D01*
Y-128017D01*
X920650Y-127808D01*
X920960Y-128017D01*
Y-128433D01*
X920650Y-128642D01*
G01X933050Y-115725D02*
X931810Y-116142D01*
X930880Y-117183D01*
X930260Y-118433D01*
X929795Y-120100D01*
X929640Y-121975D01*
X929795Y-123850D01*
X930260Y-125517D01*
X930880Y-126767D01*
X931810Y-127808D01*
X933050Y-128225D01*
X934290Y-127808D01*
X935220Y-126767D01*
X935840Y-125517D01*
X936305Y-123850D01*
X936460Y-121975D01*
X936305Y-120100D01*
X935840Y-118433D01*
X935220Y-117183D01*
X934290Y-116142D01*
X933050Y-115725D01*
G01X897710Y-99875D02*
Y-87375D01*
X891975Y-96333D01*
X899725D01*
G01X908250Y-99875D02*
X909335Y-99667D01*
X910575Y-99042D01*
X911350Y-98000D01*
X911660Y-96542D01*
X911350Y-95084D01*
X910420Y-93833D01*
X909025Y-93208D01*
X907475D01*
X906545Y-92792D01*
X905770Y-91750D01*
X905460Y-90292D01*
X905925Y-88833D01*
X907010Y-87792D01*
X908250Y-87375D01*
X909490Y-87792D01*
X910575Y-88833D01*
X911040Y-90292D01*
X910730Y-91750D01*
X909955Y-92792D01*
X909025Y-93208D01*
X907475D01*
X906080Y-93833D01*
X905150Y-95084D01*
X904840Y-96542D01*
X905150Y-98000D01*
X905925Y-99042D01*
X907165Y-99667D01*
X908250Y-99875D01*
G01X920650Y-100292D02*
X920340Y-100083D01*
Y-99667D01*
X920650Y-99458D01*
X920960Y-99667D01*
Y-100083D01*
X920650Y-100292D01*
G01X933050Y-87375D02*
X931810Y-87792D01*
X930880Y-88833D01*
X930260Y-90083D01*
X929795Y-91750D01*
X929640Y-93625D01*
X929795Y-95500D01*
X930260Y-97167D01*
X930880Y-98417D01*
X931810Y-99458D01*
X933050Y-99875D01*
X934290Y-99458D01*
X935220Y-98417D01*
X935840Y-97167D01*
X936305Y-95500D01*
X936460Y-93625D01*
X936305Y-91750D01*
X935840Y-90083D01*
X935220Y-88833D01*
X934290Y-87792D01*
X933050Y-87375D01*
G01X897710Y-71525D02*
Y-59025D01*
X891975Y-67983D01*
X899725D01*
G01X908250Y-71525D02*
Y-59025D01*
X906390Y-61525D01*
G01Y-71525D02*
X910110D01*
G01X920650Y-71942D02*
X920340Y-71733D01*
Y-71317D01*
X920650Y-71108D01*
X920960Y-71317D01*
Y-71733D01*
X920650Y-71942D01*
G01X933050Y-59025D02*
X931810Y-59442D01*
X930880Y-60483D01*
X930260Y-61733D01*
X929795Y-63400D01*
X929640Y-65275D01*
X929795Y-67150D01*
X930260Y-68817D01*
X930880Y-70067D01*
X931810Y-71108D01*
X933050Y-71525D01*
X934290Y-71108D01*
X935220Y-70067D01*
X935840Y-68817D01*
X936305Y-67150D01*
X936460Y-65275D01*
X936305Y-63400D01*
X935840Y-61733D01*
X935220Y-60483D01*
X934290Y-59442D01*
X933050Y-59025D01*
G01X892440Y-40675D02*
X893370Y-42134D01*
X894610Y-42967D01*
X896005Y-43175D01*
X897245Y-42967D01*
X898485Y-41925D01*
X899260Y-40675D01*
X899415Y-39425D01*
X899105Y-37967D01*
X898020Y-36925D01*
X896935Y-36508D01*
X895540D01*
G01X896935D02*
X897865Y-35883D01*
X898640Y-34842D01*
X898950Y-33592D01*
X898640Y-32342D01*
X897865Y-31300D01*
X896470Y-30675D01*
X895075Y-30883D01*
X893680Y-31717D01*
G01X905305Y-37967D02*
X906390Y-36508D01*
X907320Y-35675D01*
X908560Y-35258D01*
X909645Y-35675D01*
X910420Y-36508D01*
X911040Y-37758D01*
X911195Y-39217D01*
X911040Y-40467D01*
X910420Y-41717D01*
X909490Y-42758D01*
X908405Y-43175D01*
X907165Y-42758D01*
X906080Y-41509D01*
X905460Y-39633D01*
X905305Y-37550D01*
X905615Y-34842D01*
X906080Y-33383D01*
X906855Y-31925D01*
X907940Y-30883D01*
X909025Y-30675D01*
X910110Y-31092D01*
X910885Y-32133D01*
G01X920650Y-43592D02*
X920340Y-43383D01*
Y-42967D01*
X920650Y-42758D01*
X920960Y-42967D01*
Y-43383D01*
X920650Y-43592D01*
G01X933050Y-30675D02*
X931810Y-31092D01*
X930880Y-32133D01*
X930260Y-33383D01*
X929795Y-35050D01*
X929640Y-36925D01*
X929795Y-38800D01*
X930260Y-40467D01*
X930880Y-41717D01*
X931810Y-42758D01*
X933050Y-43175D01*
X934290Y-42758D01*
X935220Y-41717D01*
X935840Y-40467D01*
X936305Y-38800D01*
X936460Y-36925D01*
X936305Y-35050D01*
X935840Y-33383D01*
X935220Y-32133D01*
X934290Y-31092D01*
X933050Y-30675D01*
G01X889650Y-14825D02*
Y-2325D01*
X887790Y-4825D01*
G01Y-14825D02*
X891510D01*
G01X898640Y-12950D02*
X899570Y-13992D01*
X900655Y-14617D01*
X902050Y-14825D01*
X903445Y-14408D01*
X904530Y-13575D01*
X905305Y-12117D01*
X905460Y-10450D01*
X905150Y-8783D01*
X904375Y-7742D01*
X903290Y-6908D01*
X902205Y-6700D01*
X901120Y-6908D01*
X899725Y-7742D01*
X900190Y-2325D01*
X904375D01*
G01X914450D02*
X913210Y-2742D01*
X912280Y-3783D01*
X911660Y-5033D01*
X911195Y-6700D01*
X911040Y-8575D01*
X911195Y-10450D01*
X911660Y-12117D01*
X912280Y-13367D01*
X913210Y-14408D01*
X914450Y-14825D01*
X915690Y-14408D01*
X916620Y-13367D01*
X917240Y-12117D01*
X917705Y-10450D01*
X917860Y-8575D01*
X917705Y-6700D01*
X917240Y-5033D01*
X916620Y-3783D01*
X915690Y-2742D01*
X914450Y-2325D01*
G01X926850Y-15242D02*
X926540Y-15033D01*
Y-14617D01*
X926850Y-14408D01*
X927160Y-14617D01*
Y-15033D01*
X926850Y-15242D01*
G01X939250Y-2325D02*
X938010Y-2742D01*
X937080Y-3783D01*
X936460Y-5033D01*
X935995Y-6700D01*
X935840Y-8575D01*
X935995Y-10450D01*
X936460Y-12117D01*
X937080Y-13367D01*
X938010Y-14408D01*
X939250Y-14825D01*
X940490Y-14408D01*
X941420Y-13367D01*
X942040Y-12117D01*
X942505Y-10450D01*
X942660Y-8575D01*
X942505Y-6700D01*
X942040Y-5033D01*
X941420Y-3783D01*
X940490Y-2742D01*
X939250Y-2325D01*
G01X889650Y13525D02*
Y26025D01*
X887790Y23525D01*
G01Y13525D02*
X891510D01*
G01X898640Y16025D02*
X899570Y14566D01*
X900810Y13733D01*
X902205Y13525D01*
X903445Y13733D01*
X904685Y14775D01*
X905460Y16025D01*
X905615Y17275D01*
X905305Y18733D01*
X904220Y19775D01*
X903135Y20192D01*
X901740D01*
G01X903135D02*
X904065Y20817D01*
X904840Y21858D01*
X905150Y23108D01*
X904840Y24358D01*
X904065Y25400D01*
X902670Y26025D01*
X901275Y25817D01*
X899880Y24983D01*
G01X916310Y13525D02*
Y26025D01*
X910575Y17067D01*
X918325D01*
G01X926850Y13108D02*
X926540Y13317D01*
Y13733D01*
X926850Y13942D01*
X927160Y13733D01*
Y13317D01*
X926850Y13108D01*
G01X939250Y26025D02*
X938010Y25608D01*
X937080Y24567D01*
X936460Y23317D01*
X935995Y21650D01*
X935840Y19775D01*
X935995Y17900D01*
X936460Y16233D01*
X937080Y14983D01*
X938010Y13942D01*
X939250Y13525D01*
X940490Y13942D01*
X941420Y14983D01*
X942040Y16233D01*
X942505Y17900D01*
X942660Y19775D01*
X942505Y21650D01*
X942040Y23317D01*
X941420Y24567D01*
X940490Y25608D01*
X939250Y26025D01*
G01X889650Y41875D02*
Y54375D01*
X887790Y51875D01*
G01Y41875D02*
X891510D01*
G01X899105Y52292D02*
X900035Y53541D01*
X901120Y54167D01*
X902360Y54375D01*
X903910Y53958D01*
X904995Y52917D01*
X905305Y51667D01*
X905150Y50416D01*
X904530Y49375D01*
X901430Y47292D01*
X900035Y45833D01*
X899105Y43750D01*
X898795Y41875D01*
X905305D01*
G01X911505Y47083D02*
X912590Y48542D01*
X913520Y49375D01*
X914760Y49792D01*
X915845Y49375D01*
X916620Y48542D01*
X917240Y47292D01*
X917395Y45833D01*
X917240Y44583D01*
X916620Y43333D01*
X915690Y42292D01*
X914605Y41875D01*
X913365Y42292D01*
X912280Y43541D01*
X911660Y45417D01*
X911505Y47500D01*
X911815Y50208D01*
X912280Y51667D01*
X913055Y53125D01*
X914140Y54167D01*
X915225Y54375D01*
X916310Y53958D01*
X917085Y52917D01*
G01X926850Y41458D02*
X926540Y41667D01*
Y42083D01*
X926850Y42292D01*
X927160Y42083D01*
Y41667D01*
X926850Y41458D01*
G01X939250Y54375D02*
X938010Y53958D01*
X937080Y52917D01*
X936460Y51667D01*
X935995Y50000D01*
X935840Y48125D01*
X935995Y46250D01*
X936460Y44583D01*
X937080Y43333D01*
X938010Y42292D01*
X939250Y41875D01*
X940490Y42292D01*
X941420Y43333D01*
X942040Y44583D01*
X942505Y46250D01*
X942660Y48125D01*
X942505Y50000D01*
X942040Y51667D01*
X941420Y52917D01*
X940490Y53958D01*
X939250Y54375D01*
G01X889650Y70225D02*
Y82725D01*
X887790Y80225D01*
G01Y70225D02*
X891510D01*
G01X899105Y80642D02*
X900035Y81891D01*
X901120Y82517D01*
X902360Y82725D01*
X903910Y82308D01*
X904995Y81267D01*
X905305Y80017D01*
X905150Y78766D01*
X904530Y77725D01*
X901430Y75642D01*
X900035Y74183D01*
X899105Y72100D01*
X898795Y70225D01*
X905305D01*
G01X916310D02*
Y82725D01*
X910575Y73767D01*
X918325D01*
G01X926850Y69808D02*
X926540Y70017D01*
Y70433D01*
X926850Y70642D01*
X927160Y70433D01*
Y70017D01*
X926850Y69808D01*
G01X939250Y82725D02*
X938010Y82308D01*
X937080Y81267D01*
X936460Y80017D01*
X935995Y78350D01*
X935840Y76475D01*
X935995Y74600D01*
X936460Y72933D01*
X937080Y71683D01*
X938010Y70642D01*
X939250Y70225D01*
X940490Y70642D01*
X941420Y71683D01*
X942040Y72933D01*
X942505Y74600D01*
X942660Y76475D01*
X942505Y78350D01*
X942040Y80017D01*
X941420Y81267D01*
X940490Y82308D01*
X939250Y82725D01*
G01X893215Y100033D02*
X894300Y98992D01*
X895540Y98575D01*
X896780Y98992D01*
X897865Y100241D01*
X898640Y102117D01*
X898950Y103992D01*
Y106283D01*
X898640Y108158D01*
X897865Y109825D01*
X896935Y110658D01*
X895850Y111075D01*
X894610Y110658D01*
X893680Y109825D01*
X893060Y108575D01*
X892750Y106908D01*
X893060Y105450D01*
X893835Y103992D01*
X894765Y103158D01*
X895850Y102950D01*
X897090Y103366D01*
X898020Y104408D01*
X898950Y106283D01*
G01X908250Y98575D02*
Y111075D01*
X906390Y108575D01*
G01Y98575D02*
X910110D01*
G01X920650Y98158D02*
X920340Y98367D01*
Y98783D01*
X920650Y98992D01*
X920960Y98783D01*
Y98367D01*
X920650Y98158D01*
G01X933050Y111075D02*
X931810Y110658D01*
X930880Y109617D01*
X930260Y108367D01*
X929795Y106700D01*
X929640Y104825D01*
X929795Y102950D01*
X930260Y101283D01*
X930880Y100033D01*
X931810Y98992D01*
X933050Y98575D01*
X934290Y98992D01*
X935220Y100033D01*
X935840Y101283D01*
X936305Y102950D01*
X936460Y104825D01*
X936305Y106700D01*
X935840Y108367D01*
X935220Y109617D01*
X934290Y110658D01*
X933050Y111075D01*
G01X892905Y132133D02*
X893990Y133592D01*
X894920Y134425D01*
X896160Y134842D01*
X897245Y134425D01*
X898020Y133592D01*
X898640Y132342D01*
X898795Y130883D01*
X898640Y129633D01*
X898020Y128383D01*
X897090Y127342D01*
X896005Y126925D01*
X894765Y127342D01*
X893680Y128591D01*
X893060Y130467D01*
X892905Y132550D01*
X893215Y135258D01*
X893680Y136717D01*
X894455Y138175D01*
X895540Y139217D01*
X896625Y139425D01*
X897710Y139008D01*
X898485Y137967D01*
G01X907940Y126925D02*
X908250Y129633D01*
X908715Y131925D01*
X909335Y134008D01*
X910110Y136300D01*
X911350Y139425D01*
X905150D01*
G01X920650Y126508D02*
X920340Y126717D01*
Y127133D01*
X920650Y127342D01*
X920960Y127133D01*
Y126717D01*
X920650Y126508D01*
G01X933050Y139425D02*
X931810Y139008D01*
X930880Y137967D01*
X930260Y136717D01*
X929795Y135050D01*
X929640Y133175D01*
X929795Y131300D01*
X930260Y129633D01*
X930880Y128383D01*
X931810Y127342D01*
X933050Y126925D01*
X934290Y127342D01*
X935220Y128383D01*
X935840Y129633D01*
X936305Y131300D01*
X936460Y133175D01*
X936305Y135050D01*
X935840Y136717D01*
X935220Y137967D01*
X934290Y139008D01*
X933050Y139425D01*
G01X897710Y155275D02*
Y167775D01*
X891975Y158817D01*
X899725D01*
G01X908250Y155275D02*
Y167775D01*
X906390Y165275D01*
G01Y155275D02*
X910110D01*
G01X920650Y154858D02*
X920340Y155067D01*
Y155483D01*
X920650Y155692D01*
X920960Y155483D01*
Y155067D01*
X920650Y154858D01*
G01X933050Y167775D02*
X931810Y167358D01*
X930880Y166317D01*
X930260Y165067D01*
X929795Y163400D01*
X929640Y161525D01*
X929795Y159650D01*
X930260Y157983D01*
X930880Y156733D01*
X931810Y155692D01*
X933050Y155275D01*
X934290Y155692D01*
X935220Y156733D01*
X935840Y157983D01*
X936305Y159650D01*
X936460Y161525D01*
X936305Y163400D01*
X935840Y165067D01*
X935220Y166317D01*
X934290Y167358D01*
X933050Y167775D01*
G01X892440Y186125D02*
X893370Y184666D01*
X894610Y183833D01*
X896005Y183625D01*
X897245Y183833D01*
X898485Y184875D01*
X899260Y186125D01*
X899415Y187375D01*
X899105Y188833D01*
X898020Y189875D01*
X896935Y190292D01*
X895540D01*
G01X896935D02*
X897865Y190917D01*
X898640Y191958D01*
X898950Y193208D01*
X898640Y194458D01*
X897865Y195500D01*
X896470Y196125D01*
X895075Y195917D01*
X893680Y195083D01*
G01X905305Y194042D02*
X906235Y195291D01*
X907320Y195917D01*
X908560Y196125D01*
X910110Y195708D01*
X911195Y194667D01*
X911505Y193417D01*
X911350Y192166D01*
X910730Y191125D01*
X907630Y189042D01*
X906235Y187583D01*
X905305Y185500D01*
X904995Y183625D01*
X911505D01*
G01X920650Y183208D02*
X920340Y183417D01*
Y183833D01*
X920650Y184042D01*
X920960Y183833D01*
Y183417D01*
X920650Y183208D01*
G01X933050Y196125D02*
X931810Y195708D01*
X930880Y194667D01*
X930260Y193417D01*
X929795Y191750D01*
X929640Y189875D01*
X929795Y188000D01*
X930260Y186333D01*
X930880Y185083D01*
X931810Y184042D01*
X933050Y183625D01*
X934290Y184042D01*
X935220Y185083D01*
X935840Y186333D01*
X936305Y188000D01*
X936460Y189875D01*
X936305Y191750D01*
X935840Y193417D01*
X935220Y194667D01*
X934290Y195708D01*
X933050Y196125D01*
G01X892440Y214475D02*
X893370Y213016D01*
X894610Y212183D01*
X896005Y211975D01*
X897245Y212183D01*
X898485Y213225D01*
X899260Y214475D01*
X899415Y215725D01*
X899105Y217183D01*
X898020Y218225D01*
X896935Y218642D01*
X895540D01*
G01X896935D02*
X897865Y219267D01*
X898640Y220308D01*
X898950Y221558D01*
X898640Y222808D01*
X897865Y223850D01*
X896470Y224475D01*
X895075Y224267D01*
X893680Y223433D01*
G01X905305Y222392D02*
X906235Y223641D01*
X907320Y224267D01*
X908560Y224475D01*
X910110Y224058D01*
X911195Y223017D01*
X911505Y221767D01*
X911350Y220516D01*
X910730Y219475D01*
X907630Y217392D01*
X906235Y215933D01*
X905305Y213850D01*
X904995Y211975D01*
X911505D01*
G01X920650Y211558D02*
X920340Y211767D01*
Y212183D01*
X920650Y212392D01*
X920960Y212183D01*
Y211767D01*
X920650Y211558D01*
G01X933050Y224475D02*
X931810Y224058D01*
X930880Y223017D01*
X930260Y221767D01*
X929795Y220100D01*
X929640Y218225D01*
X929795Y216350D01*
X930260Y214683D01*
X930880Y213433D01*
X931810Y212392D01*
X933050Y211975D01*
X934290Y212392D01*
X935220Y213433D01*
X935840Y214683D01*
X936305Y216350D01*
X936460Y218225D01*
X936305Y220100D01*
X935840Y221767D01*
X935220Y223017D01*
X934290Y224058D01*
X933050Y224475D01*
G01X892905Y250742D02*
X893835Y251991D01*
X894920Y252617D01*
X896160Y252825D01*
X897710Y252408D01*
X898795Y251367D01*
X899105Y250117D01*
X898950Y248866D01*
X898330Y247825D01*
X895230Y245742D01*
X893835Y244283D01*
X892905Y242200D01*
X892595Y240325D01*
X899105D01*
G01X908250D02*
X909335Y240533D01*
X910575Y241158D01*
X911350Y242200D01*
X911660Y243658D01*
X911350Y245116D01*
X910420Y246367D01*
X909025Y246992D01*
X907475D01*
X906545Y247408D01*
X905770Y248450D01*
X905460Y249908D01*
X905925Y251367D01*
X907010Y252408D01*
X908250Y252825D01*
X909490Y252408D01*
X910575Y251367D01*
X911040Y249908D01*
X910730Y248450D01*
X909955Y247408D01*
X909025Y246992D01*
X907475D01*
X906080Y246367D01*
X905150Y245116D01*
X904840Y243658D01*
X905150Y242200D01*
X905925Y241158D01*
X907165Y240533D01*
X908250Y240325D01*
G01X920650Y239908D02*
X920340Y240117D01*
Y240533D01*
X920650Y240742D01*
X920960Y240533D01*
Y240117D01*
X920650Y239908D01*
G01X933050Y252825D02*
X931810Y252408D01*
X930880Y251367D01*
X930260Y250117D01*
X929795Y248450D01*
X929640Y246575D01*
X929795Y244700D01*
X930260Y243033D01*
X930880Y241783D01*
X931810Y240742D01*
X933050Y240325D01*
X934290Y240742D01*
X935220Y241783D01*
X935840Y243033D01*
X936305Y244700D01*
X936460Y246575D01*
X936305Y248450D01*
X935840Y250117D01*
X935220Y251367D01*
X934290Y252408D01*
X933050Y252825D01*
G01X895850Y268675D02*
Y281175D01*
X893990Y278675D01*
G01Y268675D02*
X897710D01*
G01X908250Y281175D02*
X907010Y280758D01*
X906080Y279717D01*
X905460Y278467D01*
X904995Y276800D01*
X904840Y274925D01*
X904995Y273050D01*
X905460Y271383D01*
X906080Y270133D01*
X907010Y269092D01*
X908250Y268675D01*
X909490Y269092D01*
X910420Y270133D01*
X911040Y271383D01*
X911505Y273050D01*
X911660Y274925D01*
X911505Y276800D01*
X911040Y278467D01*
X910420Y279717D01*
X909490Y280758D01*
X908250Y281175D01*
G01X920650Y268258D02*
X920340Y268467D01*
Y268883D01*
X920650Y269092D01*
X920960Y268883D01*
Y268467D01*
X920650Y268258D01*
G01X933050Y281175D02*
X931810Y280758D01*
X930880Y279717D01*
X930260Y278467D01*
X929795Y276800D01*
X929640Y274925D01*
X929795Y273050D01*
X930260Y271383D01*
X930880Y270133D01*
X931810Y269092D01*
X933050Y268675D01*
X934290Y269092D01*
X935220Y270133D01*
X935840Y271383D01*
X936305Y273050D01*
X936460Y274925D01*
X936305Y276800D01*
X935840Y278467D01*
X935220Y279717D01*
X934290Y280758D01*
X933050Y281175D01*
G01X895850Y297025D02*
Y309525D01*
X893990Y307025D01*
G01Y297025D02*
X897710D01*
G01X908250Y309525D02*
X907010Y309108D01*
X906080Y308067D01*
X905460Y306817D01*
X904995Y305150D01*
X904840Y303275D01*
X904995Y301400D01*
X905460Y299733D01*
X906080Y298483D01*
X907010Y297442D01*
X908250Y297025D01*
X909490Y297442D01*
X910420Y298483D01*
X911040Y299733D01*
X911505Y301400D01*
X911660Y303275D01*
X911505Y305150D01*
X911040Y306817D01*
X910420Y308067D01*
X909490Y309108D01*
X908250Y309525D01*
G01X920650Y296608D02*
X920340Y296817D01*
Y297233D01*
X920650Y297442D01*
X920960Y297233D01*
Y296817D01*
X920650Y296608D01*
G01X933050Y309525D02*
X931810Y309108D01*
X930880Y308067D01*
X930260Y306817D01*
X929795Y305150D01*
X929640Y303275D01*
X929795Y301400D01*
X930260Y299733D01*
X930880Y298483D01*
X931810Y297442D01*
X933050Y297025D01*
X934290Y297442D01*
X935220Y298483D01*
X935840Y299733D01*
X936305Y301400D01*
X936460Y303275D01*
X936305Y305150D01*
X935840Y306817D01*
X935220Y308067D01*
X934290Y309108D01*
X933050Y309525D01*
G01X895850Y325375D02*
Y337875D01*
X893990Y335375D01*
G01Y325375D02*
X897710D01*
G01X908250Y337875D02*
X907010Y337458D01*
X906080Y336417D01*
X905460Y335167D01*
X904995Y333500D01*
X904840Y331625D01*
X904995Y329750D01*
X905460Y328083D01*
X906080Y326833D01*
X907010Y325792D01*
X908250Y325375D01*
X909490Y325792D01*
X910420Y326833D01*
X911040Y328083D01*
X911505Y329750D01*
X911660Y331625D01*
X911505Y333500D01*
X911040Y335167D01*
X910420Y336417D01*
X909490Y337458D01*
X908250Y337875D01*
G01X920650Y324958D02*
X920340Y325167D01*
Y325583D01*
X920650Y325792D01*
X920960Y325583D01*
Y325167D01*
X920650Y324958D01*
G01X933050Y337875D02*
X931810Y337458D01*
X930880Y336417D01*
X930260Y335167D01*
X929795Y333500D01*
X929640Y331625D01*
X929795Y329750D01*
X930260Y328083D01*
X930880Y326833D01*
X931810Y325792D01*
X933050Y325375D01*
X934290Y325792D01*
X935220Y326833D01*
X935840Y328083D01*
X936305Y329750D01*
X936460Y331625D01*
X936305Y333500D01*
X935840Y335167D01*
X935220Y336417D01*
X934290Y337458D01*
X933050Y337875D01*
G01X895850Y353725D02*
Y366225D01*
X893990Y363725D01*
G01Y353725D02*
X897710D01*
G01X908250Y366225D02*
X907010Y365808D01*
X906080Y364767D01*
X905460Y363517D01*
X904995Y361850D01*
X904840Y359975D01*
X904995Y358100D01*
X905460Y356433D01*
X906080Y355183D01*
X907010Y354142D01*
X908250Y353725D01*
X909490Y354142D01*
X910420Y355183D01*
X911040Y356433D01*
X911505Y358100D01*
X911660Y359975D01*
X911505Y361850D01*
X911040Y363517D01*
X910420Y364767D01*
X909490Y365808D01*
X908250Y366225D01*
G01X920650Y353308D02*
X920340Y353517D01*
Y353933D01*
X920650Y354142D01*
X920960Y353933D01*
Y353517D01*
X920650Y353308D01*
G01X933050Y366225D02*
X931810Y365808D01*
X930880Y364767D01*
X930260Y363517D01*
X929795Y361850D01*
X929640Y359975D01*
X929795Y358100D01*
X930260Y356433D01*
X930880Y355183D01*
X931810Y354142D01*
X933050Y353725D01*
X934290Y354142D01*
X935220Y355183D01*
X935840Y356433D01*
X936305Y358100D01*
X936460Y359975D01*
X936305Y361850D01*
X935840Y363517D01*
X935220Y364767D01*
X934290Y365808D01*
X933050Y366225D01*
G01X893215Y383533D02*
X894300Y382492D01*
X895540Y382075D01*
X896780Y382492D01*
X897865Y383741D01*
X898640Y385617D01*
X898950Y387492D01*
Y389783D01*
X898640Y391658D01*
X897865Y393325D01*
X896935Y394158D01*
X895850Y394575D01*
X894610Y394158D01*
X893680Y393325D01*
X893060Y392075D01*
X892750Y390408D01*
X893060Y388950D01*
X893835Y387492D01*
X894765Y386658D01*
X895850Y386450D01*
X897090Y386866D01*
X898020Y387908D01*
X898950Y389783D01*
G01X908250Y381658D02*
X907940Y381867D01*
Y382283D01*
X908250Y382492D01*
X908560Y382283D01*
Y381867D01*
X908250Y381658D01*
G01X920650Y382075D02*
X921735Y382283D01*
X922975Y382908D01*
X923750Y383950D01*
X924060Y385408D01*
X923750Y386866D01*
X922820Y388117D01*
X921425Y388742D01*
X919875D01*
X918945Y389158D01*
X918170Y390200D01*
X917860Y391658D01*
X918325Y393117D01*
X919410Y394158D01*
X920650Y394575D01*
X921890Y394158D01*
X922975Y393117D01*
X923440Y391658D01*
X923130Y390200D01*
X922355Y389158D01*
X921425Y388742D01*
X919875D01*
X918480Y388117D01*
X917550Y386866D01*
X917240Y385408D01*
X917550Y383950D01*
X918325Y382908D01*
X919565Y382283D01*
X920650Y382075D01*
G01X934910D02*
Y394575D01*
X929175Y385617D01*
X936925D01*
G01X1406541Y759705D02*
G03I-200000J0D01*
G01X1032250Y408750D02*
Y421250D01*
X1036125D01*
X1037365Y420625D01*
X1038140Y419792D01*
X1038450Y418125D01*
X1038140Y416458D01*
X1037210Y415417D01*
X1036125Y414792D01*
X1032250D01*
G01X1036125D02*
X1038450Y408750D01*
G01X1047750D02*
X1046510Y408958D01*
X1045425Y409791D01*
X1044495Y411042D01*
X1043875Y412500D01*
X1043565Y414167D01*
Y415833D01*
X1043875Y417500D01*
X1044495Y418958D01*
X1045425Y420208D01*
X1046510Y421042D01*
X1047750Y421250D01*
X1048990Y421042D01*
X1050075Y420208D01*
X1051005Y418958D01*
X1051625Y417500D01*
X1051935Y415833D01*
Y414167D01*
X1051625Y412500D01*
X1051005Y411042D01*
X1050075Y409791D01*
X1048990Y408958D01*
X1047750Y408750D01*
G01X1060150Y421250D02*
Y408750D01*
G01X1056585Y421250D02*
X1063715D01*
G01X1068675Y408750D02*
X1072550Y421250D01*
X1076425Y408750D01*
G01X1075030Y413125D02*
X1070070D01*
G01X1084950Y421250D02*
Y408750D01*
G01X1081385Y421250D02*
X1088515D01*
G01X1095490D02*
X1099210D01*
G01X1097350D02*
Y408750D01*
G01X1095490D02*
X1099210D01*
G01X1109750D02*
X1108510Y408958D01*
X1107425Y409791D01*
X1106495Y411042D01*
X1105875Y412500D01*
X1105565Y414167D01*
Y415833D01*
X1105875Y417500D01*
X1106495Y418958D01*
X1107425Y420208D01*
X1108510Y421042D01*
X1109750Y421250D01*
X1110990Y421042D01*
X1112075Y420208D01*
X1113005Y418958D01*
X1113625Y417500D01*
X1113935Y415833D01*
Y414167D01*
X1113625Y412500D01*
X1113005Y411042D01*
X1112075Y409791D01*
X1110990Y408958D01*
X1109750Y408750D01*
G01X1118585D02*
Y421250D01*
X1125715Y408750D01*
Y421250D01*
G01X1045115Y-183467D02*
X1046200Y-184508D01*
X1047440Y-184925D01*
X1048680Y-184508D01*
X1049765Y-183259D01*
X1050540Y-181383D01*
X1050850Y-179508D01*
Y-177217D01*
X1050540Y-175342D01*
X1049765Y-173675D01*
X1048835Y-172842D01*
X1047750Y-172425D01*
X1046510Y-172842D01*
X1045580Y-173675D01*
X1044960Y-174925D01*
X1044650Y-176592D01*
X1044960Y-178050D01*
X1045735Y-179508D01*
X1046665Y-180342D01*
X1047750Y-180550D01*
X1048990Y-180134D01*
X1049920Y-179092D01*
X1050850Y-177217D01*
G01X1060150Y-172425D02*
X1058910Y-172842D01*
X1057980Y-173883D01*
X1057360Y-175133D01*
X1056895Y-176800D01*
X1056740Y-178675D01*
X1056895Y-180550D01*
X1057360Y-182217D01*
X1057980Y-183467D01*
X1058910Y-184508D01*
X1060150Y-184925D01*
X1061390Y-184508D01*
X1062320Y-183467D01*
X1062940Y-182217D01*
X1063405Y-180550D01*
X1063560Y-178675D01*
X1063405Y-176800D01*
X1062940Y-175133D01*
X1062320Y-173883D01*
X1061390Y-172842D01*
X1060150Y-172425D01*
G01X1072550Y-185342D02*
X1072240Y-185133D01*
Y-184717D01*
X1072550Y-184508D01*
X1072860Y-184717D01*
Y-185133D01*
X1072550Y-185342D01*
G01X1084950Y-172425D02*
X1083710Y-172842D01*
X1082780Y-173883D01*
X1082160Y-175133D01*
X1081695Y-176800D01*
X1081540Y-178675D01*
X1081695Y-180550D01*
X1082160Y-182217D01*
X1082780Y-183467D01*
X1083710Y-184508D01*
X1084950Y-184925D01*
X1086190Y-184508D01*
X1087120Y-183467D01*
X1087740Y-182217D01*
X1088205Y-180550D01*
X1088360Y-178675D01*
X1088205Y-176800D01*
X1087740Y-175133D01*
X1087120Y-173883D01*
X1086190Y-172842D01*
X1084950Y-172425D01*
G01X1097350D02*
X1096110Y-172842D01*
X1095180Y-173883D01*
X1094560Y-175133D01*
X1094095Y-176800D01*
X1093940Y-178675D01*
X1094095Y-180550D01*
X1094560Y-182217D01*
X1095180Y-183467D01*
X1096110Y-184508D01*
X1097350Y-184925D01*
X1098590Y-184508D01*
X1099520Y-183467D01*
X1100140Y-182217D01*
X1100605Y-180550D01*
X1100760Y-178675D01*
X1100605Y-176800D01*
X1100140Y-175133D01*
X1099520Y-173883D01*
X1098590Y-172842D01*
X1097350Y-172425D01*
G01X1109750D02*
X1108510Y-172842D01*
X1107580Y-173883D01*
X1106960Y-175133D01*
X1106495Y-176800D01*
X1106340Y-178675D01*
X1106495Y-180550D01*
X1106960Y-182217D01*
X1107580Y-183467D01*
X1108510Y-184508D01*
X1109750Y-184925D01*
X1110990Y-184508D01*
X1111920Y-183467D01*
X1112540Y-182217D01*
X1113005Y-180550D01*
X1113160Y-178675D01*
X1113005Y-176800D01*
X1112540Y-175133D01*
X1111920Y-173883D01*
X1110990Y-172842D01*
X1109750Y-172425D01*
G01X1076735Y-152408D02*
X1080765D01*
G01X1076735Y-124058D02*
X1080765D01*
G01X1076735Y-95708D02*
X1080765D01*
G01X1076735Y-67358D02*
X1080765D01*
G01X1076735Y-39008D02*
X1080765D01*
G01X1076735Y-10658D02*
X1080765D01*
G01X1076735Y17692D02*
X1080765D01*
G01X1076735Y46042D02*
X1080765D01*
G01X1076735Y74392D02*
X1080765D01*
G01X1076735Y102742D02*
X1080765D01*
G01X1076735Y131092D02*
X1080765D01*
G01X1076735Y159442D02*
X1080765D01*
G01X1076735Y187792D02*
X1080765D01*
G01X1076735Y216142D02*
X1080765D01*
G01X1076735Y244492D02*
X1080765D01*
G01X1076735Y272842D02*
X1080765D01*
G01X1076735Y301192D02*
X1080765D01*
G01X1076735Y329542D02*
X1080765D01*
G01X1076735Y357892D02*
X1080765D01*
G01X1076735Y386242D02*
X1080765D01*
G01X1078440Y458750D02*
Y471250D01*
X1081540D01*
X1082780Y470625D01*
X1083710Y469792D01*
X1084485Y468542D01*
X1085105Y467083D01*
X1085260Y465000D01*
X1085105Y462917D01*
X1084485Y461458D01*
X1083710Y460208D01*
X1082780Y459375D01*
X1081540Y458750D01*
X1078440D01*
G01X1091150D02*
Y471250D01*
X1095025D01*
X1096265Y470625D01*
X1097040Y469792D01*
X1097350Y468125D01*
X1097040Y466458D01*
X1096110Y465417D01*
X1095025Y464792D01*
X1091150D01*
G01X1095025D02*
X1097350Y458750D01*
G01X1104790Y471250D02*
X1108510D01*
G01X1106650D02*
Y458750D01*
G01X1104790D02*
X1108510D01*
G01X1115950Y471250D02*
Y458750D01*
X1122150D01*
G01X1128350Y471250D02*
Y458750D01*
X1134550D01*
G01X1159660Y470208D02*
X1158730Y470833D01*
X1157645Y471250D01*
X1156405D01*
X1155010Y470625D01*
X1153925Y469583D01*
X1153150Y468333D01*
X1152530Y466250D01*
X1152375Y464375D01*
X1152685Y462500D01*
X1153150Y461250D01*
X1154080Y460000D01*
X1155165Y459167D01*
X1156250Y458750D01*
X1157335D01*
X1158420Y459167D01*
X1159350Y459791D01*
X1160125Y460625D01*
G01X1165395Y458750D02*
Y471250D01*
G01X1171905D02*
Y458750D01*
G01Y465000D02*
X1165395D01*
G01X1177175Y458750D02*
X1181050Y471250D01*
X1184925Y458750D01*
G01X1183530Y463125D02*
X1178570D01*
G01X1190350Y458750D02*
Y471250D01*
X1194225D01*
X1195465Y470625D01*
X1196240Y469792D01*
X1196550Y468125D01*
X1196240Y466458D01*
X1195310Y465417D01*
X1194225Y464792D01*
X1190350D01*
G01X1194225D02*
X1196550Y458750D01*
G01X1205850Y471250D02*
Y458750D01*
G01X1202285Y471250D02*
X1209415D01*
G01X1218250Y458333D02*
X1217940Y458542D01*
Y458958D01*
X1218250Y459167D01*
X1218560Y458958D01*
Y458542D01*
X1218250Y458333D01*
G01Y463958D02*
X1217940Y464167D01*
Y464583D01*
X1218250Y464792D01*
X1218560Y464583D01*
Y464167D01*
X1218250Y463958D01*
G01X1243050Y471250D02*
Y458750D01*
G01X1239485Y471250D02*
X1246615D01*
G01X1255450Y458750D02*
X1254210Y458958D01*
X1253125Y459791D01*
X1252195Y461042D01*
X1251575Y462500D01*
X1251265Y464167D01*
Y465833D01*
X1251575Y467500D01*
X1252195Y468958D01*
X1253125Y470208D01*
X1254210Y471042D01*
X1255450Y471250D01*
X1256690Y471042D01*
X1257775Y470208D01*
X1258705Y468958D01*
X1259325Y467500D01*
X1259635Y465833D01*
Y464167D01*
X1259325Y462500D01*
X1258705Y461042D01*
X1257775Y459791D01*
X1256690Y458958D01*
X1255450Y458750D01*
G01X1264750D02*
Y471250D01*
X1268470D01*
X1269710Y470625D01*
X1270640Y469167D01*
X1270950Y467500D01*
X1270640Y465833D01*
X1269865Y464583D01*
X1268470Y463958D01*
X1264750D01*
G01X1292650Y471250D02*
Y458750D01*
G01X1290480Y467083D02*
X1294820D01*
G01X1305050Y458750D02*
X1304120Y458958D01*
X1303190Y459791D01*
X1302570Y461250D01*
X1302260Y462917D01*
X1302570Y464583D01*
X1303190Y466042D01*
X1304120Y466875D01*
X1305050Y467083D01*
X1305980Y466875D01*
X1306910Y466042D01*
X1307530Y464583D01*
X1307685Y462917D01*
X1307530Y461250D01*
X1306910Y459791D01*
X1305980Y458958D01*
X1305050Y458750D01*
G01X1331090Y465417D02*
X1331710Y466042D01*
X1332175Y467083D01*
X1332485Y468542D01*
X1332175Y469792D01*
X1331555Y470625D01*
X1330470Y471250D01*
X1326285D01*
Y458750D01*
X1331400D01*
X1332485Y459583D01*
X1333105Y460833D01*
X1333415Y462292D01*
X1333105Y463750D01*
X1332175Y465000D01*
X1331090Y465417D01*
X1326285D01*
G01X1342250Y458750D02*
X1341010Y458958D01*
X1339925Y459791D01*
X1338995Y461042D01*
X1338375Y462500D01*
X1338065Y464167D01*
Y465833D01*
X1338375Y467500D01*
X1338995Y468958D01*
X1339925Y470208D01*
X1341010Y471042D01*
X1342250Y471250D01*
X1343490Y471042D01*
X1344575Y470208D01*
X1345505Y468958D01*
X1346125Y467500D01*
X1346435Y465833D01*
Y464167D01*
X1346125Y462500D01*
X1345505Y461042D01*
X1344575Y459791D01*
X1343490Y458958D01*
X1342250Y458750D01*
G01X1354650Y471250D02*
Y458750D01*
G01X1351085Y471250D02*
X1358215D01*
G01X1367050D02*
Y458750D01*
G01X1363485Y471250D02*
X1370615D01*
G01X1379450Y458750D02*
X1378210Y458958D01*
X1377125Y459791D01*
X1376195Y461042D01*
X1375575Y462500D01*
X1375265Y464167D01*
Y465833D01*
X1375575Y467500D01*
X1376195Y468958D01*
X1377125Y470208D01*
X1378210Y471042D01*
X1379450Y471250D01*
X1380690Y471042D01*
X1381775Y470208D01*
X1382705Y468958D01*
X1383325Y467500D01*
X1383635Y465833D01*
Y464167D01*
X1383325Y462500D01*
X1382705Y461042D01*
X1381775Y459791D01*
X1380690Y458958D01*
X1379450Y458750D01*
G01X1387820D02*
Y471250D01*
X1391850Y460833D01*
X1395880Y471250D01*
Y458750D01*
G01X1108975Y433750D02*
X1112850Y446250D01*
X1116725Y433750D01*
G01X1115330Y438125D02*
X1110370D01*
G01X1122150Y446250D02*
Y433750D01*
X1128350D01*
G01X1134550Y446250D02*
Y433750D01*
X1140750D01*
G01X1159040Y446250D02*
Y437292D01*
X1159660Y435416D01*
X1160900Y434167D01*
X1162450Y433750D01*
X1164000Y434167D01*
X1165240Y435416D01*
X1165860Y437292D01*
Y446250D01*
G01X1171285Y433750D02*
Y446250D01*
X1178415Y433750D01*
Y446250D01*
G01X1185390D02*
X1189110D01*
G01X1187250D02*
Y433750D01*
G01X1185390D02*
X1189110D01*
G01X1199650Y446250D02*
Y433750D01*
G01X1196085Y446250D02*
X1203215D01*
G01X1208795Y435416D02*
X1210035Y434375D01*
X1211430Y433750D01*
X1212670D01*
X1213910Y434375D01*
X1214840Y435416D01*
X1215305Y436875D01*
X1214995Y438333D01*
X1214220Y439583D01*
X1212825Y440417D01*
X1210965Y440833D01*
X1209880Y441667D01*
X1209415Y443125D01*
X1209725Y444583D01*
X1210500Y445625D01*
X1211585Y446250D01*
X1212670D01*
X1213755Y445833D01*
X1214685Y444792D01*
G01X1232975Y433750D02*
X1236850Y446250D01*
X1240725Y433750D01*
G01X1239330Y438125D02*
X1234370D01*
G01X1246150Y433750D02*
Y446250D01*
X1250025D01*
X1251265Y445625D01*
X1252040Y444792D01*
X1252350Y443125D01*
X1252040Y441458D01*
X1251110Y440417D01*
X1250025Y439792D01*
X1246150D01*
G01X1250025D02*
X1252350Y433750D01*
G01X1264750D02*
X1258550D01*
Y446250D01*
X1264750D01*
G01X1262270Y440208D02*
X1258550D01*
G01X1284590Y446250D02*
X1288310D01*
G01X1286450D02*
Y433750D01*
G01X1284590D02*
X1288310D01*
G01X1295285D02*
Y446250D01*
X1302415Y433750D01*
Y446250D01*
G01X1319620Y433750D02*
Y446250D01*
X1323650Y435833D01*
X1327680Y446250D01*
Y433750D01*
G01X1334190Y446250D02*
X1337910D01*
G01X1336050D02*
Y433750D01*
G01X1334190D02*
X1337910D01*
G01X1345350Y446250D02*
Y433750D01*
X1351550D01*
G01X1357595Y435416D02*
X1358835Y434375D01*
X1360230Y433750D01*
X1361470D01*
X1362710Y434375D01*
X1363640Y435416D01*
X1364105Y436875D01*
X1363795Y438333D01*
X1363020Y439583D01*
X1361625Y440417D01*
X1359765Y440833D01*
X1358680Y441667D01*
X1358215Y443125D01*
X1358525Y444583D01*
X1359300Y445625D01*
X1360385Y446250D01*
X1361470D01*
X1362555Y445833D01*
X1363485Y444792D01*
G01X1116849Y888302D02*
Y894602D01*
X1118729D01*
X1119356Y894287D01*
X1119826Y893552D01*
X1119983Y892712D01*
X1119826Y891872D01*
X1119434Y891242D01*
X1118729Y890927D01*
X1116849D01*
G01X1124716Y888302D02*
Y894602D01*
G01X1129841Y891137D02*
X1132348D01*
X1132113Y891872D01*
X1131721Y892292D01*
X1131173Y892502D01*
X1130624Y892397D01*
X1130154Y892082D01*
X1129841Y891347D01*
X1129684Y890717D01*
Y890087D01*
X1129841Y889457D01*
X1130233Y888827D01*
X1130703Y888407D01*
X1131251Y888302D01*
X1131799Y888512D01*
X1132348Y889142D01*
G01X1138726Y888302D02*
Y892502D01*
G01Y891767D02*
X1138413Y892187D01*
X1137943Y892397D01*
X1137394Y892502D01*
X1136846Y892292D01*
X1136376Y891872D01*
X1136063Y891242D01*
X1135906Y890402D01*
X1136063Y889562D01*
X1136376Y888932D01*
X1136846Y888512D01*
X1137394Y888302D01*
X1137943Y888407D01*
X1138413Y888722D01*
X1138726Y889142D01*
G01X1142441Y889037D02*
X1142833Y888617D01*
X1143381Y888302D01*
X1143851D01*
X1144321Y888512D01*
X1144634Y888827D01*
X1144791Y889247D01*
X1144713Y889877D01*
X1144399Y890192D01*
X1142989Y890822D01*
X1142676Y891557D01*
X1142833Y892082D01*
X1143146Y892397D01*
X1143616Y892502D01*
X1144086Y892397D01*
X1144556Y892082D01*
G01X1148741Y891137D02*
X1151248D01*
X1151013Y891872D01*
X1150621Y892292D01*
X1150073Y892502D01*
X1149524Y892397D01*
X1149054Y892082D01*
X1148741Y891347D01*
X1148584Y890717D01*
Y890087D01*
X1148741Y889457D01*
X1149133Y888827D01*
X1149603Y888407D01*
X1150151Y888302D01*
X1150699Y888512D01*
X1151248Y889142D01*
G01X1161419Y888302D02*
Y892502D01*
G01Y891662D02*
X1161811Y892082D01*
X1162203Y892397D01*
X1162751Y892502D01*
X1163143Y892397D01*
X1163613Y892082D01*
G01X1167641Y891137D02*
X1170148D01*
X1169913Y891872D01*
X1169521Y892292D01*
X1168973Y892502D01*
X1168424Y892397D01*
X1167954Y892082D01*
X1167641Y891347D01*
X1167484Y890717D01*
Y890087D01*
X1167641Y889457D01*
X1168033Y888827D01*
X1168503Y888407D01*
X1169051Y888302D01*
X1169599Y888512D01*
X1170148Y889142D01*
G01X1174646Y888302D02*
Y893657D01*
X1174803Y894182D01*
X1175116Y894497D01*
X1175586Y894602D01*
X1176056Y894392D01*
X1176291Y893867D01*
G01X1175351Y892082D02*
X1173784D01*
G01X1180241Y891137D02*
X1182748D01*
X1182513Y891872D01*
X1182121Y892292D01*
X1181573Y892502D01*
X1181024Y892397D01*
X1180554Y892082D01*
X1180241Y891347D01*
X1180084Y890717D01*
Y890087D01*
X1180241Y889457D01*
X1180633Y888827D01*
X1181103Y888407D01*
X1181651Y888302D01*
X1182199Y888512D01*
X1182748Y889142D01*
G01X1186619Y888302D02*
Y892502D01*
G01Y891662D02*
X1187011Y892082D01*
X1187403Y892397D01*
X1187951Y892502D01*
X1188343Y892397D01*
X1188813Y892082D01*
G01X1200316Y894602D02*
Y888302D01*
G01X1199219Y892502D02*
X1201413D01*
G01X1206616Y888302D02*
X1206146Y888407D01*
X1205676Y888827D01*
X1205363Y889562D01*
X1205206Y890402D01*
X1205363Y891242D01*
X1205676Y891977D01*
X1206146Y892397D01*
X1206616Y892502D01*
X1207086Y892397D01*
X1207556Y891977D01*
X1207869Y891242D01*
X1207948Y890402D01*
X1207869Y889562D01*
X1207556Y888827D01*
X1207086Y888407D01*
X1206616Y888302D01*
G01X1218041Y889037D02*
X1218433Y888617D01*
X1218981Y888302D01*
X1219451D01*
X1219921Y888512D01*
X1220234Y888827D01*
X1220391Y889247D01*
X1220313Y889877D01*
X1219999Y890192D01*
X1218589Y890822D01*
X1218276Y891557D01*
X1218433Y892082D01*
X1218746Y892397D01*
X1219216Y892502D01*
X1219686Y892397D01*
X1220156Y892082D01*
G01X1225516Y894602D02*
Y888302D01*
G01X1224419Y892502D02*
X1226613D01*
G01X1233226Y888302D02*
Y892502D01*
G01Y891767D02*
X1232913Y892187D01*
X1232443Y892397D01*
X1231894Y892502D01*
X1231346Y892292D01*
X1230876Y891872D01*
X1230563Y891242D01*
X1230406Y890402D01*
X1230563Y889562D01*
X1230876Y888932D01*
X1231346Y888512D01*
X1231894Y888302D01*
X1232443Y888407D01*
X1232913Y888722D01*
X1233226Y889142D01*
G01X1239369Y891977D02*
X1238821Y892397D01*
X1238351Y892502D01*
X1237724Y892292D01*
X1237254Y891872D01*
X1236941Y891137D01*
X1236863Y890402D01*
X1236941Y889667D01*
X1237254Y889037D01*
X1237724Y888512D01*
X1238351Y888302D01*
X1238899Y888512D01*
X1239369Y888932D01*
G01X1243084Y888302D02*
Y894602D01*
G01X1245591Y892502D02*
X1243084Y890087D01*
G01X1244103Y891032D02*
X1245748Y888302D01*
G01X1249384Y892502D02*
Y889562D01*
X1249698Y888827D01*
X1250168Y888407D01*
X1250716Y888302D01*
X1251264Y888407D01*
X1251734Y888827D01*
X1252048Y889562D01*
G01Y888302D02*
Y892502D01*
G01X1255606Y886202D02*
Y892502D01*
G01Y891557D02*
X1255998Y892082D01*
X1256389Y892397D01*
X1257016Y892502D01*
X1257564Y892397D01*
X1258113Y891872D01*
X1258348Y891137D01*
X1258426Y890402D01*
X1258348Y889667D01*
X1258113Y888932D01*
X1257643Y888512D01*
X1257016Y888302D01*
X1256468Y888407D01*
X1255919Y888722D01*
X1255606Y889142D01*
G01X1269146Y888302D02*
Y893657D01*
X1269303Y894182D01*
X1269616Y894497D01*
X1270086Y894602D01*
X1270556Y894392D01*
X1270791Y893867D01*
G01X1269851Y892082D02*
X1268284D01*
G01X1275916Y892502D02*
Y888302D01*
G01Y894182D02*
X1275759Y894287D01*
Y894497D01*
X1275916Y894602D01*
X1276073Y894497D01*
Y894287D01*
X1275916Y894182D01*
G01X1282216Y888302D02*
Y894602D01*
G01X1287341Y891137D02*
X1289848D01*
X1289613Y891872D01*
X1289221Y892292D01*
X1288673Y892502D01*
X1288124Y892397D01*
X1287654Y892082D01*
X1287341Y891347D01*
X1287184Y890717D01*
Y890087D01*
X1287341Y889457D01*
X1287733Y888827D01*
X1288203Y888407D01*
X1288751Y888302D01*
X1289299Y888512D01*
X1289848Y889142D01*
G01X1294816Y888092D02*
X1294659Y888197D01*
Y888407D01*
X1294816Y888512D01*
X1294973Y888407D01*
Y888197D01*
X1294816Y888092D01*
G01X1116662Y901692D02*
Y907992D01*
X1118699Y902742D01*
X1120736Y907992D01*
Y901692D01*
G01X1126409D02*
Y905892D01*
G01Y905157D02*
X1126096Y905577D01*
X1125626Y905787D01*
X1125077Y905892D01*
X1124529Y905682D01*
X1124059Y905262D01*
X1123746Y904632D01*
X1123589Y903792D01*
X1123746Y902952D01*
X1124059Y902322D01*
X1124529Y901902D01*
X1125077Y901692D01*
X1125626Y901797D01*
X1126096Y902112D01*
X1126409Y902532D01*
G01X1130124Y902427D02*
X1130516Y902007D01*
X1131064Y901692D01*
X1131534D01*
X1132004Y901902D01*
X1132317Y902217D01*
X1132474Y902637D01*
X1132396Y903267D01*
X1132082Y903582D01*
X1130672Y904212D01*
X1130359Y904947D01*
X1130516Y905472D01*
X1130829Y905787D01*
X1131299Y905892D01*
X1131769Y905787D01*
X1132239Y905472D01*
G01X1136267Y901692D02*
Y907992D01*
G01X1138774Y905892D02*
X1136267Y903477D01*
G01X1137286Y904422D02*
X1138931Y901692D01*
G01X1150199Y907992D02*
Y901692D01*
G01X1149102Y905892D02*
X1151296D01*
G01X1156499Y901692D02*
X1156029Y901797D01*
X1155559Y902217D01*
X1155246Y902952D01*
X1155089Y903792D01*
X1155246Y904632D01*
X1155559Y905367D01*
X1156029Y905787D01*
X1156499Y905892D01*
X1156969Y905787D01*
X1157439Y905367D01*
X1157752Y904632D01*
X1157831Y903792D01*
X1157752Y902952D01*
X1157439Y902217D01*
X1156969Y901797D01*
X1156499Y901692D01*
G01X1167062D02*
Y907992D01*
X1169099Y902742D01*
X1171136Y907992D01*
Y901692D01*
G01X1176809D02*
Y905892D01*
G01Y905157D02*
X1176496Y905577D01*
X1176026Y905787D01*
X1175477Y905892D01*
X1174929Y905682D01*
X1174459Y905262D01*
X1174146Y904632D01*
X1173989Y903792D01*
X1174146Y902952D01*
X1174459Y902322D01*
X1174929Y901902D01*
X1175477Y901692D01*
X1176026Y901797D01*
X1176496Y902112D01*
X1176809Y902532D01*
G01X1180524Y902427D02*
X1180916Y902007D01*
X1181464Y901692D01*
X1181934D01*
X1182404Y901902D01*
X1182717Y902217D01*
X1182874Y902637D01*
X1182796Y903267D01*
X1182482Y903582D01*
X1181072Y904212D01*
X1180759Y904947D01*
X1180916Y905472D01*
X1181229Y905787D01*
X1181699Y905892D01*
X1182169Y905787D01*
X1182639Y905472D01*
G01X1186667Y901692D02*
Y907992D01*
G01X1189174Y905892D02*
X1186667Y903477D01*
G01X1187686Y904422D02*
X1189331Y901692D01*
G01X1200599Y907992D02*
Y901692D01*
G01X1199502Y905892D02*
X1201696D01*
G01X1205567Y901692D02*
Y907992D01*
G01Y904947D02*
X1205959Y905472D01*
X1206351Y905787D01*
X1206977Y905892D01*
X1207447Y905787D01*
X1207996Y905367D01*
X1208231Y904737D01*
Y901692D01*
G01X1213199Y905892D02*
Y901692D01*
G01Y907572D02*
X1213042Y907677D01*
Y907887D01*
X1213199Y907992D01*
X1213356Y907887D01*
Y907677D01*
X1213199Y907572D01*
G01X1220752Y905367D02*
X1220204Y905787D01*
X1219734Y905892D01*
X1219107Y905682D01*
X1218637Y905262D01*
X1218324Y904527D01*
X1218246Y903792D01*
X1218324Y903057D01*
X1218637Y902427D01*
X1219107Y901902D01*
X1219734Y901692D01*
X1220282Y901902D01*
X1220752Y902322D01*
G01X1224467Y901692D02*
Y907992D01*
G01X1226974Y905892D02*
X1224467Y903477D01*
G01X1225486Y904422D02*
X1227131Y901692D01*
G01X1230767D02*
Y905892D01*
G01Y904842D02*
X1231081Y905367D01*
X1231551Y905787D01*
X1232177Y905892D01*
X1232726Y905787D01*
X1233196Y905367D01*
X1233431Y904632D01*
Y901692D01*
G01X1237224Y904527D02*
X1239731D01*
X1239496Y905262D01*
X1239104Y905682D01*
X1238556Y905892D01*
X1238007Y905787D01*
X1237537Y905472D01*
X1237224Y904737D01*
X1237067Y904107D01*
Y903477D01*
X1237224Y902847D01*
X1237616Y902217D01*
X1238086Y901797D01*
X1238634Y901692D01*
X1239182Y901902D01*
X1239731Y902532D01*
G01X1243524Y902427D02*
X1243916Y902007D01*
X1244464Y901692D01*
X1244934D01*
X1245404Y901902D01*
X1245717Y902217D01*
X1245874Y902637D01*
X1245796Y903267D01*
X1245482Y903582D01*
X1244072Y904212D01*
X1243759Y904947D01*
X1243916Y905472D01*
X1244229Y905787D01*
X1244699Y905892D01*
X1245169Y905787D01*
X1245639Y905472D01*
G01X1249824Y902427D02*
X1250216Y902007D01*
X1250764Y901692D01*
X1251234D01*
X1251704Y901902D01*
X1252017Y902217D01*
X1252174Y902637D01*
X1252096Y903267D01*
X1251782Y903582D01*
X1250372Y904212D01*
X1250059Y904947D01*
X1250216Y905472D01*
X1250529Y905787D01*
X1250999Y905892D01*
X1251469Y905787D01*
X1251939Y905472D01*
G01X1131453Y603218D02*
Y609518D01*
X1133333D01*
X1133960Y609203D01*
X1134430Y608468D01*
X1134587Y607628D01*
X1134430Y606788D01*
X1134038Y606158D01*
X1133333Y605843D01*
X1131453D01*
G01X1139320Y603218D02*
Y609518D01*
G01X1144445Y606053D02*
X1146952D01*
X1146717Y606788D01*
X1146325Y607208D01*
X1145777Y607418D01*
X1145228Y607313D01*
X1144758Y606998D01*
X1144445Y606263D01*
X1144288Y605633D01*
Y605003D01*
X1144445Y604373D01*
X1144837Y603743D01*
X1145307Y603323D01*
X1145855Y603218D01*
X1146403Y603428D01*
X1146952Y604058D01*
G01X1153330Y603218D02*
Y607418D01*
G01Y606683D02*
X1153017Y607103D01*
X1152547Y607313D01*
X1151998Y607418D01*
X1151450Y607208D01*
X1150980Y606788D01*
X1150667Y606158D01*
X1150510Y605318D01*
X1150667Y604478D01*
X1150980Y603848D01*
X1151450Y603428D01*
X1151998Y603218D01*
X1152547Y603323D01*
X1153017Y603638D01*
X1153330Y604058D01*
G01X1157045Y603953D02*
X1157437Y603533D01*
X1157985Y603218D01*
X1158455D01*
X1158925Y603428D01*
X1159238Y603743D01*
X1159395Y604163D01*
X1159317Y604793D01*
X1159003Y605108D01*
X1157593Y605738D01*
X1157280Y606473D01*
X1157437Y606998D01*
X1157750Y607313D01*
X1158220Y607418D01*
X1158690Y607313D01*
X1159160Y606998D01*
G01X1163345Y606053D02*
X1165852D01*
X1165617Y606788D01*
X1165225Y607208D01*
X1164677Y607418D01*
X1164128Y607313D01*
X1163658Y606998D01*
X1163345Y606263D01*
X1163188Y605633D01*
Y605003D01*
X1163345Y604373D01*
X1163737Y603743D01*
X1164207Y603323D01*
X1164755Y603218D01*
X1165303Y603428D01*
X1165852Y604058D01*
G01X1176023Y603218D02*
Y607418D01*
G01Y606578D02*
X1176415Y606998D01*
X1176807Y607313D01*
X1177355Y607418D01*
X1177747Y607313D01*
X1178217Y606998D01*
G01X1182245Y606053D02*
X1184752D01*
X1184517Y606788D01*
X1184125Y607208D01*
X1183577Y607418D01*
X1183028Y607313D01*
X1182558Y606998D01*
X1182245Y606263D01*
X1182088Y605633D01*
Y605003D01*
X1182245Y604373D01*
X1182637Y603743D01*
X1183107Y603323D01*
X1183655Y603218D01*
X1184203Y603428D01*
X1184752Y604058D01*
G01X1189250Y603218D02*
Y608573D01*
X1189407Y609098D01*
X1189720Y609413D01*
X1190190Y609518D01*
X1190660Y609308D01*
X1190895Y608783D01*
G01X1189955Y606998D02*
X1188388D01*
G01X1194845Y606053D02*
X1197352D01*
X1197117Y606788D01*
X1196725Y607208D01*
X1196177Y607418D01*
X1195628Y607313D01*
X1195158Y606998D01*
X1194845Y606263D01*
X1194688Y605633D01*
Y605003D01*
X1194845Y604373D01*
X1195237Y603743D01*
X1195707Y603323D01*
X1196255Y603218D01*
X1196803Y603428D01*
X1197352Y604058D01*
G01X1201223Y603218D02*
Y607418D01*
G01Y606578D02*
X1201615Y606998D01*
X1202007Y607313D01*
X1202555Y607418D01*
X1202947Y607313D01*
X1203417Y606998D01*
G01X1214920Y609518D02*
Y603218D01*
G01X1213823Y607418D02*
X1216017D01*
G01X1221220Y603218D02*
X1220750Y603323D01*
X1220280Y603743D01*
X1219967Y604478D01*
X1219810Y605318D01*
X1219967Y606158D01*
X1220280Y606893D01*
X1220750Y607313D01*
X1221220Y607418D01*
X1221690Y607313D01*
X1222160Y606893D01*
X1222473Y606158D01*
X1222552Y605318D01*
X1222473Y604478D01*
X1222160Y603743D01*
X1221690Y603323D01*
X1221220Y603218D01*
G01X1232645Y603953D02*
X1233037Y603533D01*
X1233585Y603218D01*
X1234055D01*
X1234525Y603428D01*
X1234838Y603743D01*
X1234995Y604163D01*
X1234917Y604793D01*
X1234603Y605108D01*
X1233193Y605738D01*
X1232880Y606473D01*
X1233037Y606998D01*
X1233350Y607313D01*
X1233820Y607418D01*
X1234290Y607313D01*
X1234760Y606998D01*
G01X1240120Y609518D02*
Y603218D01*
G01X1239023Y607418D02*
X1241217D01*
G01X1247830Y603218D02*
Y607418D01*
G01Y606683D02*
X1247517Y607103D01*
X1247047Y607313D01*
X1246498Y607418D01*
X1245950Y607208D01*
X1245480Y606788D01*
X1245167Y606158D01*
X1245010Y605318D01*
X1245167Y604478D01*
X1245480Y603848D01*
X1245950Y603428D01*
X1246498Y603218D01*
X1247047Y603323D01*
X1247517Y603638D01*
X1247830Y604058D01*
G01X1253973Y606893D02*
X1253425Y607313D01*
X1252955Y607418D01*
X1252328Y607208D01*
X1251858Y606788D01*
X1251545Y606053D01*
X1251467Y605318D01*
X1251545Y604583D01*
X1251858Y603953D01*
X1252328Y603428D01*
X1252955Y603218D01*
X1253503Y603428D01*
X1253973Y603848D01*
G01X1257688Y603218D02*
Y609518D01*
G01X1260195Y607418D02*
X1257688Y605003D01*
G01X1258707Y605948D02*
X1260352Y603218D01*
G01X1263988Y607418D02*
Y604478D01*
X1264302Y603743D01*
X1264772Y603323D01*
X1265320Y603218D01*
X1265868Y603323D01*
X1266338Y603743D01*
X1266652Y604478D01*
G01Y603218D02*
Y607418D01*
G01X1270210Y601118D02*
Y607418D01*
G01Y606473D02*
X1270602Y606998D01*
X1270993Y607313D01*
X1271620Y607418D01*
X1272168Y607313D01*
X1272717Y606788D01*
X1272952Y606053D01*
X1273030Y605318D01*
X1272952Y604583D01*
X1272717Y603848D01*
X1272247Y603428D01*
X1271620Y603218D01*
X1271072Y603323D01*
X1270523Y603638D01*
X1270210Y604058D01*
G01X1283750Y603218D02*
Y608573D01*
X1283907Y609098D01*
X1284220Y609413D01*
X1284690Y609518D01*
X1285160Y609308D01*
X1285395Y608783D01*
G01X1284455Y606998D02*
X1282888D01*
G01X1290520Y607418D02*
Y603218D01*
G01Y609098D02*
X1290363Y609203D01*
Y609413D01*
X1290520Y609518D01*
X1290677Y609413D01*
Y609203D01*
X1290520Y609098D01*
G01X1296820Y603218D02*
Y609518D01*
G01X1301945Y606053D02*
X1304452D01*
X1304217Y606788D01*
X1303825Y607208D01*
X1303277Y607418D01*
X1302728Y607313D01*
X1302258Y606998D01*
X1301945Y606263D01*
X1301788Y605633D01*
Y605003D01*
X1301945Y604373D01*
X1302337Y603743D01*
X1302807Y603323D01*
X1303355Y603218D01*
X1303903Y603428D01*
X1304452Y604058D01*
G01X1309420Y603008D02*
X1309263Y603113D01*
Y603323D01*
X1309420Y603428D01*
X1309577Y603323D01*
Y603113D01*
X1309420Y603008D01*
G01X1131324Y617405D02*
Y623705D01*
X1133204D01*
X1133831Y623390D01*
X1134301Y622655D01*
X1134458Y621815D01*
X1134301Y620975D01*
X1133909Y620345D01*
X1133204Y620030D01*
X1131324D01*
G01X1140601Y617405D02*
Y621605D01*
G01Y620870D02*
X1140288Y621290D01*
X1139818Y621500D01*
X1139269Y621605D01*
X1138721Y621395D01*
X1138251Y620975D01*
X1137938Y620345D01*
X1137781Y619505D01*
X1137938Y618665D01*
X1138251Y618035D01*
X1138721Y617615D01*
X1139269Y617405D01*
X1139818Y617510D01*
X1140288Y617825D01*
X1140601Y618245D01*
G01X1146901Y623705D02*
Y617405D01*
G01Y618350D02*
X1146588Y617825D01*
X1146118Y617510D01*
X1145569Y617405D01*
X1144943Y617615D01*
X1144473Y618140D01*
X1144159Y618770D01*
X1144081Y619505D01*
X1144159Y620240D01*
X1144473Y620870D01*
X1144943Y621395D01*
X1145569Y621605D01*
X1146118Y621500D01*
X1146509Y621290D01*
X1146901Y620870D01*
G01X1158091Y623705D02*
Y617405D01*
G01X1156994Y621605D02*
X1159188D01*
G01X1164391Y617405D02*
X1163921Y617510D01*
X1163451Y617930D01*
X1163138Y618665D01*
X1162981Y619505D01*
X1163138Y620345D01*
X1163451Y621080D01*
X1163921Y621500D01*
X1164391Y621605D01*
X1164861Y621500D01*
X1165331Y621080D01*
X1165644Y620345D01*
X1165723Y619505D01*
X1165644Y618665D01*
X1165331Y617930D01*
X1164861Y617510D01*
X1164391Y617405D01*
G01X1175424D02*
Y623705D01*
X1177304D01*
X1177931Y623390D01*
X1178401Y622655D01*
X1178558Y621815D01*
X1178401Y620975D01*
X1178009Y620345D01*
X1177304Y620030D01*
X1175424D01*
G01X1184701Y617405D02*
Y621605D01*
G01Y620870D02*
X1184388Y621290D01*
X1183918Y621500D01*
X1183369Y621605D01*
X1182821Y621395D01*
X1182351Y620975D01*
X1182038Y620345D01*
X1181881Y619505D01*
X1182038Y618665D01*
X1182351Y618035D01*
X1182821Y617615D01*
X1183369Y617405D01*
X1183918Y617510D01*
X1184388Y617825D01*
X1184701Y618245D01*
G01X1191001Y623705D02*
Y617405D01*
G01Y618350D02*
X1190688Y617825D01*
X1190218Y617510D01*
X1189669Y617405D01*
X1189043Y617615D01*
X1188573Y618140D01*
X1188259Y618770D01*
X1188181Y619505D01*
X1188259Y620240D01*
X1188573Y620870D01*
X1189043Y621395D01*
X1189669Y621605D01*
X1190218Y621500D01*
X1190609Y621290D01*
X1191001Y620870D01*
G01X1202191Y623705D02*
Y617405D01*
G01X1201094Y621605D02*
X1203288D01*
G01X1207159Y617405D02*
Y623705D01*
G01Y620660D02*
X1207551Y621185D01*
X1207943Y621500D01*
X1208569Y621605D01*
X1209039Y621500D01*
X1209588Y621080D01*
X1209823Y620450D01*
Y617405D01*
G01X1214791Y621605D02*
Y617405D01*
G01Y623285D02*
X1214634Y623390D01*
Y623600D01*
X1214791Y623705D01*
X1214948Y623600D01*
Y623390D01*
X1214791Y623285D01*
G01X1222344Y621080D02*
X1221796Y621500D01*
X1221326Y621605D01*
X1220699Y621395D01*
X1220229Y620975D01*
X1219916Y620240D01*
X1219838Y619505D01*
X1219916Y618770D01*
X1220229Y618140D01*
X1220699Y617615D01*
X1221326Y617405D01*
X1221874Y617615D01*
X1222344Y618035D01*
G01X1226059Y617405D02*
Y623705D01*
G01X1228566Y621605D02*
X1226059Y619190D01*
G01X1227078Y620135D02*
X1228723Y617405D01*
G01X1232359D02*
Y621605D01*
G01Y620555D02*
X1232673Y621080D01*
X1233143Y621500D01*
X1233769Y621605D01*
X1234318Y621500D01*
X1234788Y621080D01*
X1235023Y620345D01*
Y617405D01*
G01X1238816Y620240D02*
X1241323D01*
X1241088Y620975D01*
X1240696Y621395D01*
X1240148Y621605D01*
X1239599Y621500D01*
X1239129Y621185D01*
X1238816Y620450D01*
X1238659Y619820D01*
Y619190D01*
X1238816Y618560D01*
X1239208Y617930D01*
X1239678Y617510D01*
X1240226Y617405D01*
X1240774Y617615D01*
X1241323Y618245D01*
G01X1245116Y618140D02*
X1245508Y617720D01*
X1246056Y617405D01*
X1246526D01*
X1246996Y617615D01*
X1247309Y617930D01*
X1247466Y618350D01*
X1247388Y618980D01*
X1247074Y619295D01*
X1245664Y619925D01*
X1245351Y620660D01*
X1245508Y621185D01*
X1245821Y621500D01*
X1246291Y621605D01*
X1246761Y621500D01*
X1247231Y621185D01*
G01X1251416Y618140D02*
X1251808Y617720D01*
X1252356Y617405D01*
X1252826D01*
X1253296Y617615D01*
X1253609Y617930D01*
X1253766Y618350D01*
X1253688Y618980D01*
X1253374Y619295D01*
X1251964Y619925D01*
X1251651Y620660D01*
X1251808Y621185D01*
X1252121Y621500D01*
X1252591Y621605D01*
X1253061Y621500D01*
X1253531Y621185D01*
G01X1150641Y928705D02*
X1146641D01*
Y936705D01*
X1150641D01*
G01X1149041Y932838D02*
X1146641D01*
G01X1158441Y936705D02*
Y928705D01*
G01Y929905D02*
X1158041Y929238D01*
X1157441Y928838D01*
X1156741Y928705D01*
X1155941Y928972D01*
X1155341Y929638D01*
X1154941Y930438D01*
X1154841Y931372D01*
X1154941Y932305D01*
X1155341Y933105D01*
X1155941Y933772D01*
X1156741Y934038D01*
X1157441Y933905D01*
X1157941Y933638D01*
X1158441Y933105D01*
G01X1163241Y926705D02*
X1163941Y926172D01*
X1164741Y926038D01*
X1165441Y926172D01*
X1166041Y926838D01*
X1166441Y927772D01*
Y934038D01*
G01Y932972D02*
X1166041Y933505D01*
X1165441Y933905D01*
X1164741Y934038D01*
X1163941Y933772D01*
X1163441Y933238D01*
X1163041Y932305D01*
X1162841Y931372D01*
X1162941Y930572D01*
X1163341Y929638D01*
X1163941Y928972D01*
X1164741Y928705D01*
X1165341Y928838D01*
X1166041Y929372D01*
X1166441Y929905D01*
G01X1171141Y932305D02*
X1174341D01*
X1174041Y933238D01*
X1173541Y933772D01*
X1172841Y934038D01*
X1172141Y933905D01*
X1171541Y933505D01*
X1171141Y932572D01*
X1170941Y931771D01*
Y930972D01*
X1171141Y930172D01*
X1171641Y929372D01*
X1172241Y928838D01*
X1172941Y928705D01*
X1173641Y928972D01*
X1174341Y929771D01*
G01X1190841Y936038D02*
X1190241Y936438D01*
X1189541Y936705D01*
X1188741D01*
X1187841Y936305D01*
X1187141Y935638D01*
X1186641Y934838D01*
X1186241Y933505D01*
X1186141Y932305D01*
X1186341Y931105D01*
X1186641Y930305D01*
X1187241Y929505D01*
X1187941Y928972D01*
X1188641Y928705D01*
X1189341D01*
X1190041Y928972D01*
X1190641Y929372D01*
X1191141Y929905D01*
G01X1196641Y928705D02*
X1196041Y928838D01*
X1195441Y929372D01*
X1195041Y930305D01*
X1194841Y931372D01*
X1195041Y932438D01*
X1195441Y933372D01*
X1196041Y933905D01*
X1196641Y934038D01*
X1197241Y933905D01*
X1197841Y933372D01*
X1198241Y932438D01*
X1198341Y931372D01*
X1198241Y930305D01*
X1197841Y929372D01*
X1197241Y928838D01*
X1196641Y928705D01*
G01X1202941D02*
Y934038D01*
G01Y932705D02*
X1203341Y933372D01*
X1203941Y933905D01*
X1204741Y934038D01*
X1205441Y933905D01*
X1206041Y933372D01*
X1206341Y932438D01*
Y928705D01*
G01X1210941D02*
Y934038D01*
G01Y932705D02*
X1211341Y933372D01*
X1211941Y933905D01*
X1212741Y934038D01*
X1213441Y933905D01*
X1214041Y933372D01*
X1214341Y932438D01*
Y928705D01*
G01X1219141Y932305D02*
X1222341D01*
X1222041Y933238D01*
X1221541Y933772D01*
X1220841Y934038D01*
X1220141Y933905D01*
X1219541Y933505D01*
X1219141Y932572D01*
X1218941Y931771D01*
Y930972D01*
X1219141Y930172D01*
X1219641Y929372D01*
X1220241Y928838D01*
X1220941Y928705D01*
X1221641Y928972D01*
X1222341Y929771D01*
G01X1230241Y933372D02*
X1229541Y933905D01*
X1228941Y934038D01*
X1228141Y933772D01*
X1227541Y933238D01*
X1227141Y932305D01*
X1227041Y931372D01*
X1227141Y930438D01*
X1227541Y929638D01*
X1228141Y928972D01*
X1228941Y928705D01*
X1229641Y928972D01*
X1230241Y929505D01*
G01X1236641Y936705D02*
Y928705D01*
G01X1235241Y934038D02*
X1238041D01*
G01X1244641Y928705D02*
X1244041Y928838D01*
X1243441Y929372D01*
X1243041Y930305D01*
X1242841Y931372D01*
X1243041Y932438D01*
X1243441Y933372D01*
X1244041Y933905D01*
X1244641Y934038D01*
X1245241Y933905D01*
X1245841Y933372D01*
X1246241Y932438D01*
X1246341Y931372D01*
X1246241Y930305D01*
X1245841Y929372D01*
X1245241Y928838D01*
X1244641Y928705D01*
G01X1251241D02*
Y934038D01*
G01Y932972D02*
X1251741Y933505D01*
X1252241Y933905D01*
X1252941Y934038D01*
X1253441Y933905D01*
X1254041Y933505D01*
G01X1156250Y421250D02*
Y408750D01*
G01X1152685Y421250D02*
X1159815D01*
G01X1168650Y408750D02*
X1167410Y408958D01*
X1166325Y409791D01*
X1165395Y411042D01*
X1164775Y412500D01*
X1164465Y414167D01*
Y415833D01*
X1164775Y417500D01*
X1165395Y418958D01*
X1166325Y420208D01*
X1167410Y421042D01*
X1168650Y421250D01*
X1169890Y421042D01*
X1170975Y420208D01*
X1171905Y418958D01*
X1172525Y417500D01*
X1172835Y415833D01*
Y414167D01*
X1172525Y412500D01*
X1171905Y411042D01*
X1170975Y409791D01*
X1169890Y408958D01*
X1168650Y408750D01*
G01X1177950Y421250D02*
Y408750D01*
X1184150D01*
G01X1196550D02*
X1190350D01*
Y421250D01*
X1196550D01*
G01X1194070Y415208D02*
X1190350D01*
G01X1202750Y408750D02*
Y421250D01*
X1206625D01*
X1207865Y420625D01*
X1208640Y419792D01*
X1208950Y418125D01*
X1208640Y416458D01*
X1207710Y415417D01*
X1206625Y414792D01*
X1202750D01*
G01X1206625D02*
X1208950Y408750D01*
G01X1214375D02*
X1218250Y421250D01*
X1222125Y408750D01*
G01X1220730Y413125D02*
X1215770D01*
G01X1227085Y408750D02*
Y421250D01*
X1234215Y408750D01*
Y421250D01*
G01X1246460Y420208D02*
X1245530Y420833D01*
X1244445Y421250D01*
X1243205D01*
X1241810Y420625D01*
X1240725Y419583D01*
X1239950Y418333D01*
X1239330Y416250D01*
X1239175Y414375D01*
X1239485Y412500D01*
X1239950Y411250D01*
X1240880Y410000D01*
X1241965Y409167D01*
X1243050Y408750D01*
X1244135D01*
X1245220Y409167D01*
X1246150Y409791D01*
X1246925Y410625D01*
G01X1258550Y408750D02*
X1252350D01*
Y421250D01*
X1258550D01*
G01X1256070Y415208D02*
X1252350D01*
G01X1263200Y404583D02*
X1272500D01*
G01X1276840Y408750D02*
Y421250D01*
X1279940D01*
X1281180Y420625D01*
X1282110Y419792D01*
X1282885Y418542D01*
X1283505Y417083D01*
X1283660Y415000D01*
X1283505Y412917D01*
X1282885Y411458D01*
X1282110Y410208D01*
X1281180Y409375D01*
X1279940Y408750D01*
X1276840D01*
G01X1289550D02*
Y421250D01*
X1293425D01*
X1294665Y420625D01*
X1295440Y419792D01*
X1295750Y418125D01*
X1295440Y416458D01*
X1294510Y415417D01*
X1293425Y414792D01*
X1289550D01*
G01X1293425D02*
X1295750Y408750D01*
G01X1303190Y421250D02*
X1306910D01*
G01X1305050D02*
Y408750D01*
G01X1303190D02*
X1306910D01*
G01X1314350Y421250D02*
Y408750D01*
X1320550D01*
G01X1326750Y421250D02*
Y408750D01*
X1332950D01*
G01X1173741Y637605D02*
X1158741D01*
G01X1155824Y878736D02*
X1170824D01*
G01X1179345Y-124058D02*
X1183065D01*
G01X1181050Y-121350D02*
Y-126767D01*
G01X1193450Y-128225D02*
Y-115725D01*
X1191590Y-118225D01*
G01Y-128225D02*
X1195310D01*
G01X1205850Y-128642D02*
X1205540Y-128433D01*
Y-128017D01*
X1205850Y-127808D01*
X1206160Y-128017D01*
Y-128433D01*
X1205850Y-128642D01*
G01X1215615Y-126767D02*
X1216700Y-127808D01*
X1217940Y-128225D01*
X1219180Y-127808D01*
X1220265Y-126559D01*
X1221040Y-124683D01*
X1221350Y-122808D01*
Y-120517D01*
X1221040Y-118642D01*
X1220265Y-116975D01*
X1219335Y-116142D01*
X1218250Y-115725D01*
X1217010Y-116142D01*
X1216080Y-116975D01*
X1215460Y-118225D01*
X1215150Y-119892D01*
X1215460Y-121350D01*
X1216235Y-122808D01*
X1217165Y-123642D01*
X1218250Y-123850D01*
X1219490Y-123434D01*
X1220420Y-122392D01*
X1221350Y-120517D01*
G01X1227705Y-123017D02*
X1228790Y-121558D01*
X1229720Y-120725D01*
X1230960Y-120308D01*
X1232045Y-120725D01*
X1232820Y-121558D01*
X1233440Y-122808D01*
X1233595Y-124267D01*
X1233440Y-125517D01*
X1232820Y-126767D01*
X1231890Y-127808D01*
X1230805Y-128225D01*
X1229565Y-127808D01*
X1228480Y-126559D01*
X1227860Y-124683D01*
X1227705Y-122600D01*
X1228015Y-119892D01*
X1228480Y-118433D01*
X1229255Y-116975D01*
X1230340Y-115933D01*
X1231425Y-115725D01*
X1232510Y-116142D01*
X1233285Y-117183D01*
G01X1240260Y-128642D02*
X1245840Y-115725D01*
G01X1253435Y-124058D02*
X1257465D01*
G01X1267850Y-128225D02*
Y-115725D01*
X1265990Y-118225D01*
G01Y-128225D02*
X1269710D01*
G01X1280250Y-128642D02*
X1279940Y-128433D01*
Y-128017D01*
X1280250Y-127808D01*
X1280560Y-128017D01*
Y-128433D01*
X1280250Y-128642D01*
G01X1290015Y-126767D02*
X1291100Y-127808D01*
X1292340Y-128225D01*
X1293580Y-127808D01*
X1294665Y-126559D01*
X1295440Y-124683D01*
X1295750Y-122808D01*
Y-120517D01*
X1295440Y-118642D01*
X1294665Y-116975D01*
X1293735Y-116142D01*
X1292650Y-115725D01*
X1291410Y-116142D01*
X1290480Y-116975D01*
X1289860Y-118225D01*
X1289550Y-119892D01*
X1289860Y-121350D01*
X1290635Y-122808D01*
X1291565Y-123642D01*
X1292650Y-123850D01*
X1293890Y-123434D01*
X1294820Y-122392D01*
X1295750Y-120517D01*
G01X1302105Y-123017D02*
X1303190Y-121558D01*
X1304120Y-120725D01*
X1305360Y-120308D01*
X1306445Y-120725D01*
X1307220Y-121558D01*
X1307840Y-122808D01*
X1307995Y-124267D01*
X1307840Y-125517D01*
X1307220Y-126767D01*
X1306290Y-127808D01*
X1305205Y-128225D01*
X1303965Y-127808D01*
X1302880Y-126559D01*
X1302260Y-124683D01*
X1302105Y-122600D01*
X1302415Y-119892D01*
X1302880Y-118433D01*
X1303655Y-116975D01*
X1304740Y-115933D01*
X1305825Y-115725D01*
X1306910Y-116142D01*
X1307685Y-117183D01*
G01X1179345Y-95708D02*
X1183065D01*
G01X1181050Y-93000D02*
Y-98417D01*
G01X1193450Y-99875D02*
Y-87375D01*
X1191590Y-89875D01*
G01Y-99875D02*
X1195310D01*
G01X1205850Y-100292D02*
X1205540Y-100083D01*
Y-99667D01*
X1205850Y-99458D01*
X1206160Y-99667D01*
Y-100083D01*
X1205850Y-100292D01*
G01X1215615Y-98417D02*
X1216700Y-99458D01*
X1217940Y-99875D01*
X1219180Y-99458D01*
X1220265Y-98209D01*
X1221040Y-96333D01*
X1221350Y-94458D01*
Y-92167D01*
X1221040Y-90292D01*
X1220265Y-88625D01*
X1219335Y-87792D01*
X1218250Y-87375D01*
X1217010Y-87792D01*
X1216080Y-88625D01*
X1215460Y-89875D01*
X1215150Y-91542D01*
X1215460Y-93000D01*
X1216235Y-94458D01*
X1217165Y-95292D01*
X1218250Y-95500D01*
X1219490Y-95084D01*
X1220420Y-94042D01*
X1221350Y-92167D01*
G01X1227705Y-94667D02*
X1228790Y-93208D01*
X1229720Y-92375D01*
X1230960Y-91958D01*
X1232045Y-92375D01*
X1232820Y-93208D01*
X1233440Y-94458D01*
X1233595Y-95917D01*
X1233440Y-97167D01*
X1232820Y-98417D01*
X1231890Y-99458D01*
X1230805Y-99875D01*
X1229565Y-99458D01*
X1228480Y-98209D01*
X1227860Y-96333D01*
X1227705Y-94250D01*
X1228015Y-91542D01*
X1228480Y-90083D01*
X1229255Y-88625D01*
X1230340Y-87583D01*
X1231425Y-87375D01*
X1232510Y-87792D01*
X1233285Y-88833D01*
G01X1240260Y-100292D02*
X1245840Y-87375D01*
G01X1253435Y-95708D02*
X1257465D01*
G01X1267850Y-99875D02*
Y-87375D01*
X1265990Y-89875D01*
G01Y-99875D02*
X1269710D01*
G01X1280250Y-100292D02*
X1279940Y-100083D01*
Y-99667D01*
X1280250Y-99458D01*
X1280560Y-99667D01*
Y-100083D01*
X1280250Y-100292D01*
G01X1290015Y-98417D02*
X1291100Y-99458D01*
X1292340Y-99875D01*
X1293580Y-99458D01*
X1294665Y-98209D01*
X1295440Y-96333D01*
X1295750Y-94458D01*
Y-92167D01*
X1295440Y-90292D01*
X1294665Y-88625D01*
X1293735Y-87792D01*
X1292650Y-87375D01*
X1291410Y-87792D01*
X1290480Y-88625D01*
X1289860Y-89875D01*
X1289550Y-91542D01*
X1289860Y-93000D01*
X1290635Y-94458D01*
X1291565Y-95292D01*
X1292650Y-95500D01*
X1293890Y-95084D01*
X1294820Y-94042D01*
X1295750Y-92167D01*
G01X1302105Y-94667D02*
X1303190Y-93208D01*
X1304120Y-92375D01*
X1305360Y-91958D01*
X1306445Y-92375D01*
X1307220Y-93208D01*
X1307840Y-94458D01*
X1307995Y-95917D01*
X1307840Y-97167D01*
X1307220Y-98417D01*
X1306290Y-99458D01*
X1305205Y-99875D01*
X1303965Y-99458D01*
X1302880Y-98209D01*
X1302260Y-96333D01*
X1302105Y-94250D01*
X1302415Y-91542D01*
X1302880Y-90083D01*
X1303655Y-88625D01*
X1304740Y-87583D01*
X1305825Y-87375D01*
X1306910Y-87792D01*
X1307685Y-88833D01*
G01X1173741Y680605D02*
Y632605D01*
G01Y637605D02*
X1168741Y639105D01*
Y636105D01*
X1173741Y637605D01*
G01X1170741Y848325D02*
Y746605D01*
X1173741D01*
Y686605D01*
X1178741Y666605D01*
X1188741D01*
X1193741Y686605D01*
Y746605D01*
X1196741D01*
Y851205D01*
G01X1170824Y855736D02*
Y883736D01*
G01Y878736D02*
X1165824Y877236D01*
Y880236D01*
X1170824Y878736D01*
G01X1191745Y-180758D02*
X1195465D01*
G01X1193450Y-178050D02*
Y-183467D01*
G01X1207710Y-184925D02*
Y-172425D01*
X1201975Y-181383D01*
X1209725D01*
G01X1218250Y-185342D02*
X1217940Y-185133D01*
Y-184717D01*
X1218250Y-184508D01*
X1218560Y-184717D01*
Y-185133D01*
X1218250Y-185342D01*
G01X1230650Y-172425D02*
X1229410Y-172842D01*
X1228480Y-173883D01*
X1227860Y-175133D01*
X1227395Y-176800D01*
X1227240Y-178675D01*
X1227395Y-180550D01*
X1227860Y-182217D01*
X1228480Y-183467D01*
X1229410Y-184508D01*
X1230650Y-184925D01*
X1231890Y-184508D01*
X1232820Y-183467D01*
X1233440Y-182217D01*
X1233905Y-180550D01*
X1234060Y-178675D01*
X1233905Y-176800D01*
X1233440Y-175133D01*
X1232820Y-173883D01*
X1231890Y-172842D01*
X1230650Y-172425D01*
G01X1240260Y-185342D02*
X1245840Y-172425D01*
G01X1253435Y-180758D02*
X1257465D01*
G01X1269710Y-184925D02*
Y-172425D01*
X1263975Y-181383D01*
X1271725D01*
G01X1280250Y-185342D02*
X1279940Y-185133D01*
Y-184717D01*
X1280250Y-184508D01*
X1280560Y-184717D01*
Y-185133D01*
X1280250Y-185342D01*
G01X1292650Y-172425D02*
X1291410Y-172842D01*
X1290480Y-173883D01*
X1289860Y-175133D01*
X1289395Y-176800D01*
X1289240Y-178675D01*
X1289395Y-180550D01*
X1289860Y-182217D01*
X1290480Y-183467D01*
X1291410Y-184508D01*
X1292650Y-184925D01*
X1293890Y-184508D01*
X1294820Y-183467D01*
X1295440Y-182217D01*
X1295905Y-180550D01*
X1296060Y-178675D01*
X1295905Y-176800D01*
X1295440Y-175133D01*
X1294820Y-173883D01*
X1293890Y-172842D01*
X1292650Y-172425D01*
G01X1191745Y-152408D02*
X1195465D01*
G01X1193450Y-149700D02*
Y-155117D01*
G01X1202905Y-146158D02*
X1203835Y-144909D01*
X1204920Y-144283D01*
X1206160Y-144075D01*
X1207710Y-144492D01*
X1208795Y-145533D01*
X1209105Y-146783D01*
X1208950Y-148034D01*
X1208330Y-149075D01*
X1205230Y-151158D01*
X1203835Y-152617D01*
X1202905Y-154700D01*
X1202595Y-156575D01*
X1209105D01*
G01X1218250Y-156992D02*
X1217940Y-156783D01*
Y-156367D01*
X1218250Y-156158D01*
X1218560Y-156367D01*
Y-156783D01*
X1218250Y-156992D01*
G01X1230650Y-144075D02*
X1229410Y-144492D01*
X1228480Y-145533D01*
X1227860Y-146783D01*
X1227395Y-148450D01*
X1227240Y-150325D01*
X1227395Y-152200D01*
X1227860Y-153867D01*
X1228480Y-155117D01*
X1229410Y-156158D01*
X1230650Y-156575D01*
X1231890Y-156158D01*
X1232820Y-155117D01*
X1233440Y-153867D01*
X1233905Y-152200D01*
X1234060Y-150325D01*
X1233905Y-148450D01*
X1233440Y-146783D01*
X1232820Y-145533D01*
X1231890Y-144492D01*
X1230650Y-144075D01*
G01X1240260Y-156992D02*
X1245840Y-144075D01*
G01X1253435Y-152408D02*
X1257465D01*
G01X1267850Y-144075D02*
X1266610Y-144492D01*
X1265680Y-145533D01*
X1265060Y-146783D01*
X1264595Y-148450D01*
X1264440Y-150325D01*
X1264595Y-152200D01*
X1265060Y-153867D01*
X1265680Y-155117D01*
X1266610Y-156158D01*
X1267850Y-156575D01*
X1269090Y-156158D01*
X1270020Y-155117D01*
X1270640Y-153867D01*
X1271105Y-152200D01*
X1271260Y-150325D01*
X1271105Y-148450D01*
X1270640Y-146783D01*
X1270020Y-145533D01*
X1269090Y-144492D01*
X1267850Y-144075D01*
G01X1280250Y-156992D02*
X1279940Y-156783D01*
Y-156367D01*
X1280250Y-156158D01*
X1280560Y-156367D01*
Y-156783D01*
X1280250Y-156992D01*
G01X1292650Y-144075D02*
X1291410Y-144492D01*
X1290480Y-145533D01*
X1289860Y-146783D01*
X1289395Y-148450D01*
X1289240Y-150325D01*
X1289395Y-152200D01*
X1289860Y-153867D01*
X1290480Y-155117D01*
X1291410Y-156158D01*
X1292650Y-156575D01*
X1293890Y-156158D01*
X1294820Y-155117D01*
X1295440Y-153867D01*
X1295905Y-152200D01*
X1296060Y-150325D01*
X1295905Y-148450D01*
X1295440Y-146783D01*
X1294820Y-145533D01*
X1293890Y-144492D01*
X1292650Y-144075D01*
G01X1191745Y-67358D02*
X1195465D01*
G01X1193450Y-64650D02*
Y-70067D01*
G01X1202905Y-61108D02*
X1203835Y-59859D01*
X1204920Y-59233D01*
X1206160Y-59025D01*
X1207710Y-59442D01*
X1208795Y-60483D01*
X1209105Y-61733D01*
X1208950Y-62984D01*
X1208330Y-64025D01*
X1205230Y-66108D01*
X1203835Y-67567D01*
X1202905Y-69650D01*
X1202595Y-71525D01*
X1209105D01*
G01X1218250Y-71942D02*
X1217940Y-71733D01*
Y-71317D01*
X1218250Y-71108D01*
X1218560Y-71317D01*
Y-71733D01*
X1218250Y-71942D01*
G01X1230650Y-59025D02*
X1229410Y-59442D01*
X1228480Y-60483D01*
X1227860Y-61733D01*
X1227395Y-63400D01*
X1227240Y-65275D01*
X1227395Y-67150D01*
X1227860Y-68817D01*
X1228480Y-70067D01*
X1229410Y-71108D01*
X1230650Y-71525D01*
X1231890Y-71108D01*
X1232820Y-70067D01*
X1233440Y-68817D01*
X1233905Y-67150D01*
X1234060Y-65275D01*
X1233905Y-63400D01*
X1233440Y-61733D01*
X1232820Y-60483D01*
X1231890Y-59442D01*
X1230650Y-59025D01*
G01X1240260Y-71942D02*
X1245840Y-59025D01*
G01X1253435Y-67358D02*
X1257465D01*
G01X1264905Y-61108D02*
X1265835Y-59859D01*
X1266920Y-59233D01*
X1268160Y-59025D01*
X1269710Y-59442D01*
X1270795Y-60483D01*
X1271105Y-61733D01*
X1270950Y-62984D01*
X1270330Y-64025D01*
X1267230Y-66108D01*
X1265835Y-67567D01*
X1264905Y-69650D01*
X1264595Y-71525D01*
X1271105D01*
G01X1280250Y-71942D02*
X1279940Y-71733D01*
Y-71317D01*
X1280250Y-71108D01*
X1280560Y-71317D01*
Y-71733D01*
X1280250Y-71942D01*
G01X1292650Y-59025D02*
X1291410Y-59442D01*
X1290480Y-60483D01*
X1289860Y-61733D01*
X1289395Y-63400D01*
X1289240Y-65275D01*
X1289395Y-67150D01*
X1289860Y-68817D01*
X1290480Y-70067D01*
X1291410Y-71108D01*
X1292650Y-71525D01*
X1293890Y-71108D01*
X1294820Y-70067D01*
X1295440Y-68817D01*
X1295905Y-67150D01*
X1296060Y-65275D01*
X1295905Y-63400D01*
X1295440Y-61733D01*
X1294820Y-60483D01*
X1293890Y-59442D01*
X1292650Y-59025D01*
G01X1191745Y-39008D02*
X1195465D01*
G01X1193450Y-36300D02*
Y-41717D01*
G01X1202905Y-32758D02*
X1203835Y-31509D01*
X1204920Y-30883D01*
X1206160Y-30675D01*
X1207710Y-31092D01*
X1208795Y-32133D01*
X1209105Y-33383D01*
X1208950Y-34634D01*
X1208330Y-35675D01*
X1205230Y-37758D01*
X1203835Y-39217D01*
X1202905Y-41300D01*
X1202595Y-43175D01*
X1209105D01*
G01X1218250Y-43592D02*
X1217940Y-43383D01*
Y-42967D01*
X1218250Y-42758D01*
X1218560Y-42967D01*
Y-43383D01*
X1218250Y-43592D01*
G01X1230650Y-30675D02*
X1229410Y-31092D01*
X1228480Y-32133D01*
X1227860Y-33383D01*
X1227395Y-35050D01*
X1227240Y-36925D01*
X1227395Y-38800D01*
X1227860Y-40467D01*
X1228480Y-41717D01*
X1229410Y-42758D01*
X1230650Y-43175D01*
X1231890Y-42758D01*
X1232820Y-41717D01*
X1233440Y-40467D01*
X1233905Y-38800D01*
X1234060Y-36925D01*
X1233905Y-35050D01*
X1233440Y-33383D01*
X1232820Y-32133D01*
X1231890Y-31092D01*
X1230650Y-30675D01*
G01X1240260Y-43592D02*
X1245840Y-30675D01*
G01X1253435Y-39008D02*
X1257465D01*
G01X1264905Y-32758D02*
X1265835Y-31509D01*
X1266920Y-30883D01*
X1268160Y-30675D01*
X1269710Y-31092D01*
X1270795Y-32133D01*
X1271105Y-33383D01*
X1270950Y-34634D01*
X1270330Y-35675D01*
X1267230Y-37758D01*
X1265835Y-39217D01*
X1264905Y-41300D01*
X1264595Y-43175D01*
X1271105D01*
G01X1280250Y-43592D02*
X1279940Y-43383D01*
Y-42967D01*
X1280250Y-42758D01*
X1280560Y-42967D01*
Y-43383D01*
X1280250Y-43592D01*
G01X1292650Y-30675D02*
X1291410Y-31092D01*
X1290480Y-32133D01*
X1289860Y-33383D01*
X1289395Y-35050D01*
X1289240Y-36925D01*
X1289395Y-38800D01*
X1289860Y-40467D01*
X1290480Y-41717D01*
X1291410Y-42758D01*
X1292650Y-43175D01*
X1293890Y-42758D01*
X1294820Y-41717D01*
X1295440Y-40467D01*
X1295905Y-38800D01*
X1296060Y-36925D01*
X1295905Y-35050D01*
X1295440Y-33383D01*
X1294820Y-32133D01*
X1293890Y-31092D01*
X1292650Y-30675D01*
G01X1191745Y-10658D02*
X1195465D01*
G01X1193450Y-7950D02*
Y-13367D01*
G01X1202440Y-12325D02*
X1203370Y-13784D01*
X1204610Y-14617D01*
X1206005Y-14825D01*
X1207245Y-14617D01*
X1208485Y-13575D01*
X1209260Y-12325D01*
X1209415Y-11075D01*
X1209105Y-9617D01*
X1208020Y-8575D01*
X1206935Y-8158D01*
X1205540D01*
G01X1206935D02*
X1207865Y-7533D01*
X1208640Y-6492D01*
X1208950Y-5242D01*
X1208640Y-3992D01*
X1207865Y-2950D01*
X1206470Y-2325D01*
X1205075Y-2533D01*
X1203680Y-3367D01*
G01X1218250Y-15242D02*
X1217940Y-15033D01*
Y-14617D01*
X1218250Y-14408D01*
X1218560Y-14617D01*
Y-15033D01*
X1218250Y-15242D01*
G01X1230650Y-2325D02*
X1229410Y-2742D01*
X1228480Y-3783D01*
X1227860Y-5033D01*
X1227395Y-6700D01*
X1227240Y-8575D01*
X1227395Y-10450D01*
X1227860Y-12117D01*
X1228480Y-13367D01*
X1229410Y-14408D01*
X1230650Y-14825D01*
X1231890Y-14408D01*
X1232820Y-13367D01*
X1233440Y-12117D01*
X1233905Y-10450D01*
X1234060Y-8575D01*
X1233905Y-6700D01*
X1233440Y-5033D01*
X1232820Y-3783D01*
X1231890Y-2742D01*
X1230650Y-2325D01*
G01X1240260Y-15242D02*
X1245840Y-2325D01*
G01X1253435Y-10658D02*
X1257465D01*
G01X1264440Y-12325D02*
X1265370Y-13784D01*
X1266610Y-14617D01*
X1268005Y-14825D01*
X1269245Y-14617D01*
X1270485Y-13575D01*
X1271260Y-12325D01*
X1271415Y-11075D01*
X1271105Y-9617D01*
X1270020Y-8575D01*
X1268935Y-8158D01*
X1267540D01*
G01X1268935D02*
X1269865Y-7533D01*
X1270640Y-6492D01*
X1270950Y-5242D01*
X1270640Y-3992D01*
X1269865Y-2950D01*
X1268470Y-2325D01*
X1267075Y-2533D01*
X1265680Y-3367D01*
G01X1280250Y-15242D02*
X1279940Y-15033D01*
Y-14617D01*
X1280250Y-14408D01*
X1280560Y-14617D01*
Y-15033D01*
X1280250Y-15242D01*
G01X1292650Y-2325D02*
X1291410Y-2742D01*
X1290480Y-3783D01*
X1289860Y-5033D01*
X1289395Y-6700D01*
X1289240Y-8575D01*
X1289395Y-10450D01*
X1289860Y-12117D01*
X1290480Y-13367D01*
X1291410Y-14408D01*
X1292650Y-14825D01*
X1293890Y-14408D01*
X1294820Y-13367D01*
X1295440Y-12117D01*
X1295905Y-10450D01*
X1296060Y-8575D01*
X1295905Y-6700D01*
X1295440Y-5033D01*
X1294820Y-3783D01*
X1293890Y-2742D01*
X1292650Y-2325D01*
G01X1191745Y17692D02*
X1195465D01*
G01X1193450Y20400D02*
Y14983D01*
G01X1202440Y16025D02*
X1203370Y14566D01*
X1204610Y13733D01*
X1206005Y13525D01*
X1207245Y13733D01*
X1208485Y14775D01*
X1209260Y16025D01*
X1209415Y17275D01*
X1209105Y18733D01*
X1208020Y19775D01*
X1206935Y20192D01*
X1205540D01*
G01X1206935D02*
X1207865Y20817D01*
X1208640Y21858D01*
X1208950Y23108D01*
X1208640Y24358D01*
X1207865Y25400D01*
X1206470Y26025D01*
X1205075Y25817D01*
X1203680Y24983D01*
G01X1218250Y13108D02*
X1217940Y13317D01*
Y13733D01*
X1218250Y13942D01*
X1218560Y13733D01*
Y13317D01*
X1218250Y13108D01*
G01X1230650Y26025D02*
X1229410Y25608D01*
X1228480Y24567D01*
X1227860Y23317D01*
X1227395Y21650D01*
X1227240Y19775D01*
X1227395Y17900D01*
X1227860Y16233D01*
X1228480Y14983D01*
X1229410Y13942D01*
X1230650Y13525D01*
X1231890Y13942D01*
X1232820Y14983D01*
X1233440Y16233D01*
X1233905Y17900D01*
X1234060Y19775D01*
X1233905Y21650D01*
X1233440Y23317D01*
X1232820Y24567D01*
X1231890Y25608D01*
X1230650Y26025D01*
G01X1240260Y13108D02*
X1245840Y26025D01*
G01X1253435Y17692D02*
X1257465D01*
G01X1264440Y16025D02*
X1265370Y14566D01*
X1266610Y13733D01*
X1268005Y13525D01*
X1269245Y13733D01*
X1270485Y14775D01*
X1271260Y16025D01*
X1271415Y17275D01*
X1271105Y18733D01*
X1270020Y19775D01*
X1268935Y20192D01*
X1267540D01*
G01X1268935D02*
X1269865Y20817D01*
X1270640Y21858D01*
X1270950Y23108D01*
X1270640Y24358D01*
X1269865Y25400D01*
X1268470Y26025D01*
X1267075Y25817D01*
X1265680Y24983D01*
G01X1280250Y13108D02*
X1279940Y13317D01*
Y13733D01*
X1280250Y13942D01*
X1280560Y13733D01*
Y13317D01*
X1280250Y13108D01*
G01X1292650Y26025D02*
X1291410Y25608D01*
X1290480Y24567D01*
X1289860Y23317D01*
X1289395Y21650D01*
X1289240Y19775D01*
X1289395Y17900D01*
X1289860Y16233D01*
X1290480Y14983D01*
X1291410Y13942D01*
X1292650Y13525D01*
X1293890Y13942D01*
X1294820Y14983D01*
X1295440Y16233D01*
X1295905Y17900D01*
X1296060Y19775D01*
X1295905Y21650D01*
X1295440Y23317D01*
X1294820Y24567D01*
X1293890Y25608D01*
X1292650Y26025D01*
G01X1191745Y46042D02*
X1195465D01*
G01X1193450Y48750D02*
Y43333D01*
G01X1202440Y44375D02*
X1203370Y42916D01*
X1204610Y42083D01*
X1206005Y41875D01*
X1207245Y42083D01*
X1208485Y43125D01*
X1209260Y44375D01*
X1209415Y45625D01*
X1209105Y47083D01*
X1208020Y48125D01*
X1206935Y48542D01*
X1205540D01*
G01X1206935D02*
X1207865Y49167D01*
X1208640Y50208D01*
X1208950Y51458D01*
X1208640Y52708D01*
X1207865Y53750D01*
X1206470Y54375D01*
X1205075Y54167D01*
X1203680Y53333D01*
G01X1218250Y41458D02*
X1217940Y41667D01*
Y42083D01*
X1218250Y42292D01*
X1218560Y42083D01*
Y41667D01*
X1218250Y41458D01*
G01X1230650Y54375D02*
X1229410Y53958D01*
X1228480Y52917D01*
X1227860Y51667D01*
X1227395Y50000D01*
X1227240Y48125D01*
X1227395Y46250D01*
X1227860Y44583D01*
X1228480Y43333D01*
X1229410Y42292D01*
X1230650Y41875D01*
X1231890Y42292D01*
X1232820Y43333D01*
X1233440Y44583D01*
X1233905Y46250D01*
X1234060Y48125D01*
X1233905Y50000D01*
X1233440Y51667D01*
X1232820Y52917D01*
X1231890Y53958D01*
X1230650Y54375D01*
G01X1240260Y41458D02*
X1245840Y54375D01*
G01X1253435Y46042D02*
X1257465D01*
G01X1264440Y44375D02*
X1265370Y42916D01*
X1266610Y42083D01*
X1268005Y41875D01*
X1269245Y42083D01*
X1270485Y43125D01*
X1271260Y44375D01*
X1271415Y45625D01*
X1271105Y47083D01*
X1270020Y48125D01*
X1268935Y48542D01*
X1267540D01*
G01X1268935D02*
X1269865Y49167D01*
X1270640Y50208D01*
X1270950Y51458D01*
X1270640Y52708D01*
X1269865Y53750D01*
X1268470Y54375D01*
X1267075Y54167D01*
X1265680Y53333D01*
G01X1280250Y41458D02*
X1279940Y41667D01*
Y42083D01*
X1280250Y42292D01*
X1280560Y42083D01*
Y41667D01*
X1280250Y41458D01*
G01X1292650Y54375D02*
X1291410Y53958D01*
X1290480Y52917D01*
X1289860Y51667D01*
X1289395Y50000D01*
X1289240Y48125D01*
X1289395Y46250D01*
X1289860Y44583D01*
X1290480Y43333D01*
X1291410Y42292D01*
X1292650Y41875D01*
X1293890Y42292D01*
X1294820Y43333D01*
X1295440Y44583D01*
X1295905Y46250D01*
X1296060Y48125D01*
X1295905Y50000D01*
X1295440Y51667D01*
X1294820Y52917D01*
X1293890Y53958D01*
X1292650Y54375D01*
G01X1191745Y74392D02*
X1195465D01*
G01X1193450Y77100D02*
Y71683D01*
G01X1202440Y72725D02*
X1203370Y71266D01*
X1204610Y70433D01*
X1206005Y70225D01*
X1207245Y70433D01*
X1208485Y71475D01*
X1209260Y72725D01*
X1209415Y73975D01*
X1209105Y75433D01*
X1208020Y76475D01*
X1206935Y76892D01*
X1205540D01*
G01X1206935D02*
X1207865Y77517D01*
X1208640Y78558D01*
X1208950Y79808D01*
X1208640Y81058D01*
X1207865Y82100D01*
X1206470Y82725D01*
X1205075Y82517D01*
X1203680Y81683D01*
G01X1218250Y69808D02*
X1217940Y70017D01*
Y70433D01*
X1218250Y70642D01*
X1218560Y70433D01*
Y70017D01*
X1218250Y69808D01*
G01X1230650Y82725D02*
X1229410Y82308D01*
X1228480Y81267D01*
X1227860Y80017D01*
X1227395Y78350D01*
X1227240Y76475D01*
X1227395Y74600D01*
X1227860Y72933D01*
X1228480Y71683D01*
X1229410Y70642D01*
X1230650Y70225D01*
X1231890Y70642D01*
X1232820Y71683D01*
X1233440Y72933D01*
X1233905Y74600D01*
X1234060Y76475D01*
X1233905Y78350D01*
X1233440Y80017D01*
X1232820Y81267D01*
X1231890Y82308D01*
X1230650Y82725D01*
G01X1240260Y69808D02*
X1245840Y82725D01*
G01X1253435Y74392D02*
X1257465D01*
G01X1264440Y72725D02*
X1265370Y71266D01*
X1266610Y70433D01*
X1268005Y70225D01*
X1269245Y70433D01*
X1270485Y71475D01*
X1271260Y72725D01*
X1271415Y73975D01*
X1271105Y75433D01*
X1270020Y76475D01*
X1268935Y76892D01*
X1267540D01*
G01X1268935D02*
X1269865Y77517D01*
X1270640Y78558D01*
X1270950Y79808D01*
X1270640Y81058D01*
X1269865Y82100D01*
X1268470Y82725D01*
X1267075Y82517D01*
X1265680Y81683D01*
G01X1280250Y69808D02*
X1279940Y70017D01*
Y70433D01*
X1280250Y70642D01*
X1280560Y70433D01*
Y70017D01*
X1280250Y69808D01*
G01X1292650Y82725D02*
X1291410Y82308D01*
X1290480Y81267D01*
X1289860Y80017D01*
X1289395Y78350D01*
X1289240Y76475D01*
X1289395Y74600D01*
X1289860Y72933D01*
X1290480Y71683D01*
X1291410Y70642D01*
X1292650Y70225D01*
X1293890Y70642D01*
X1294820Y71683D01*
X1295440Y72933D01*
X1295905Y74600D01*
X1296060Y76475D01*
X1295905Y78350D01*
X1295440Y80017D01*
X1294820Y81267D01*
X1293890Y82308D01*
X1292650Y82725D01*
G01X1191745Y102742D02*
X1195465D01*
G01X1193450Y105450D02*
Y100033D01*
G01X1202440Y101075D02*
X1203370Y99616D01*
X1204610Y98783D01*
X1206005Y98575D01*
X1207245Y98783D01*
X1208485Y99825D01*
X1209260Y101075D01*
X1209415Y102325D01*
X1209105Y103783D01*
X1208020Y104825D01*
X1206935Y105242D01*
X1205540D01*
G01X1206935D02*
X1207865Y105867D01*
X1208640Y106908D01*
X1208950Y108158D01*
X1208640Y109408D01*
X1207865Y110450D01*
X1206470Y111075D01*
X1205075Y110867D01*
X1203680Y110033D01*
G01X1218250Y98158D02*
X1217940Y98367D01*
Y98783D01*
X1218250Y98992D01*
X1218560Y98783D01*
Y98367D01*
X1218250Y98158D01*
G01X1230650Y111075D02*
X1229410Y110658D01*
X1228480Y109617D01*
X1227860Y108367D01*
X1227395Y106700D01*
X1227240Y104825D01*
X1227395Y102950D01*
X1227860Y101283D01*
X1228480Y100033D01*
X1229410Y98992D01*
X1230650Y98575D01*
X1231890Y98992D01*
X1232820Y100033D01*
X1233440Y101283D01*
X1233905Y102950D01*
X1234060Y104825D01*
X1233905Y106700D01*
X1233440Y108367D01*
X1232820Y109617D01*
X1231890Y110658D01*
X1230650Y111075D01*
G01X1240260Y98158D02*
X1245840Y111075D01*
G01X1253435Y102742D02*
X1257465D01*
G01X1264440Y101075D02*
X1265370Y99616D01*
X1266610Y98783D01*
X1268005Y98575D01*
X1269245Y98783D01*
X1270485Y99825D01*
X1271260Y101075D01*
X1271415Y102325D01*
X1271105Y103783D01*
X1270020Y104825D01*
X1268935Y105242D01*
X1267540D01*
G01X1268935D02*
X1269865Y105867D01*
X1270640Y106908D01*
X1270950Y108158D01*
X1270640Y109408D01*
X1269865Y110450D01*
X1268470Y111075D01*
X1267075Y110867D01*
X1265680Y110033D01*
G01X1280250Y98158D02*
X1279940Y98367D01*
Y98783D01*
X1280250Y98992D01*
X1280560Y98783D01*
Y98367D01*
X1280250Y98158D01*
G01X1292650Y111075D02*
X1291410Y110658D01*
X1290480Y109617D01*
X1289860Y108367D01*
X1289395Y106700D01*
X1289240Y104825D01*
X1289395Y102950D01*
X1289860Y101283D01*
X1290480Y100033D01*
X1291410Y98992D01*
X1292650Y98575D01*
X1293890Y98992D01*
X1294820Y100033D01*
X1295440Y101283D01*
X1295905Y102950D01*
X1296060Y104825D01*
X1295905Y106700D01*
X1295440Y108367D01*
X1294820Y109617D01*
X1293890Y110658D01*
X1292650Y111075D01*
G01X1191745Y131092D02*
X1195465D01*
G01X1193450Y133800D02*
Y128383D01*
G01X1202440Y129425D02*
X1203370Y127966D01*
X1204610Y127133D01*
X1206005Y126925D01*
X1207245Y127133D01*
X1208485Y128175D01*
X1209260Y129425D01*
X1209415Y130675D01*
X1209105Y132133D01*
X1208020Y133175D01*
X1206935Y133592D01*
X1205540D01*
G01X1206935D02*
X1207865Y134217D01*
X1208640Y135258D01*
X1208950Y136508D01*
X1208640Y137758D01*
X1207865Y138800D01*
X1206470Y139425D01*
X1205075Y139217D01*
X1203680Y138383D01*
G01X1218250Y126508D02*
X1217940Y126717D01*
Y127133D01*
X1218250Y127342D01*
X1218560Y127133D01*
Y126717D01*
X1218250Y126508D01*
G01X1230650Y139425D02*
X1229410Y139008D01*
X1228480Y137967D01*
X1227860Y136717D01*
X1227395Y135050D01*
X1227240Y133175D01*
X1227395Y131300D01*
X1227860Y129633D01*
X1228480Y128383D01*
X1229410Y127342D01*
X1230650Y126925D01*
X1231890Y127342D01*
X1232820Y128383D01*
X1233440Y129633D01*
X1233905Y131300D01*
X1234060Y133175D01*
X1233905Y135050D01*
X1233440Y136717D01*
X1232820Y137967D01*
X1231890Y139008D01*
X1230650Y139425D01*
G01X1240260Y126508D02*
X1245840Y139425D01*
G01X1253435Y131092D02*
X1257465D01*
G01X1264440Y129425D02*
X1265370Y127966D01*
X1266610Y127133D01*
X1268005Y126925D01*
X1269245Y127133D01*
X1270485Y128175D01*
X1271260Y129425D01*
X1271415Y130675D01*
X1271105Y132133D01*
X1270020Y133175D01*
X1268935Y133592D01*
X1267540D01*
G01X1268935D02*
X1269865Y134217D01*
X1270640Y135258D01*
X1270950Y136508D01*
X1270640Y137758D01*
X1269865Y138800D01*
X1268470Y139425D01*
X1267075Y139217D01*
X1265680Y138383D01*
G01X1280250Y126508D02*
X1279940Y126717D01*
Y127133D01*
X1280250Y127342D01*
X1280560Y127133D01*
Y126717D01*
X1280250Y126508D01*
G01X1292650Y139425D02*
X1291410Y139008D01*
X1290480Y137967D01*
X1289860Y136717D01*
X1289395Y135050D01*
X1289240Y133175D01*
X1289395Y131300D01*
X1289860Y129633D01*
X1290480Y128383D01*
X1291410Y127342D01*
X1292650Y126925D01*
X1293890Y127342D01*
X1294820Y128383D01*
X1295440Y129633D01*
X1295905Y131300D01*
X1296060Y133175D01*
X1295905Y135050D01*
X1295440Y136717D01*
X1294820Y137967D01*
X1293890Y139008D01*
X1292650Y139425D01*
G01X1191745Y159442D02*
X1195465D01*
G01X1193450Y162150D02*
Y156733D01*
G01X1202440Y157775D02*
X1203370Y156316D01*
X1204610Y155483D01*
X1206005Y155275D01*
X1207245Y155483D01*
X1208485Y156525D01*
X1209260Y157775D01*
X1209415Y159025D01*
X1209105Y160483D01*
X1208020Y161525D01*
X1206935Y161942D01*
X1205540D01*
G01X1206935D02*
X1207865Y162567D01*
X1208640Y163608D01*
X1208950Y164858D01*
X1208640Y166108D01*
X1207865Y167150D01*
X1206470Y167775D01*
X1205075Y167567D01*
X1203680Y166733D01*
G01X1218250Y154858D02*
X1217940Y155067D01*
Y155483D01*
X1218250Y155692D01*
X1218560Y155483D01*
Y155067D01*
X1218250Y154858D01*
G01X1230650Y167775D02*
X1229410Y167358D01*
X1228480Y166317D01*
X1227860Y165067D01*
X1227395Y163400D01*
X1227240Y161525D01*
X1227395Y159650D01*
X1227860Y157983D01*
X1228480Y156733D01*
X1229410Y155692D01*
X1230650Y155275D01*
X1231890Y155692D01*
X1232820Y156733D01*
X1233440Y157983D01*
X1233905Y159650D01*
X1234060Y161525D01*
X1233905Y163400D01*
X1233440Y165067D01*
X1232820Y166317D01*
X1231890Y167358D01*
X1230650Y167775D01*
G01X1240260Y154858D02*
X1245840Y167775D01*
G01X1253435Y159442D02*
X1257465D01*
G01X1264440Y157775D02*
X1265370Y156316D01*
X1266610Y155483D01*
X1268005Y155275D01*
X1269245Y155483D01*
X1270485Y156525D01*
X1271260Y157775D01*
X1271415Y159025D01*
X1271105Y160483D01*
X1270020Y161525D01*
X1268935Y161942D01*
X1267540D01*
G01X1268935D02*
X1269865Y162567D01*
X1270640Y163608D01*
X1270950Y164858D01*
X1270640Y166108D01*
X1269865Y167150D01*
X1268470Y167775D01*
X1267075Y167567D01*
X1265680Y166733D01*
G01X1280250Y154858D02*
X1279940Y155067D01*
Y155483D01*
X1280250Y155692D01*
X1280560Y155483D01*
Y155067D01*
X1280250Y154858D01*
G01X1292650Y167775D02*
X1291410Y167358D01*
X1290480Y166317D01*
X1289860Y165067D01*
X1289395Y163400D01*
X1289240Y161525D01*
X1289395Y159650D01*
X1289860Y157983D01*
X1290480Y156733D01*
X1291410Y155692D01*
X1292650Y155275D01*
X1293890Y155692D01*
X1294820Y156733D01*
X1295440Y157983D01*
X1295905Y159650D01*
X1296060Y161525D01*
X1295905Y163400D01*
X1295440Y165067D01*
X1294820Y166317D01*
X1293890Y167358D01*
X1292650Y167775D01*
G01X1191745Y187792D02*
X1195465D01*
G01X1193450Y190500D02*
Y185083D01*
G01X1202905Y188833D02*
X1203990Y190292D01*
X1204920Y191125D01*
X1206160Y191542D01*
X1207245Y191125D01*
X1208020Y190292D01*
X1208640Y189042D01*
X1208795Y187583D01*
X1208640Y186333D01*
X1208020Y185083D01*
X1207090Y184042D01*
X1206005Y183625D01*
X1204765Y184042D01*
X1203680Y185291D01*
X1203060Y187167D01*
X1202905Y189250D01*
X1203215Y191958D01*
X1203680Y193417D01*
X1204455Y194875D01*
X1205540Y195917D01*
X1206625Y196125D01*
X1207710Y195708D01*
X1208485Y194667D01*
G01X1218250Y183208D02*
X1217940Y183417D01*
Y183833D01*
X1218250Y184042D01*
X1218560Y183833D01*
Y183417D01*
X1218250Y183208D01*
G01X1230650Y196125D02*
X1229410Y195708D01*
X1228480Y194667D01*
X1227860Y193417D01*
X1227395Y191750D01*
X1227240Y189875D01*
X1227395Y188000D01*
X1227860Y186333D01*
X1228480Y185083D01*
X1229410Y184042D01*
X1230650Y183625D01*
X1231890Y184042D01*
X1232820Y185083D01*
X1233440Y186333D01*
X1233905Y188000D01*
X1234060Y189875D01*
X1233905Y191750D01*
X1233440Y193417D01*
X1232820Y194667D01*
X1231890Y195708D01*
X1230650Y196125D01*
G01X1240260Y183208D02*
X1245840Y196125D01*
G01X1253435Y187792D02*
X1257465D01*
G01X1267850Y196125D02*
X1266610Y195708D01*
X1265680Y194667D01*
X1265060Y193417D01*
X1264595Y191750D01*
X1264440Y189875D01*
X1264595Y188000D01*
X1265060Y186333D01*
X1265680Y185083D01*
X1266610Y184042D01*
X1267850Y183625D01*
X1269090Y184042D01*
X1270020Y185083D01*
X1270640Y186333D01*
X1271105Y188000D01*
X1271260Y189875D01*
X1271105Y191750D01*
X1270640Y193417D01*
X1270020Y194667D01*
X1269090Y195708D01*
X1267850Y196125D01*
G01X1280250Y183208D02*
X1279940Y183417D01*
Y183833D01*
X1280250Y184042D01*
X1280560Y183833D01*
Y183417D01*
X1280250Y183208D01*
G01X1292650Y196125D02*
X1291410Y195708D01*
X1290480Y194667D01*
X1289860Y193417D01*
X1289395Y191750D01*
X1289240Y189875D01*
X1289395Y188000D01*
X1289860Y186333D01*
X1290480Y185083D01*
X1291410Y184042D01*
X1292650Y183625D01*
X1293890Y184042D01*
X1294820Y185083D01*
X1295440Y186333D01*
X1295905Y188000D01*
X1296060Y189875D01*
X1295905Y191750D01*
X1295440Y193417D01*
X1294820Y194667D01*
X1293890Y195708D01*
X1292650Y196125D01*
G01X1191745Y216142D02*
X1195465D01*
G01X1193450Y218850D02*
Y213433D01*
G01X1207710Y211975D02*
Y224475D01*
X1201975Y215517D01*
X1209725D01*
G01X1218250Y211558D02*
X1217940Y211767D01*
Y212183D01*
X1218250Y212392D01*
X1218560Y212183D01*
Y211767D01*
X1218250Y211558D01*
G01X1230650Y224475D02*
X1229410Y224058D01*
X1228480Y223017D01*
X1227860Y221767D01*
X1227395Y220100D01*
X1227240Y218225D01*
X1227395Y216350D01*
X1227860Y214683D01*
X1228480Y213433D01*
X1229410Y212392D01*
X1230650Y211975D01*
X1231890Y212392D01*
X1232820Y213433D01*
X1233440Y214683D01*
X1233905Y216350D01*
X1234060Y218225D01*
X1233905Y220100D01*
X1233440Y221767D01*
X1232820Y223017D01*
X1231890Y224058D01*
X1230650Y224475D01*
G01X1240260Y211558D02*
X1245840Y224475D01*
G01X1253435Y216142D02*
X1257465D01*
G01X1267850Y224475D02*
X1266610Y224058D01*
X1265680Y223017D01*
X1265060Y221767D01*
X1264595Y220100D01*
X1264440Y218225D01*
X1264595Y216350D01*
X1265060Y214683D01*
X1265680Y213433D01*
X1266610Y212392D01*
X1267850Y211975D01*
X1269090Y212392D01*
X1270020Y213433D01*
X1270640Y214683D01*
X1271105Y216350D01*
X1271260Y218225D01*
X1271105Y220100D01*
X1270640Y221767D01*
X1270020Y223017D01*
X1269090Y224058D01*
X1267850Y224475D01*
G01X1280250Y211558D02*
X1279940Y211767D01*
Y212183D01*
X1280250Y212392D01*
X1280560Y212183D01*
Y211767D01*
X1280250Y211558D01*
G01X1292650Y224475D02*
X1291410Y224058D01*
X1290480Y223017D01*
X1289860Y221767D01*
X1289395Y220100D01*
X1289240Y218225D01*
X1289395Y216350D01*
X1289860Y214683D01*
X1290480Y213433D01*
X1291410Y212392D01*
X1292650Y211975D01*
X1293890Y212392D01*
X1294820Y213433D01*
X1295440Y214683D01*
X1295905Y216350D01*
X1296060Y218225D01*
X1295905Y220100D01*
X1295440Y221767D01*
X1294820Y223017D01*
X1293890Y224058D01*
X1292650Y224475D01*
G01X1191745Y244492D02*
X1195465D01*
G01X1193450Y247200D02*
Y241783D01*
G01X1202905Y250742D02*
X1203835Y251991D01*
X1204920Y252617D01*
X1206160Y252825D01*
X1207710Y252408D01*
X1208795Y251367D01*
X1209105Y250117D01*
X1208950Y248866D01*
X1208330Y247825D01*
X1205230Y245742D01*
X1203835Y244283D01*
X1202905Y242200D01*
X1202595Y240325D01*
X1209105D01*
G01X1218250Y239908D02*
X1217940Y240117D01*
Y240533D01*
X1218250Y240742D01*
X1218560Y240533D01*
Y240117D01*
X1218250Y239908D01*
G01X1230650Y252825D02*
X1229410Y252408D01*
X1228480Y251367D01*
X1227860Y250117D01*
X1227395Y248450D01*
X1227240Y246575D01*
X1227395Y244700D01*
X1227860Y243033D01*
X1228480Y241783D01*
X1229410Y240742D01*
X1230650Y240325D01*
X1231890Y240742D01*
X1232820Y241783D01*
X1233440Y243033D01*
X1233905Y244700D01*
X1234060Y246575D01*
X1233905Y248450D01*
X1233440Y250117D01*
X1232820Y251367D01*
X1231890Y252408D01*
X1230650Y252825D01*
G01X1240260Y239908D02*
X1245840Y252825D01*
G01X1253435Y244492D02*
X1257465D01*
G01X1264905Y250742D02*
X1265835Y251991D01*
X1266920Y252617D01*
X1268160Y252825D01*
X1269710Y252408D01*
X1270795Y251367D01*
X1271105Y250117D01*
X1270950Y248866D01*
X1270330Y247825D01*
X1267230Y245742D01*
X1265835Y244283D01*
X1264905Y242200D01*
X1264595Y240325D01*
X1271105D01*
G01X1280250Y239908D02*
X1279940Y240117D01*
Y240533D01*
X1280250Y240742D01*
X1280560Y240533D01*
Y240117D01*
X1280250Y239908D01*
G01X1292650Y252825D02*
X1291410Y252408D01*
X1290480Y251367D01*
X1289860Y250117D01*
X1289395Y248450D01*
X1289240Y246575D01*
X1289395Y244700D01*
X1289860Y243033D01*
X1290480Y241783D01*
X1291410Y240742D01*
X1292650Y240325D01*
X1293890Y240742D01*
X1294820Y241783D01*
X1295440Y243033D01*
X1295905Y244700D01*
X1296060Y246575D01*
X1295905Y248450D01*
X1295440Y250117D01*
X1294820Y251367D01*
X1293890Y252408D01*
X1292650Y252825D01*
G01X1185545Y272842D02*
X1189265D01*
G01X1187250Y275550D02*
Y270133D01*
G01X1199650Y281175D02*
X1198410Y280758D01*
X1197480Y279717D01*
X1196860Y278467D01*
X1196395Y276800D01*
X1196240Y274925D01*
X1196395Y273050D01*
X1196860Y271383D01*
X1197480Y270133D01*
X1198410Y269092D01*
X1199650Y268675D01*
X1200890Y269092D01*
X1201820Y270133D01*
X1202440Y271383D01*
X1202905Y273050D01*
X1203060Y274925D01*
X1202905Y276800D01*
X1202440Y278467D01*
X1201820Y279717D01*
X1200890Y280758D01*
X1199650Y281175D01*
G01X1212050Y268258D02*
X1211740Y268467D01*
Y268883D01*
X1212050Y269092D01*
X1212360Y268883D01*
Y268467D01*
X1212050Y268258D01*
G01X1224450Y281175D02*
X1223210Y280758D01*
X1222280Y279717D01*
X1221660Y278467D01*
X1221195Y276800D01*
X1221040Y274925D01*
X1221195Y273050D01*
X1221660Y271383D01*
X1222280Y270133D01*
X1223210Y269092D01*
X1224450Y268675D01*
X1225690Y269092D01*
X1226620Y270133D01*
X1227240Y271383D01*
X1227705Y273050D01*
X1227860Y274925D01*
X1227705Y276800D01*
X1227240Y278467D01*
X1226620Y279717D01*
X1225690Y280758D01*
X1224450Y281175D01*
G01X1234060Y268258D02*
X1239640Y281175D01*
G01X1247235Y272842D02*
X1251265D01*
G01X1261650Y268675D02*
Y281175D01*
X1259790Y278675D01*
G01Y268675D02*
X1263510D01*
G01X1274050Y281175D02*
X1272810Y280758D01*
X1271880Y279717D01*
X1271260Y278467D01*
X1270795Y276800D01*
X1270640Y274925D01*
X1270795Y273050D01*
X1271260Y271383D01*
X1271880Y270133D01*
X1272810Y269092D01*
X1274050Y268675D01*
X1275290Y269092D01*
X1276220Y270133D01*
X1276840Y271383D01*
X1277305Y273050D01*
X1277460Y274925D01*
X1277305Y276800D01*
X1276840Y278467D01*
X1276220Y279717D01*
X1275290Y280758D01*
X1274050Y281175D01*
G01X1286450Y268258D02*
X1286140Y268467D01*
Y268883D01*
X1286450Y269092D01*
X1286760Y268883D01*
Y268467D01*
X1286450Y268258D01*
G01X1298850Y281175D02*
X1297610Y280758D01*
X1296680Y279717D01*
X1296060Y278467D01*
X1295595Y276800D01*
X1295440Y274925D01*
X1295595Y273050D01*
X1296060Y271383D01*
X1296680Y270133D01*
X1297610Y269092D01*
X1298850Y268675D01*
X1300090Y269092D01*
X1301020Y270133D01*
X1301640Y271383D01*
X1302105Y273050D01*
X1302260Y274925D01*
X1302105Y276800D01*
X1301640Y278467D01*
X1301020Y279717D01*
X1300090Y280758D01*
X1298850Y281175D01*
G01X1185545Y301192D02*
X1189265D01*
G01X1187250Y303900D02*
Y298483D01*
G01X1199650Y309525D02*
X1198410Y309108D01*
X1197480Y308067D01*
X1196860Y306817D01*
X1196395Y305150D01*
X1196240Y303275D01*
X1196395Y301400D01*
X1196860Y299733D01*
X1197480Y298483D01*
X1198410Y297442D01*
X1199650Y297025D01*
X1200890Y297442D01*
X1201820Y298483D01*
X1202440Y299733D01*
X1202905Y301400D01*
X1203060Y303275D01*
X1202905Y305150D01*
X1202440Y306817D01*
X1201820Y308067D01*
X1200890Y309108D01*
X1199650Y309525D01*
G01X1212050Y296608D02*
X1211740Y296817D01*
Y297233D01*
X1212050Y297442D01*
X1212360Y297233D01*
Y296817D01*
X1212050Y296608D01*
G01X1224450Y309525D02*
X1223210Y309108D01*
X1222280Y308067D01*
X1221660Y306817D01*
X1221195Y305150D01*
X1221040Y303275D01*
X1221195Y301400D01*
X1221660Y299733D01*
X1222280Y298483D01*
X1223210Y297442D01*
X1224450Y297025D01*
X1225690Y297442D01*
X1226620Y298483D01*
X1227240Y299733D01*
X1227705Y301400D01*
X1227860Y303275D01*
X1227705Y305150D01*
X1227240Y306817D01*
X1226620Y308067D01*
X1225690Y309108D01*
X1224450Y309525D01*
G01X1234060Y296608D02*
X1239640Y309525D01*
G01X1247235Y301192D02*
X1251265D01*
G01X1261650Y297025D02*
Y309525D01*
X1259790Y307025D01*
G01Y297025D02*
X1263510D01*
G01X1274050Y309525D02*
X1272810Y309108D01*
X1271880Y308067D01*
X1271260Y306817D01*
X1270795Y305150D01*
X1270640Y303275D01*
X1270795Y301400D01*
X1271260Y299733D01*
X1271880Y298483D01*
X1272810Y297442D01*
X1274050Y297025D01*
X1275290Y297442D01*
X1276220Y298483D01*
X1276840Y299733D01*
X1277305Y301400D01*
X1277460Y303275D01*
X1277305Y305150D01*
X1276840Y306817D01*
X1276220Y308067D01*
X1275290Y309108D01*
X1274050Y309525D01*
G01X1286450Y296608D02*
X1286140Y296817D01*
Y297233D01*
X1286450Y297442D01*
X1286760Y297233D01*
Y296817D01*
X1286450Y296608D01*
G01X1298850Y309525D02*
X1297610Y309108D01*
X1296680Y308067D01*
X1296060Y306817D01*
X1295595Y305150D01*
X1295440Y303275D01*
X1295595Y301400D01*
X1296060Y299733D01*
X1296680Y298483D01*
X1297610Y297442D01*
X1298850Y297025D01*
X1300090Y297442D01*
X1301020Y298483D01*
X1301640Y299733D01*
X1302105Y301400D01*
X1302260Y303275D01*
X1302105Y305150D01*
X1301640Y306817D01*
X1301020Y308067D01*
X1300090Y309108D01*
X1298850Y309525D01*
G01X1185545Y329542D02*
X1189265D01*
G01X1187250Y332250D02*
Y326833D01*
G01X1199650Y337875D02*
X1198410Y337458D01*
X1197480Y336417D01*
X1196860Y335167D01*
X1196395Y333500D01*
X1196240Y331625D01*
X1196395Y329750D01*
X1196860Y328083D01*
X1197480Y326833D01*
X1198410Y325792D01*
X1199650Y325375D01*
X1200890Y325792D01*
X1201820Y326833D01*
X1202440Y328083D01*
X1202905Y329750D01*
X1203060Y331625D01*
X1202905Y333500D01*
X1202440Y335167D01*
X1201820Y336417D01*
X1200890Y337458D01*
X1199650Y337875D01*
G01X1212050Y324958D02*
X1211740Y325167D01*
Y325583D01*
X1212050Y325792D01*
X1212360Y325583D01*
Y325167D01*
X1212050Y324958D01*
G01X1224450Y337875D02*
X1223210Y337458D01*
X1222280Y336417D01*
X1221660Y335167D01*
X1221195Y333500D01*
X1221040Y331625D01*
X1221195Y329750D01*
X1221660Y328083D01*
X1222280Y326833D01*
X1223210Y325792D01*
X1224450Y325375D01*
X1225690Y325792D01*
X1226620Y326833D01*
X1227240Y328083D01*
X1227705Y329750D01*
X1227860Y331625D01*
X1227705Y333500D01*
X1227240Y335167D01*
X1226620Y336417D01*
X1225690Y337458D01*
X1224450Y337875D01*
G01X1234060Y324958D02*
X1239640Y337875D01*
G01X1247235Y329542D02*
X1251265D01*
G01X1261650Y325375D02*
Y337875D01*
X1259790Y335375D01*
G01Y325375D02*
X1263510D01*
G01X1274050Y337875D02*
X1272810Y337458D01*
X1271880Y336417D01*
X1271260Y335167D01*
X1270795Y333500D01*
X1270640Y331625D01*
X1270795Y329750D01*
X1271260Y328083D01*
X1271880Y326833D01*
X1272810Y325792D01*
X1274050Y325375D01*
X1275290Y325792D01*
X1276220Y326833D01*
X1276840Y328083D01*
X1277305Y329750D01*
X1277460Y331625D01*
X1277305Y333500D01*
X1276840Y335167D01*
X1276220Y336417D01*
X1275290Y337458D01*
X1274050Y337875D01*
G01X1286450Y324958D02*
X1286140Y325167D01*
Y325583D01*
X1286450Y325792D01*
X1286760Y325583D01*
Y325167D01*
X1286450Y324958D01*
G01X1298850Y337875D02*
X1297610Y337458D01*
X1296680Y336417D01*
X1296060Y335167D01*
X1295595Y333500D01*
X1295440Y331625D01*
X1295595Y329750D01*
X1296060Y328083D01*
X1296680Y326833D01*
X1297610Y325792D01*
X1298850Y325375D01*
X1300090Y325792D01*
X1301020Y326833D01*
X1301640Y328083D01*
X1302105Y329750D01*
X1302260Y331625D01*
X1302105Y333500D01*
X1301640Y335167D01*
X1301020Y336417D01*
X1300090Y337458D01*
X1298850Y337875D01*
G01X1185545Y357892D02*
X1189265D01*
G01X1187250Y360600D02*
Y355183D01*
G01X1199650Y366225D02*
X1198410Y365808D01*
X1197480Y364767D01*
X1196860Y363517D01*
X1196395Y361850D01*
X1196240Y359975D01*
X1196395Y358100D01*
X1196860Y356433D01*
X1197480Y355183D01*
X1198410Y354142D01*
X1199650Y353725D01*
X1200890Y354142D01*
X1201820Y355183D01*
X1202440Y356433D01*
X1202905Y358100D01*
X1203060Y359975D01*
X1202905Y361850D01*
X1202440Y363517D01*
X1201820Y364767D01*
X1200890Y365808D01*
X1199650Y366225D01*
G01X1212050Y353308D02*
X1211740Y353517D01*
Y353933D01*
X1212050Y354142D01*
X1212360Y353933D01*
Y353517D01*
X1212050Y353308D01*
G01X1224450Y366225D02*
X1223210Y365808D01*
X1222280Y364767D01*
X1221660Y363517D01*
X1221195Y361850D01*
X1221040Y359975D01*
X1221195Y358100D01*
X1221660Y356433D01*
X1222280Y355183D01*
X1223210Y354142D01*
X1224450Y353725D01*
X1225690Y354142D01*
X1226620Y355183D01*
X1227240Y356433D01*
X1227705Y358100D01*
X1227860Y359975D01*
X1227705Y361850D01*
X1227240Y363517D01*
X1226620Y364767D01*
X1225690Y365808D01*
X1224450Y366225D01*
G01X1234060Y353308D02*
X1239640Y366225D01*
G01X1247235Y357892D02*
X1251265D01*
G01X1261650Y353725D02*
Y366225D01*
X1259790Y363725D01*
G01Y353725D02*
X1263510D01*
G01X1274050Y366225D02*
X1272810Y365808D01*
X1271880Y364767D01*
X1271260Y363517D01*
X1270795Y361850D01*
X1270640Y359975D01*
X1270795Y358100D01*
X1271260Y356433D01*
X1271880Y355183D01*
X1272810Y354142D01*
X1274050Y353725D01*
X1275290Y354142D01*
X1276220Y355183D01*
X1276840Y356433D01*
X1277305Y358100D01*
X1277460Y359975D01*
X1277305Y361850D01*
X1276840Y363517D01*
X1276220Y364767D01*
X1275290Y365808D01*
X1274050Y366225D01*
G01X1286450Y353308D02*
X1286140Y353517D01*
Y353933D01*
X1286450Y354142D01*
X1286760Y353933D01*
Y353517D01*
X1286450Y353308D01*
G01X1298850Y366225D02*
X1297610Y365808D01*
X1296680Y364767D01*
X1296060Y363517D01*
X1295595Y361850D01*
X1295440Y359975D01*
X1295595Y358100D01*
X1296060Y356433D01*
X1296680Y355183D01*
X1297610Y354142D01*
X1298850Y353725D01*
X1300090Y354142D01*
X1301020Y355183D01*
X1301640Y356433D01*
X1302105Y358100D01*
X1302260Y359975D01*
X1302105Y361850D01*
X1301640Y363517D01*
X1301020Y364767D01*
X1300090Y365808D01*
X1298850Y366225D01*
G01X1191745Y386242D02*
X1195465D01*
G01X1193450Y388950D02*
Y383533D01*
G01X1202905Y392492D02*
X1203835Y393741D01*
X1204920Y394367D01*
X1206160Y394575D01*
X1207710Y394158D01*
X1208795Y393117D01*
X1209105Y391867D01*
X1208950Y390616D01*
X1208330Y389575D01*
X1205230Y387492D01*
X1203835Y386033D01*
X1202905Y383950D01*
X1202595Y382075D01*
X1209105D01*
G01X1218250Y381658D02*
X1217940Y381867D01*
Y382283D01*
X1218250Y382492D01*
X1218560Y382283D01*
Y381867D01*
X1218250Y381658D01*
G01X1230650Y394575D02*
X1229410Y394158D01*
X1228480Y393117D01*
X1227860Y391867D01*
X1227395Y390200D01*
X1227240Y388325D01*
X1227395Y386450D01*
X1227860Y384783D01*
X1228480Y383533D01*
X1229410Y382492D01*
X1230650Y382075D01*
X1231890Y382492D01*
X1232820Y383533D01*
X1233440Y384783D01*
X1233905Y386450D01*
X1234060Y388325D01*
X1233905Y390200D01*
X1233440Y391867D01*
X1232820Y393117D01*
X1231890Y394158D01*
X1230650Y394575D01*
G01X1240260Y381658D02*
X1245840Y394575D01*
G01X1253435Y386242D02*
X1257465D01*
G01X1264905Y392492D02*
X1265835Y393741D01*
X1266920Y394367D01*
X1268160Y394575D01*
X1269710Y394158D01*
X1270795Y393117D01*
X1271105Y391867D01*
X1270950Y390616D01*
X1270330Y389575D01*
X1267230Y387492D01*
X1265835Y386033D01*
X1264905Y383950D01*
X1264595Y382075D01*
X1271105D01*
G01X1280250Y381658D02*
X1279940Y381867D01*
Y382283D01*
X1280250Y382492D01*
X1280560Y382283D01*
Y381867D01*
X1280250Y381658D01*
G01X1292650Y394575D02*
X1291410Y394158D01*
X1290480Y393117D01*
X1289860Y391867D01*
X1289395Y390200D01*
X1289240Y388325D01*
X1289395Y386450D01*
X1289860Y384783D01*
X1290480Y383533D01*
X1291410Y382492D01*
X1292650Y382075D01*
X1293890Y382492D01*
X1294820Y383533D01*
X1295440Y384783D01*
X1295905Y386450D01*
X1296060Y388325D01*
X1295905Y390200D01*
X1295440Y391867D01*
X1294820Y393117D01*
X1293890Y394158D01*
X1292650Y394575D01*
G01X1193741Y680605D02*
Y632605D01*
G01Y637605D02*
X1198741Y639105D01*
Y636105D01*
X1193741Y637605D01*
G01X1208741D02*
X1193741D01*
G01X1190741Y666605D02*
X1237741D01*
G01X1236388Y857193D02*
X1194817Y690909D01*
G01X1195741Y686605D02*
X1237741D01*
G01X1211591Y717405D02*
X1210964Y717195D01*
X1210494Y716670D01*
X1210181Y716040D01*
X1209946Y715200D01*
X1209868Y714255D01*
X1209946Y713310D01*
X1210181Y712470D01*
X1210494Y711840D01*
X1210964Y711315D01*
X1211591Y711105D01*
X1212218Y711315D01*
X1212688Y711840D01*
X1213001Y712470D01*
X1213236Y713310D01*
X1213314Y714255D01*
X1213236Y715200D01*
X1213001Y716040D01*
X1212688Y716670D01*
X1212218Y717195D01*
X1211591Y717405D01*
G01X1217891Y710895D02*
X1217734Y711000D01*
Y711210D01*
X1217891Y711315D01*
X1218048Y711210D01*
Y711000D01*
X1217891Y710895D01*
G01X1222703Y713730D02*
X1223251Y714465D01*
X1223721Y714885D01*
X1224348Y715095D01*
X1224896Y714885D01*
X1225288Y714465D01*
X1225601Y713835D01*
X1225679Y713100D01*
X1225601Y712470D01*
X1225288Y711840D01*
X1224818Y711315D01*
X1224269Y711105D01*
X1223643Y711315D01*
X1223094Y711945D01*
X1222781Y712890D01*
X1222703Y713940D01*
X1222859Y715305D01*
X1223094Y716040D01*
X1223486Y716775D01*
X1224034Y717300D01*
X1224583Y717405D01*
X1225131Y717195D01*
X1225523Y716670D01*
G01X1229003Y716355D02*
X1229473Y716985D01*
X1230021Y717300D01*
X1230648Y717405D01*
X1231431Y717195D01*
X1231979Y716670D01*
X1232136Y716040D01*
X1232058Y715410D01*
X1231744Y714885D01*
X1230178Y713835D01*
X1229473Y713100D01*
X1229003Y712050D01*
X1228846Y711105D01*
X1232136D01*
G01X1234441D02*
Y715305D01*
G01Y714150D02*
X1234676Y714675D01*
X1235068Y715095D01*
X1235616Y715305D01*
X1236164Y715095D01*
X1236556Y714675D01*
X1236791Y714150D01*
Y711105D01*
G01Y714150D02*
X1237026Y714675D01*
X1237418Y715095D01*
X1237966Y715305D01*
X1238514Y715095D01*
X1238906Y714675D01*
X1239141Y714045D01*
Y711105D01*
G01X1240741D02*
Y715305D01*
G01Y714150D02*
X1240976Y714675D01*
X1241368Y715095D01*
X1241916Y715305D01*
X1242464Y715095D01*
X1242856Y714675D01*
X1243091Y714150D01*
Y711105D01*
G01Y714150D02*
X1243326Y714675D01*
X1243718Y715095D01*
X1244266Y715305D01*
X1244814Y715095D01*
X1245206Y714675D01*
X1245441Y714045D01*
Y711105D01*
G01X1261991Y717405D02*
X1261364Y717195D01*
X1260894Y716670D01*
X1260581Y716040D01*
X1260346Y715200D01*
X1260268Y714255D01*
X1260346Y713310D01*
X1260581Y712470D01*
X1260894Y711840D01*
X1261364Y711315D01*
X1261991Y711105D01*
X1262618Y711315D01*
X1263088Y711840D01*
X1263401Y712470D01*
X1263636Y713310D01*
X1263714Y714255D01*
X1263636Y715200D01*
X1263401Y716040D01*
X1263088Y716670D01*
X1262618Y717195D01*
X1261991Y717405D01*
G01X1268291Y710895D02*
X1268134Y711000D01*
Y711210D01*
X1268291Y711315D01*
X1268448Y711210D01*
Y711000D01*
X1268291Y710895D01*
G01X1274591Y711105D02*
Y717405D01*
X1273651Y716145D01*
G01Y711105D02*
X1275531D01*
G01X1279168Y712365D02*
X1279638Y711630D01*
X1280264Y711210D01*
X1280969Y711105D01*
X1281596Y711210D01*
X1282223Y711735D01*
X1282614Y712365D01*
X1282693Y712995D01*
X1282536Y713730D01*
X1281988Y714255D01*
X1281439Y714465D01*
X1280734D01*
G01X1281439D02*
X1281909Y714780D01*
X1282301Y715305D01*
X1282458Y715935D01*
X1282301Y716565D01*
X1281909Y717090D01*
X1281204Y717405D01*
X1280499Y717300D01*
X1279794Y716880D01*
G01X1196798Y828965D02*
X1201798Y827465D01*
Y830465D01*
X1196798Y828965D01*
G01X1244295Y809924D02*
G03X1196995Y829085I-47300J-48801D01*
G01X1196724Y856036D02*
Y884036D01*
G01Y879036D02*
X1201724Y877536D01*
Y880536D01*
X1196724Y879036D01*
G01D02*
X1211724D01*
G01X1227482Y821852D02*
X1222482Y822852D01*
X1223982Y825352D01*
X1227482Y821852D01*
G01X1227741Y666605D02*
X1226241Y671605D01*
X1229241D01*
X1227741Y666605D01*
G01Y706605D02*
Y666605D01*
G01Y686605D02*
X1226241Y681605D01*
X1229241D01*
X1227741Y686605D01*
G01X1229368Y798865D02*
X1229838Y798130D01*
X1230464Y797710D01*
X1231169Y797605D01*
X1231796Y797710D01*
X1232423Y798235D01*
X1232814Y798865D01*
X1232893Y799495D01*
X1232736Y800230D01*
X1232188Y800755D01*
X1231639Y800965D01*
X1230934D01*
G01X1231639D02*
X1232109Y801280D01*
X1232501Y801805D01*
X1232658Y802435D01*
X1232501Y803065D01*
X1232109Y803590D01*
X1231404Y803905D01*
X1230699Y803800D01*
X1229994Y803380D01*
G01X1237391Y803905D02*
X1236764Y803695D01*
X1236294Y803170D01*
X1235981Y802540D01*
X1235746Y801700D01*
X1235668Y800755D01*
X1235746Y799810D01*
X1235981Y798970D01*
X1236294Y798340D01*
X1236764Y797815D01*
X1237391Y797605D01*
X1238018Y797815D01*
X1238488Y798340D01*
X1238801Y798970D01*
X1239036Y799810D01*
X1239114Y800755D01*
X1239036Y801700D01*
X1238801Y802540D01*
X1238488Y803170D01*
X1238018Y803695D01*
X1237391Y803905D01*
G01X1254568Y798550D02*
X1255038Y798025D01*
X1255586Y797710D01*
X1256291Y797605D01*
X1256996Y797815D01*
X1257544Y798235D01*
X1257936Y798970D01*
X1258014Y799810D01*
X1257858Y800650D01*
X1257466Y801175D01*
X1256918Y801595D01*
X1256369Y801700D01*
X1255821Y801595D01*
X1255116Y801175D01*
X1255351Y803905D01*
X1257466D01*
G01X1241859Y805605D02*
G03I-1118J0D01*
G01X1254241Y717605D02*
Y712605D01*
G01X1251741Y711105D02*
X1256741D01*
G01X1251741Y715105D02*
X1256741D01*
G01X1246241Y797605D02*
X1251241D01*
G01X1248741Y804105D02*
Y799105D01*
G01X1246241Y801605D02*
X1251241D01*
G01X1260859Y805605D02*
G03I-1118J0D01*
G01X1351550Y421250D02*
Y408750D01*
G01X1347985Y421250D02*
X1355115D01*
G01X1363950Y408750D02*
X1362710Y408958D01*
X1361625Y409791D01*
X1360695Y411042D01*
X1360075Y412500D01*
X1359765Y414167D01*
Y415833D01*
X1360075Y417500D01*
X1360695Y418958D01*
X1361625Y420208D01*
X1362710Y421042D01*
X1363950Y421250D01*
X1365190Y421042D01*
X1366275Y420208D01*
X1367205Y418958D01*
X1367825Y417500D01*
X1368135Y415833D01*
Y414167D01*
X1367825Y412500D01*
X1367205Y411042D01*
X1366275Y409791D01*
X1365190Y408958D01*
X1363950Y408750D01*
G01X1373250Y421250D02*
Y408750D01*
X1379450D01*
G01X1391850D02*
X1385650D01*
Y421250D01*
X1391850D01*
G01X1389370Y415208D02*
X1385650D01*
G01X1398050Y408750D02*
Y421250D01*
X1401925D01*
X1403165Y420625D01*
X1403940Y419792D01*
X1404250Y418125D01*
X1403940Y416458D01*
X1403010Y415417D01*
X1401925Y414792D01*
X1398050D01*
G01X1401925D02*
X1404250Y408750D01*
G01X1409675D02*
X1413550Y421250D01*
X1417425Y408750D01*
G01X1416030Y413125D02*
X1411070D01*
G01X1422385Y408750D02*
Y421250D01*
X1429515Y408750D01*
Y421250D01*
G01X1441760Y420208D02*
X1440830Y420833D01*
X1439745Y421250D01*
X1438505D01*
X1437110Y420625D01*
X1436025Y419583D01*
X1435250Y418333D01*
X1434630Y416250D01*
X1434475Y414375D01*
X1434785Y412500D01*
X1435250Y411250D01*
X1436180Y410000D01*
X1437265Y409167D01*
X1438350Y408750D01*
X1439435D01*
X1440520Y409167D01*
X1441450Y409791D01*
X1442225Y410625D01*
G01X1453850Y408750D02*
X1447650D01*
Y421250D01*
X1453850D01*
G01X1451370Y415208D02*
X1447650D01*
G01X1458500Y404583D02*
X1467800D01*
G01X1475550Y421250D02*
Y408750D01*
G01X1471985Y421250D02*
X1479115D01*
G01X1484850Y408750D02*
Y421250D01*
X1488725D01*
X1489965Y420625D01*
X1490740Y419792D01*
X1491050Y418125D01*
X1490740Y416458D01*
X1489810Y415417D01*
X1488725Y414792D01*
X1484850D01*
G01X1488725D02*
X1491050Y408750D01*
G01X1496475D02*
X1500350Y421250D01*
X1504225Y408750D01*
G01X1502830Y413125D02*
X1497870D01*
G01X1508875Y421250D02*
X1512750Y408750D01*
X1516625Y421250D01*
G01X1528250Y408750D02*
X1522050D01*
Y421250D01*
X1528250D01*
G01X1525770Y415208D02*
X1522050D01*
G01X1534450Y421250D02*
Y408750D01*
X1540650D01*
G01X1393245Y-180758D02*
X1396965D01*
G01X1394950Y-178050D02*
Y-183467D01*
G01X1409210Y-184925D02*
Y-172425D01*
X1403475Y-181383D01*
X1411225D01*
G01X1419750Y-185342D02*
X1419440Y-185133D01*
Y-184717D01*
X1419750Y-184508D01*
X1420060Y-184717D01*
Y-185133D01*
X1419750Y-185342D01*
G01X1432150Y-172425D02*
X1430910Y-172842D01*
X1429980Y-173883D01*
X1429360Y-175133D01*
X1428895Y-176800D01*
X1428740Y-178675D01*
X1428895Y-180550D01*
X1429360Y-182217D01*
X1429980Y-183467D01*
X1430910Y-184508D01*
X1432150Y-184925D01*
X1433390Y-184508D01*
X1434320Y-183467D01*
X1434940Y-182217D01*
X1435405Y-180550D01*
X1435560Y-178675D01*
X1435405Y-176800D01*
X1434940Y-175133D01*
X1434320Y-173883D01*
X1433390Y-172842D01*
X1432150Y-172425D01*
G01X1441760Y-185342D02*
X1447340Y-172425D01*
G01X1454935Y-180758D02*
X1458965D01*
G01X1471210Y-184925D02*
Y-172425D01*
X1465475Y-181383D01*
X1473225D01*
G01X1481750Y-185342D02*
X1481440Y-185133D01*
Y-184717D01*
X1481750Y-184508D01*
X1482060Y-184717D01*
Y-185133D01*
X1481750Y-185342D01*
G01X1494150Y-172425D02*
X1492910Y-172842D01*
X1491980Y-173883D01*
X1491360Y-175133D01*
X1490895Y-176800D01*
X1490740Y-178675D01*
X1490895Y-180550D01*
X1491360Y-182217D01*
X1491980Y-183467D01*
X1492910Y-184508D01*
X1494150Y-184925D01*
X1495390Y-184508D01*
X1496320Y-183467D01*
X1496940Y-182217D01*
X1497405Y-180550D01*
X1497560Y-178675D01*
X1497405Y-176800D01*
X1496940Y-175133D01*
X1496320Y-173883D01*
X1495390Y-172842D01*
X1494150Y-172425D01*
G01X1442535Y-152408D02*
X1446565D01*
G01X1442535Y-124058D02*
X1446565D01*
G01X1442535Y-95708D02*
X1446565D01*
G01X1442535Y-67358D02*
X1446565D01*
G01X1442535Y-39008D02*
X1446565D01*
G01X1442535Y-10658D02*
X1446565D01*
G01X1442535Y17692D02*
X1446565D01*
G01X1442535Y46042D02*
X1446565D01*
G01X1442535Y74392D02*
X1446565D01*
G01X1442535Y102742D02*
X1446565D01*
G01X1442535Y131092D02*
X1446565D01*
G01X1442535Y159442D02*
X1446565D01*
G01X1442535Y187792D02*
X1446565D01*
G01X1442535Y216142D02*
X1446565D01*
G01X1442535Y244492D02*
X1446565D01*
G01X1442535Y272842D02*
X1446565D01*
G01X1442535Y301192D02*
X1446565D01*
G01X1442535Y329542D02*
X1446565D01*
G01X1442535Y357892D02*
X1446565D01*
G01X1442535Y386242D02*
X1446565D01*
G01X1549485Y-184925D02*
Y-172425D01*
X1556615Y-184925D01*
Y-172425D01*
G01X1565450Y-184925D02*
X1564210Y-184717D01*
X1563125Y-183884D01*
X1562195Y-182633D01*
X1561575Y-181175D01*
X1561265Y-179508D01*
Y-177842D01*
X1561575Y-176175D01*
X1562195Y-174717D01*
X1563125Y-173467D01*
X1564210Y-172633D01*
X1565450Y-172425D01*
X1566690Y-172633D01*
X1567775Y-173467D01*
X1568705Y-174717D01*
X1569325Y-176175D01*
X1569635Y-177842D01*
Y-179508D01*
X1569325Y-181175D01*
X1568705Y-182633D01*
X1567775Y-183884D01*
X1566690Y-184717D01*
X1565450Y-184925D01*
G01X1574285D02*
Y-172425D01*
X1581415Y-184925D01*
Y-172425D01*
G01X1588235Y-180758D02*
X1592265D01*
G01X1599550Y-184925D02*
Y-172425D01*
X1603270D01*
X1604510Y-173050D01*
X1605440Y-174508D01*
X1605750Y-176175D01*
X1605440Y-177842D01*
X1604665Y-179092D01*
X1603270Y-179717D01*
X1599550D01*
G01X1611950Y-172425D02*
Y-184925D01*
X1618150D01*
G01X1623575D02*
X1627450Y-172425D01*
X1631325Y-184925D01*
G01X1629930Y-180550D02*
X1624970D01*
G01X1639850Y-172425D02*
Y-184925D01*
G01X1636285Y-172425D02*
X1643415D01*
G01X1655350Y-184925D02*
X1649150D01*
Y-172425D01*
X1655350D01*
G01X1652870Y-178467D02*
X1649150D01*
G01X1661240Y-184925D02*
Y-172425D01*
X1664340D01*
X1665580Y-173050D01*
X1666510Y-173883D01*
X1667285Y-175133D01*
X1667905Y-176592D01*
X1668060Y-178675D01*
X1667905Y-180758D01*
X1667285Y-182217D01*
X1666510Y-183467D01*
X1665580Y-184300D01*
X1664340Y-184925D01*
X1661240D01*
G01X1549485Y-156575D02*
Y-144075D01*
X1556615Y-156575D01*
Y-144075D01*
G01X1565450Y-156575D02*
X1564210Y-156367D01*
X1563125Y-155534D01*
X1562195Y-154283D01*
X1561575Y-152825D01*
X1561265Y-151158D01*
Y-149492D01*
X1561575Y-147825D01*
X1562195Y-146367D01*
X1563125Y-145117D01*
X1564210Y-144283D01*
X1565450Y-144075D01*
X1566690Y-144283D01*
X1567775Y-145117D01*
X1568705Y-146367D01*
X1569325Y-147825D01*
X1569635Y-149492D01*
Y-151158D01*
X1569325Y-152825D01*
X1568705Y-154283D01*
X1567775Y-155534D01*
X1566690Y-156367D01*
X1565450Y-156575D01*
G01X1574285D02*
Y-144075D01*
X1581415Y-156575D01*
Y-144075D01*
G01X1588235Y-152408D02*
X1592265D01*
G01X1599550Y-156575D02*
Y-144075D01*
X1603270D01*
X1604510Y-144700D01*
X1605440Y-146158D01*
X1605750Y-147825D01*
X1605440Y-149492D01*
X1604665Y-150742D01*
X1603270Y-151367D01*
X1599550D01*
G01X1611950Y-144075D02*
Y-156575D01*
X1618150D01*
G01X1623575D02*
X1627450Y-144075D01*
X1631325Y-156575D01*
G01X1629930Y-152200D02*
X1624970D01*
G01X1639850Y-144075D02*
Y-156575D01*
G01X1636285Y-144075D02*
X1643415D01*
G01X1655350Y-156575D02*
X1649150D01*
Y-144075D01*
X1655350D01*
G01X1652870Y-150117D02*
X1649150D01*
G01X1661240Y-156575D02*
Y-144075D01*
X1664340D01*
X1665580Y-144700D01*
X1666510Y-145533D01*
X1667285Y-146783D01*
X1667905Y-148242D01*
X1668060Y-150325D01*
X1667905Y-152408D01*
X1667285Y-153867D01*
X1666510Y-155117D01*
X1665580Y-155950D01*
X1664340Y-156575D01*
X1661240D01*
G01X1549485Y-128225D02*
Y-115725D01*
X1556615Y-128225D01*
Y-115725D01*
G01X1565450Y-128225D02*
X1564210Y-128017D01*
X1563125Y-127184D01*
X1562195Y-125933D01*
X1561575Y-124475D01*
X1561265Y-122808D01*
Y-121142D01*
X1561575Y-119475D01*
X1562195Y-118017D01*
X1563125Y-116767D01*
X1564210Y-115933D01*
X1565450Y-115725D01*
X1566690Y-115933D01*
X1567775Y-116767D01*
X1568705Y-118017D01*
X1569325Y-119475D01*
X1569635Y-121142D01*
Y-122808D01*
X1569325Y-124475D01*
X1568705Y-125933D01*
X1567775Y-127184D01*
X1566690Y-128017D01*
X1565450Y-128225D01*
G01X1574285D02*
Y-115725D01*
X1581415Y-128225D01*
Y-115725D01*
G01X1588235Y-124058D02*
X1592265D01*
G01X1599550Y-128225D02*
Y-115725D01*
X1603270D01*
X1604510Y-116350D01*
X1605440Y-117808D01*
X1605750Y-119475D01*
X1605440Y-121142D01*
X1604665Y-122392D01*
X1603270Y-123017D01*
X1599550D01*
G01X1611950Y-115725D02*
Y-128225D01*
X1618150D01*
G01X1623575D02*
X1627450Y-115725D01*
X1631325Y-128225D01*
G01X1629930Y-123850D02*
X1624970D01*
G01X1639850Y-115725D02*
Y-128225D01*
G01X1636285Y-115725D02*
X1643415D01*
G01X1655350Y-128225D02*
X1649150D01*
Y-115725D01*
X1655350D01*
G01X1652870Y-121767D02*
X1649150D01*
G01X1661240Y-128225D02*
Y-115725D01*
X1664340D01*
X1665580Y-116350D01*
X1666510Y-117183D01*
X1667285Y-118433D01*
X1667905Y-119892D01*
X1668060Y-121975D01*
X1667905Y-124058D01*
X1667285Y-125517D01*
X1666510Y-126767D01*
X1665580Y-127600D01*
X1664340Y-128225D01*
X1661240D01*
G01X1549485Y-99875D02*
Y-87375D01*
X1556615Y-99875D01*
Y-87375D01*
G01X1565450Y-99875D02*
X1564210Y-99667D01*
X1563125Y-98834D01*
X1562195Y-97583D01*
X1561575Y-96125D01*
X1561265Y-94458D01*
Y-92792D01*
X1561575Y-91125D01*
X1562195Y-89667D01*
X1563125Y-88417D01*
X1564210Y-87583D01*
X1565450Y-87375D01*
X1566690Y-87583D01*
X1567775Y-88417D01*
X1568705Y-89667D01*
X1569325Y-91125D01*
X1569635Y-92792D01*
Y-94458D01*
X1569325Y-96125D01*
X1568705Y-97583D01*
X1567775Y-98834D01*
X1566690Y-99667D01*
X1565450Y-99875D01*
G01X1574285D02*
Y-87375D01*
X1581415Y-99875D01*
Y-87375D01*
G01X1588235Y-95708D02*
X1592265D01*
G01X1599550Y-99875D02*
Y-87375D01*
X1603270D01*
X1604510Y-88000D01*
X1605440Y-89458D01*
X1605750Y-91125D01*
X1605440Y-92792D01*
X1604665Y-94042D01*
X1603270Y-94667D01*
X1599550D01*
G01X1611950Y-87375D02*
Y-99875D01*
X1618150D01*
G01X1623575D02*
X1627450Y-87375D01*
X1631325Y-99875D01*
G01X1629930Y-95500D02*
X1624970D01*
G01X1639850Y-87375D02*
Y-99875D01*
G01X1636285Y-87375D02*
X1643415D01*
G01X1655350Y-99875D02*
X1649150D01*
Y-87375D01*
X1655350D01*
G01X1652870Y-93417D02*
X1649150D01*
G01X1661240Y-99875D02*
Y-87375D01*
X1664340D01*
X1665580Y-88000D01*
X1666510Y-88833D01*
X1667285Y-90083D01*
X1667905Y-91542D01*
X1668060Y-93625D01*
X1667905Y-95708D01*
X1667285Y-97167D01*
X1666510Y-98417D01*
X1665580Y-99250D01*
X1664340Y-99875D01*
X1661240D01*
G01X1549485Y-71525D02*
Y-59025D01*
X1556615Y-71525D01*
Y-59025D01*
G01X1565450Y-71525D02*
X1564210Y-71317D01*
X1563125Y-70484D01*
X1562195Y-69233D01*
X1561575Y-67775D01*
X1561265Y-66108D01*
Y-64442D01*
X1561575Y-62775D01*
X1562195Y-61317D01*
X1563125Y-60067D01*
X1564210Y-59233D01*
X1565450Y-59025D01*
X1566690Y-59233D01*
X1567775Y-60067D01*
X1568705Y-61317D01*
X1569325Y-62775D01*
X1569635Y-64442D01*
Y-66108D01*
X1569325Y-67775D01*
X1568705Y-69233D01*
X1567775Y-70484D01*
X1566690Y-71317D01*
X1565450Y-71525D01*
G01X1574285D02*
Y-59025D01*
X1581415Y-71525D01*
Y-59025D01*
G01X1588235Y-67358D02*
X1592265D01*
G01X1599550Y-71525D02*
Y-59025D01*
X1603270D01*
X1604510Y-59650D01*
X1605440Y-61108D01*
X1605750Y-62775D01*
X1605440Y-64442D01*
X1604665Y-65692D01*
X1603270Y-66317D01*
X1599550D01*
G01X1611950Y-59025D02*
Y-71525D01*
X1618150D01*
G01X1623575D02*
X1627450Y-59025D01*
X1631325Y-71525D01*
G01X1629930Y-67150D02*
X1624970D01*
G01X1639850Y-59025D02*
Y-71525D01*
G01X1636285Y-59025D02*
X1643415D01*
G01X1655350Y-71525D02*
X1649150D01*
Y-59025D01*
X1655350D01*
G01X1652870Y-65067D02*
X1649150D01*
G01X1661240Y-71525D02*
Y-59025D01*
X1664340D01*
X1665580Y-59650D01*
X1666510Y-60483D01*
X1667285Y-61733D01*
X1667905Y-63192D01*
X1668060Y-65275D01*
X1667905Y-67358D01*
X1667285Y-68817D01*
X1666510Y-70067D01*
X1665580Y-70900D01*
X1664340Y-71525D01*
X1661240D01*
G01X1549485Y-43175D02*
Y-30675D01*
X1556615Y-43175D01*
Y-30675D01*
G01X1565450Y-43175D02*
X1564210Y-42967D01*
X1563125Y-42134D01*
X1562195Y-40883D01*
X1561575Y-39425D01*
X1561265Y-37758D01*
Y-36092D01*
X1561575Y-34425D01*
X1562195Y-32967D01*
X1563125Y-31717D01*
X1564210Y-30883D01*
X1565450Y-30675D01*
X1566690Y-30883D01*
X1567775Y-31717D01*
X1568705Y-32967D01*
X1569325Y-34425D01*
X1569635Y-36092D01*
Y-37758D01*
X1569325Y-39425D01*
X1568705Y-40883D01*
X1567775Y-42134D01*
X1566690Y-42967D01*
X1565450Y-43175D01*
G01X1574285D02*
Y-30675D01*
X1581415Y-43175D01*
Y-30675D01*
G01X1588235Y-39008D02*
X1592265D01*
G01X1599550Y-43175D02*
Y-30675D01*
X1603270D01*
X1604510Y-31300D01*
X1605440Y-32758D01*
X1605750Y-34425D01*
X1605440Y-36092D01*
X1604665Y-37342D01*
X1603270Y-37967D01*
X1599550D01*
G01X1611950Y-30675D02*
Y-43175D01*
X1618150D01*
G01X1623575D02*
X1627450Y-30675D01*
X1631325Y-43175D01*
G01X1629930Y-38800D02*
X1624970D01*
G01X1639850Y-30675D02*
Y-43175D01*
G01X1636285Y-30675D02*
X1643415D01*
G01X1655350Y-43175D02*
X1649150D01*
Y-30675D01*
X1655350D01*
G01X1652870Y-36717D02*
X1649150D01*
G01X1661240Y-43175D02*
Y-30675D01*
X1664340D01*
X1665580Y-31300D01*
X1666510Y-32133D01*
X1667285Y-33383D01*
X1667905Y-34842D01*
X1668060Y-36925D01*
X1667905Y-39008D01*
X1667285Y-40467D01*
X1666510Y-41717D01*
X1665580Y-42550D01*
X1664340Y-43175D01*
X1661240D01*
G01X1574750Y-14825D02*
Y-2325D01*
X1578470D01*
X1579710Y-2950D01*
X1580640Y-4408D01*
X1580950Y-6075D01*
X1580640Y-7742D01*
X1579865Y-8992D01*
X1578470Y-9617D01*
X1574750D01*
G01X1587150Y-2325D02*
Y-14825D01*
X1593350D01*
G01X1598775D02*
X1602650Y-2325D01*
X1606525Y-14825D01*
G01X1605130Y-10450D02*
X1600170D01*
G01X1615050Y-2325D02*
Y-14825D01*
G01X1611485Y-2325D02*
X1618615D01*
G01X1630550Y-14825D02*
X1624350D01*
Y-2325D01*
X1630550D01*
G01X1628070Y-8367D02*
X1624350D01*
G01X1636440Y-14825D02*
Y-2325D01*
X1639540D01*
X1640780Y-2950D01*
X1641710Y-3783D01*
X1642485Y-5033D01*
X1643105Y-6492D01*
X1643260Y-8575D01*
X1643105Y-10658D01*
X1642485Y-12117D01*
X1641710Y-13367D01*
X1640780Y-14200D01*
X1639540Y-14825D01*
X1636440D01*
G01X1574750Y13525D02*
Y26025D01*
X1578470D01*
X1579710Y25400D01*
X1580640Y23942D01*
X1580950Y22275D01*
X1580640Y20608D01*
X1579865Y19358D01*
X1578470Y18733D01*
X1574750D01*
G01X1587150Y26025D02*
Y13525D01*
X1593350D01*
G01X1598775D02*
X1602650Y26025D01*
X1606525Y13525D01*
G01X1605130Y17900D02*
X1600170D01*
G01X1615050Y26025D02*
Y13525D01*
G01X1611485Y26025D02*
X1618615D01*
G01X1630550Y13525D02*
X1624350D01*
Y26025D01*
X1630550D01*
G01X1628070Y19983D02*
X1624350D01*
G01X1636440Y13525D02*
Y26025D01*
X1639540D01*
X1640780Y25400D01*
X1641710Y24567D01*
X1642485Y23317D01*
X1643105Y21858D01*
X1643260Y19775D01*
X1643105Y17692D01*
X1642485Y16233D01*
X1641710Y14983D01*
X1640780Y14150D01*
X1639540Y13525D01*
X1636440D01*
G01X1574750Y41875D02*
Y54375D01*
X1578470D01*
X1579710Y53750D01*
X1580640Y52292D01*
X1580950Y50625D01*
X1580640Y48958D01*
X1579865Y47708D01*
X1578470Y47083D01*
X1574750D01*
G01X1587150Y54375D02*
Y41875D01*
X1593350D01*
G01X1598775D02*
X1602650Y54375D01*
X1606525Y41875D01*
G01X1605130Y46250D02*
X1600170D01*
G01X1615050Y54375D02*
Y41875D01*
G01X1611485Y54375D02*
X1618615D01*
G01X1630550Y41875D02*
X1624350D01*
Y54375D01*
X1630550D01*
G01X1628070Y48333D02*
X1624350D01*
G01X1636440Y41875D02*
Y54375D01*
X1639540D01*
X1640780Y53750D01*
X1641710Y52917D01*
X1642485Y51667D01*
X1643105Y50208D01*
X1643260Y48125D01*
X1643105Y46042D01*
X1642485Y44583D01*
X1641710Y43333D01*
X1640780Y42500D01*
X1639540Y41875D01*
X1636440D01*
G01X1574750Y70225D02*
Y82725D01*
X1578470D01*
X1579710Y82100D01*
X1580640Y80642D01*
X1580950Y78975D01*
X1580640Y77308D01*
X1579865Y76058D01*
X1578470Y75433D01*
X1574750D01*
G01X1587150Y82725D02*
Y70225D01*
X1593350D01*
G01X1598775D02*
X1602650Y82725D01*
X1606525Y70225D01*
G01X1605130Y74600D02*
X1600170D01*
G01X1615050Y82725D02*
Y70225D01*
G01X1611485Y82725D02*
X1618615D01*
G01X1630550Y70225D02*
X1624350D01*
Y82725D01*
X1630550D01*
G01X1628070Y76683D02*
X1624350D01*
G01X1636440Y70225D02*
Y82725D01*
X1639540D01*
X1640780Y82100D01*
X1641710Y81267D01*
X1642485Y80017D01*
X1643105Y78558D01*
X1643260Y76475D01*
X1643105Y74392D01*
X1642485Y72933D01*
X1641710Y71683D01*
X1640780Y70850D01*
X1639540Y70225D01*
X1636440D01*
G01X1574750Y98575D02*
Y111075D01*
X1578470D01*
X1579710Y110450D01*
X1580640Y108992D01*
X1580950Y107325D01*
X1580640Y105658D01*
X1579865Y104408D01*
X1578470Y103783D01*
X1574750D01*
G01X1587150Y111075D02*
Y98575D01*
X1593350D01*
G01X1598775D02*
X1602650Y111075D01*
X1606525Y98575D01*
G01X1605130Y102950D02*
X1600170D01*
G01X1615050Y111075D02*
Y98575D01*
G01X1611485Y111075D02*
X1618615D01*
G01X1630550Y98575D02*
X1624350D01*
Y111075D01*
X1630550D01*
G01X1628070Y105033D02*
X1624350D01*
G01X1636440Y98575D02*
Y111075D01*
X1639540D01*
X1640780Y110450D01*
X1641710Y109617D01*
X1642485Y108367D01*
X1643105Y106908D01*
X1643260Y104825D01*
X1643105Y102742D01*
X1642485Y101283D01*
X1641710Y100033D01*
X1640780Y99200D01*
X1639540Y98575D01*
X1636440D01*
G01X1574750Y126925D02*
Y139425D01*
X1578470D01*
X1579710Y138800D01*
X1580640Y137342D01*
X1580950Y135675D01*
X1580640Y134008D01*
X1579865Y132758D01*
X1578470Y132133D01*
X1574750D01*
G01X1587150Y139425D02*
Y126925D01*
X1593350D01*
G01X1598775D02*
X1602650Y139425D01*
X1606525Y126925D01*
G01X1605130Y131300D02*
X1600170D01*
G01X1615050Y139425D02*
Y126925D01*
G01X1611485Y139425D02*
X1618615D01*
G01X1630550Y126925D02*
X1624350D01*
Y139425D01*
X1630550D01*
G01X1628070Y133383D02*
X1624350D01*
G01X1636440Y126925D02*
Y139425D01*
X1639540D01*
X1640780Y138800D01*
X1641710Y137967D01*
X1642485Y136717D01*
X1643105Y135258D01*
X1643260Y133175D01*
X1643105Y131092D01*
X1642485Y129633D01*
X1641710Y128383D01*
X1640780Y127550D01*
X1639540Y126925D01*
X1636440D01*
G01X1574750Y155275D02*
Y167775D01*
X1578470D01*
X1579710Y167150D01*
X1580640Y165692D01*
X1580950Y164025D01*
X1580640Y162358D01*
X1579865Y161108D01*
X1578470Y160483D01*
X1574750D01*
G01X1587150Y167775D02*
Y155275D01*
X1593350D01*
G01X1598775D02*
X1602650Y167775D01*
X1606525Y155275D01*
G01X1605130Y159650D02*
X1600170D01*
G01X1615050Y167775D02*
Y155275D01*
G01X1611485Y167775D02*
X1618615D01*
G01X1630550Y155275D02*
X1624350D01*
Y167775D01*
X1630550D01*
G01X1628070Y161733D02*
X1624350D01*
G01X1636440Y155275D02*
Y167775D01*
X1639540D01*
X1640780Y167150D01*
X1641710Y166317D01*
X1642485Y165067D01*
X1643105Y163608D01*
X1643260Y161525D01*
X1643105Y159442D01*
X1642485Y157983D01*
X1641710Y156733D01*
X1640780Y155900D01*
X1639540Y155275D01*
X1636440D01*
G01X1574750Y183625D02*
Y196125D01*
X1578470D01*
X1579710Y195500D01*
X1580640Y194042D01*
X1580950Y192375D01*
X1580640Y190708D01*
X1579865Y189458D01*
X1578470Y188833D01*
X1574750D01*
G01X1587150Y196125D02*
Y183625D01*
X1593350D01*
G01X1598775D02*
X1602650Y196125D01*
X1606525Y183625D01*
G01X1605130Y188000D02*
X1600170D01*
G01X1615050Y196125D02*
Y183625D01*
G01X1611485Y196125D02*
X1618615D01*
G01X1630550Y183625D02*
X1624350D01*
Y196125D01*
X1630550D01*
G01X1628070Y190083D02*
X1624350D01*
G01X1636440Y183625D02*
Y196125D01*
X1639540D01*
X1640780Y195500D01*
X1641710Y194667D01*
X1642485Y193417D01*
X1643105Y191958D01*
X1643260Y189875D01*
X1643105Y187792D01*
X1642485Y186333D01*
X1641710Y185083D01*
X1640780Y184250D01*
X1639540Y183625D01*
X1636440D01*
G01X1574750Y211975D02*
Y224475D01*
X1578470D01*
X1579710Y223850D01*
X1580640Y222392D01*
X1580950Y220725D01*
X1580640Y219058D01*
X1579865Y217808D01*
X1578470Y217183D01*
X1574750D01*
G01X1587150Y224475D02*
Y211975D01*
X1593350D01*
G01X1598775D02*
X1602650Y224475D01*
X1606525Y211975D01*
G01X1605130Y216350D02*
X1600170D01*
G01X1615050Y224475D02*
Y211975D01*
G01X1611485Y224475D02*
X1618615D01*
G01X1630550Y211975D02*
X1624350D01*
Y224475D01*
X1630550D01*
G01X1628070Y218433D02*
X1624350D01*
G01X1636440Y211975D02*
Y224475D01*
X1639540D01*
X1640780Y223850D01*
X1641710Y223017D01*
X1642485Y221767D01*
X1643105Y220308D01*
X1643260Y218225D01*
X1643105Y216142D01*
X1642485Y214683D01*
X1641710Y213433D01*
X1640780Y212600D01*
X1639540Y211975D01*
X1636440D01*
G01X1574750Y240325D02*
Y252825D01*
X1578470D01*
X1579710Y252200D01*
X1580640Y250742D01*
X1580950Y249075D01*
X1580640Y247408D01*
X1579865Y246158D01*
X1578470Y245533D01*
X1574750D01*
G01X1587150Y252825D02*
Y240325D01*
X1593350D01*
G01X1598775D02*
X1602650Y252825D01*
X1606525Y240325D01*
G01X1605130Y244700D02*
X1600170D01*
G01X1615050Y252825D02*
Y240325D01*
G01X1611485Y252825D02*
X1618615D01*
G01X1630550Y240325D02*
X1624350D01*
Y252825D01*
X1630550D01*
G01X1628070Y246783D02*
X1624350D01*
G01X1636440Y240325D02*
Y252825D01*
X1639540D01*
X1640780Y252200D01*
X1641710Y251367D01*
X1642485Y250117D01*
X1643105Y248658D01*
X1643260Y246575D01*
X1643105Y244492D01*
X1642485Y243033D01*
X1641710Y241783D01*
X1640780Y240950D01*
X1639540Y240325D01*
X1636440D01*
G01X1574750Y268675D02*
Y281175D01*
X1578470D01*
X1579710Y280550D01*
X1580640Y279092D01*
X1580950Y277425D01*
X1580640Y275758D01*
X1579865Y274508D01*
X1578470Y273883D01*
X1574750D01*
G01X1587150Y281175D02*
Y268675D01*
X1593350D01*
G01X1598775D02*
X1602650Y281175D01*
X1606525Y268675D01*
G01X1605130Y273050D02*
X1600170D01*
G01X1615050Y281175D02*
Y268675D01*
G01X1611485Y281175D02*
X1618615D01*
G01X1630550Y268675D02*
X1624350D01*
Y281175D01*
X1630550D01*
G01X1628070Y275133D02*
X1624350D01*
G01X1636440Y268675D02*
Y281175D01*
X1639540D01*
X1640780Y280550D01*
X1641710Y279717D01*
X1642485Y278467D01*
X1643105Y277008D01*
X1643260Y274925D01*
X1643105Y272842D01*
X1642485Y271383D01*
X1641710Y270133D01*
X1640780Y269300D01*
X1639540Y268675D01*
X1636440D01*
G01X1574750Y297025D02*
Y309525D01*
X1578470D01*
X1579710Y308900D01*
X1580640Y307442D01*
X1580950Y305775D01*
X1580640Y304108D01*
X1579865Y302858D01*
X1578470Y302233D01*
X1574750D01*
G01X1587150Y309525D02*
Y297025D01*
X1593350D01*
G01X1598775D02*
X1602650Y309525D01*
X1606525Y297025D01*
G01X1605130Y301400D02*
X1600170D01*
G01X1615050Y309525D02*
Y297025D01*
G01X1611485Y309525D02*
X1618615D01*
G01X1630550Y297025D02*
X1624350D01*
Y309525D01*
X1630550D01*
G01X1628070Y303483D02*
X1624350D01*
G01X1636440Y297025D02*
Y309525D01*
X1639540D01*
X1640780Y308900D01*
X1641710Y308067D01*
X1642485Y306817D01*
X1643105Y305358D01*
X1643260Y303275D01*
X1643105Y301192D01*
X1642485Y299733D01*
X1641710Y298483D01*
X1640780Y297650D01*
X1639540Y297025D01*
X1636440D01*
G01X1574750Y325375D02*
Y337875D01*
X1578470D01*
X1579710Y337250D01*
X1580640Y335792D01*
X1580950Y334125D01*
X1580640Y332458D01*
X1579865Y331208D01*
X1578470Y330583D01*
X1574750D01*
G01X1587150Y337875D02*
Y325375D01*
X1593350D01*
G01X1598775D02*
X1602650Y337875D01*
X1606525Y325375D01*
G01X1605130Y329750D02*
X1600170D01*
G01X1615050Y337875D02*
Y325375D01*
G01X1611485Y337875D02*
X1618615D01*
G01X1630550Y325375D02*
X1624350D01*
Y337875D01*
X1630550D01*
G01X1628070Y331833D02*
X1624350D01*
G01X1636440Y325375D02*
Y337875D01*
X1639540D01*
X1640780Y337250D01*
X1641710Y336417D01*
X1642485Y335167D01*
X1643105Y333708D01*
X1643260Y331625D01*
X1643105Y329542D01*
X1642485Y328083D01*
X1641710Y326833D01*
X1640780Y326000D01*
X1639540Y325375D01*
X1636440D01*
G01X1574750Y353725D02*
Y366225D01*
X1578470D01*
X1579710Y365600D01*
X1580640Y364142D01*
X1580950Y362475D01*
X1580640Y360808D01*
X1579865Y359558D01*
X1578470Y358933D01*
X1574750D01*
G01X1587150Y366225D02*
Y353725D01*
X1593350D01*
G01X1598775D02*
X1602650Y366225D01*
X1606525Y353725D01*
G01X1605130Y358100D02*
X1600170D01*
G01X1615050Y366225D02*
Y353725D01*
G01X1611485Y366225D02*
X1618615D01*
G01X1630550Y353725D02*
X1624350D01*
Y366225D01*
X1630550D01*
G01X1628070Y360183D02*
X1624350D01*
G01X1636440Y353725D02*
Y366225D01*
X1639540D01*
X1640780Y365600D01*
X1641710Y364767D01*
X1642485Y363517D01*
X1643105Y362058D01*
X1643260Y359975D01*
X1643105Y357892D01*
X1642485Y356433D01*
X1641710Y355183D01*
X1640780Y354350D01*
X1639540Y353725D01*
X1636440D01*
G01X1574750Y382075D02*
Y394575D01*
X1578470D01*
X1579710Y393950D01*
X1580640Y392492D01*
X1580950Y390825D01*
X1580640Y389158D01*
X1579865Y387908D01*
X1578470Y387283D01*
X1574750D01*
G01X1587150Y394575D02*
Y382075D01*
X1593350D01*
G01X1598775D02*
X1602650Y394575D01*
X1606525Y382075D01*
G01X1605130Y386450D02*
X1600170D01*
G01X1615050Y394575D02*
Y382075D01*
G01X1611485Y394575D02*
X1618615D01*
G01X1630550Y382075D02*
X1624350D01*
Y394575D01*
X1630550D01*
G01X1628070Y388533D02*
X1624350D01*
G01X1636440Y382075D02*
Y394575D01*
X1639540D01*
X1640780Y393950D01*
X1641710Y393117D01*
X1642485Y391867D01*
X1643105Y390408D01*
X1643260Y388325D01*
X1643105Y386242D01*
X1642485Y384783D01*
X1641710Y383533D01*
X1640780Y382700D01*
X1639540Y382075D01*
X1636440D01*
G01X1574750Y408750D02*
Y421250D01*
X1578470D01*
X1579710Y420625D01*
X1580640Y419167D01*
X1580950Y417500D01*
X1580640Y415833D01*
X1579865Y414583D01*
X1578470Y413958D01*
X1574750D01*
G01X1587150Y421250D02*
Y408750D01*
X1593350D01*
G01X1598775D02*
X1602650Y421250D01*
X1606525Y408750D01*
G01X1605130Y413125D02*
X1600170D01*
G01X1615050Y421250D02*
Y408750D01*
G01X1611485Y421250D02*
X1618615D01*
G01X1630550Y408750D02*
X1624350D01*
Y421250D01*
X1630550D01*
G01X1628070Y415208D02*
X1624350D01*
G01X1636440Y408750D02*
Y421250D01*
X1639540D01*
X1640780Y420625D01*
X1641710Y419792D01*
X1642485Y418542D01*
X1643105Y417083D01*
X1643260Y415000D01*
X1643105Y412917D01*
X1642485Y411458D01*
X1641710Y410208D01*
X1640780Y409375D01*
X1639540Y408750D01*
X1636440D01*
G01X1702005Y-66317D02*
X1703090Y-64858D01*
X1704020Y-64025D01*
X1705260Y-63608D01*
X1706345Y-64025D01*
X1707120Y-64858D01*
X1707740Y-66108D01*
X1707895Y-67567D01*
X1707740Y-68817D01*
X1707120Y-70067D01*
X1706190Y-71108D01*
X1705105Y-71525D01*
X1703865Y-71108D01*
X1702780Y-69859D01*
X1702160Y-67983D01*
X1702005Y-65900D01*
X1702315Y-63192D01*
X1702780Y-61733D01*
X1703555Y-60275D01*
X1704640Y-59233D01*
X1705725Y-59025D01*
X1706810Y-59442D01*
X1707585Y-60483D01*
G01X1719210Y-71525D02*
Y-59025D01*
X1713475Y-67983D01*
X1721225D01*
G01X1704950Y126925D02*
Y139425D01*
X1703090Y136925D01*
G01Y126925D02*
X1706810D01*
G01X1717350D02*
X1718435Y127133D01*
X1719675Y127758D01*
X1720450Y128800D01*
X1720760Y130258D01*
X1720450Y131716D01*
X1719520Y132967D01*
X1718125Y133592D01*
X1716575D01*
X1715645Y134008D01*
X1714870Y135050D01*
X1714560Y136508D01*
X1715025Y137967D01*
X1716110Y139008D01*
X1717350Y139425D01*
X1718590Y139008D01*
X1719675Y137967D01*
X1720140Y136508D01*
X1719830Y135050D01*
X1719055Y134008D01*
X1718125Y133592D01*
X1716575D01*
X1715180Y132967D01*
X1714250Y131716D01*
X1713940Y130258D01*
X1714250Y128800D01*
X1715025Y127758D01*
X1716265Y127133D01*
X1717350Y126925D01*
G01X1704950Y155275D02*
Y167775D01*
X1703090Y165275D01*
G01Y155275D02*
X1706810D01*
G01X1714405Y160483D02*
X1715490Y161942D01*
X1716420Y162775D01*
X1717660Y163192D01*
X1718745Y162775D01*
X1719520Y161942D01*
X1720140Y160692D01*
X1720295Y159233D01*
X1720140Y157983D01*
X1719520Y156733D01*
X1718590Y155692D01*
X1717505Y155275D01*
X1716265Y155692D01*
X1715180Y156941D01*
X1714560Y158817D01*
X1714405Y160900D01*
X1714715Y163608D01*
X1715180Y165067D01*
X1715955Y166525D01*
X1717040Y167567D01*
X1718125Y167775D01*
X1719210Y167358D01*
X1719985Y166317D01*
G01X1692550Y268675D02*
Y281175D01*
X1690690Y278675D01*
G01Y268675D02*
X1694410D01*
G01X1702315Y270133D02*
X1703400Y269092D01*
X1704640Y268675D01*
X1705880Y269092D01*
X1706965Y270341D01*
X1707740Y272217D01*
X1708050Y274092D01*
Y276383D01*
X1707740Y278258D01*
X1706965Y279925D01*
X1706035Y280758D01*
X1704950Y281175D01*
X1703710Y280758D01*
X1702780Y279925D01*
X1702160Y278675D01*
X1701850Y277008D01*
X1702160Y275550D01*
X1702935Y274092D01*
X1703865Y273258D01*
X1704950Y273050D01*
X1706190Y273466D01*
X1707120Y274508D01*
X1708050Y276383D01*
G01X1719210Y268675D02*
Y281175D01*
X1713475Y272217D01*
X1721225D01*
G01X1729750Y268675D02*
X1730835Y268883D01*
X1732075Y269508D01*
X1732850Y270550D01*
X1733160Y272008D01*
X1732850Y273466D01*
X1731920Y274717D01*
X1730525Y275342D01*
X1728975D01*
X1728045Y275758D01*
X1727270Y276800D01*
X1726960Y278258D01*
X1727425Y279717D01*
X1728510Y280758D01*
X1729750Y281175D01*
X1730990Y280758D01*
X1732075Y279717D01*
X1732540Y278258D01*
X1732230Y276800D01*
X1731455Y275758D01*
X1730525Y275342D01*
X1728975D01*
X1727580Y274717D01*
X1726650Y273466D01*
X1726340Y272008D01*
X1726650Y270550D01*
X1727425Y269508D01*
X1728665Y268883D01*
X1729750Y268675D01*
G01X1695340Y299525D02*
X1696270Y298066D01*
X1697510Y297233D01*
X1698905Y297025D01*
X1700145Y297233D01*
X1701385Y298275D01*
X1702160Y299525D01*
X1702315Y300775D01*
X1702005Y302233D01*
X1700920Y303275D01*
X1699835Y303692D01*
X1698440D01*
G01X1699835D02*
X1700765Y304317D01*
X1701540Y305358D01*
X1701850Y306608D01*
X1701540Y307858D01*
X1700765Y308900D01*
X1699370Y309525D01*
X1697975Y309317D01*
X1696580Y308483D01*
G01X1707740Y299525D02*
X1708670Y298066D01*
X1709910Y297233D01*
X1711305Y297025D01*
X1712545Y297233D01*
X1713785Y298275D01*
X1714560Y299525D01*
X1714715Y300775D01*
X1714405Y302233D01*
X1713320Y303275D01*
X1712235Y303692D01*
X1710840D01*
G01X1712235D02*
X1713165Y304317D01*
X1713940Y305358D01*
X1714250Y306608D01*
X1713940Y307858D01*
X1713165Y308900D01*
X1711770Y309525D01*
X1710375Y309317D01*
X1708980Y308483D01*
G01X1723240Y297025D02*
X1723550Y299733D01*
X1724015Y302025D01*
X1724635Y304108D01*
X1725410Y306400D01*
X1726650Y309525D01*
X1720450D01*
G01X1695340Y327250D02*
X1696270Y326208D01*
X1697355Y325583D01*
X1698750Y325375D01*
X1700145Y325792D01*
X1701230Y326625D01*
X1702005Y328083D01*
X1702160Y329750D01*
X1701850Y331417D01*
X1701075Y332458D01*
X1699990Y333292D01*
X1698905Y333500D01*
X1697820Y333292D01*
X1696425Y332458D01*
X1696890Y337875D01*
X1701075D01*
G01X1708515Y326833D02*
X1709600Y325792D01*
X1710840Y325375D01*
X1712080Y325792D01*
X1713165Y327041D01*
X1713940Y328917D01*
X1714250Y330792D01*
Y333083D01*
X1713940Y334958D01*
X1713165Y336625D01*
X1712235Y337458D01*
X1711150Y337875D01*
X1709910Y337458D01*
X1708980Y336625D01*
X1708360Y335375D01*
X1708050Y333708D01*
X1708360Y332250D01*
X1709135Y330792D01*
X1710065Y329958D01*
X1711150Y329750D01*
X1712390Y330166D01*
X1713320Y331208D01*
X1714250Y333083D01*
G01X1720140Y327875D02*
X1721070Y326416D01*
X1722310Y325583D01*
X1723705Y325375D01*
X1724945Y325583D01*
X1726185Y326625D01*
X1726960Y327875D01*
X1727115Y329125D01*
X1726805Y330583D01*
X1725720Y331625D01*
X1724635Y332042D01*
X1723240D01*
G01X1724635D02*
X1725565Y332667D01*
X1726340Y333708D01*
X1726650Y334958D01*
X1726340Y336208D01*
X1725565Y337250D01*
X1724170Y337875D01*
X1722775Y337667D01*
X1721380Y336833D01*
G01X1704950Y353725D02*
Y366225D01*
X1703090Y363725D01*
G01Y353725D02*
X1706810D01*
G01X1717350D02*
Y366225D01*
X1715490Y363725D01*
G01Y353725D02*
X1719210D01*
G01X1702005Y387283D02*
X1703090Y388742D01*
X1704020Y389575D01*
X1705260Y389992D01*
X1706345Y389575D01*
X1707120Y388742D01*
X1707740Y387492D01*
X1707895Y386033D01*
X1707740Y384783D01*
X1707120Y383533D01*
X1706190Y382492D01*
X1705105Y382075D01*
X1703865Y382492D01*
X1702780Y383741D01*
X1702160Y385617D01*
X1702005Y387700D01*
X1702315Y390408D01*
X1702780Y391867D01*
X1703555Y393325D01*
X1704640Y394367D01*
X1705725Y394575D01*
X1706810Y394158D01*
X1707585Y393117D01*
G01X1719210Y382075D02*
Y394575D01*
X1713475Y385617D01*
X1721225D01*
G01X1698750Y408750D02*
X1697510Y408958D01*
X1696425Y409791D01*
X1695495Y411042D01*
X1694875Y412500D01*
X1694565Y414167D01*
Y415833D01*
X1694875Y417500D01*
X1695495Y418958D01*
X1696425Y420208D01*
X1697510Y421042D01*
X1698750Y421250D01*
X1699990Y421042D01*
X1701075Y420208D01*
X1702005Y418958D01*
X1702625Y417500D01*
X1702935Y415833D01*
Y414167D01*
X1702625Y412500D01*
X1702005Y411042D01*
X1701075Y409791D01*
X1699990Y408958D01*
X1698750Y408750D01*
G01X1699990Y412083D02*
X1701850Y408750D01*
G01X1711150Y421250D02*
Y408750D01*
G01X1707585Y421250D02*
X1714715D01*
G01X1723550Y408750D02*
Y414375D01*
X1720450Y421250D01*
G01X1726650D02*
X1723550Y414375D01*
G01X1711150Y-184925D02*
Y-172425D01*
X1709290Y-174925D01*
G01Y-184925D02*
X1713010D01*
G01X1708205Y-146158D02*
X1709135Y-144909D01*
X1710220Y-144283D01*
X1711460Y-144075D01*
X1713010Y-144492D01*
X1714095Y-145533D01*
X1714405Y-146783D01*
X1714250Y-148034D01*
X1713630Y-149075D01*
X1710530Y-151158D01*
X1709135Y-152617D01*
X1708205Y-154700D01*
X1707895Y-156575D01*
X1714405D01*
G01X1711150Y-128225D02*
Y-115725D01*
X1709290Y-118225D01*
G01Y-128225D02*
X1713010D01*
G01X1711150Y-99875D02*
Y-87375D01*
X1709290Y-89875D01*
G01Y-99875D02*
X1713010D01*
G01X1708205Y-37967D02*
X1709290Y-36508D01*
X1710220Y-35675D01*
X1711460Y-35258D01*
X1712545Y-35675D01*
X1713320Y-36508D01*
X1713940Y-37758D01*
X1714095Y-39217D01*
X1713940Y-40467D01*
X1713320Y-41717D01*
X1712390Y-42758D01*
X1711305Y-43175D01*
X1710065Y-42758D01*
X1708980Y-41509D01*
X1708360Y-39633D01*
X1708205Y-37550D01*
X1708515Y-34842D01*
X1708980Y-33383D01*
X1709755Y-31925D01*
X1710840Y-30883D01*
X1711925Y-30675D01*
X1713010Y-31092D01*
X1713785Y-32133D01*
G01X1711150Y-14825D02*
Y-2325D01*
X1709290Y-4825D01*
G01Y-14825D02*
X1713010D01*
G01X1708205Y23942D02*
X1709135Y25191D01*
X1710220Y25817D01*
X1711460Y26025D01*
X1713010Y25608D01*
X1714095Y24567D01*
X1714405Y23317D01*
X1714250Y22066D01*
X1713630Y21025D01*
X1710530Y18942D01*
X1709135Y17483D01*
X1708205Y15400D01*
X1707895Y13525D01*
X1714405D01*
G01X1708205Y52292D02*
X1709135Y53541D01*
X1710220Y54167D01*
X1711460Y54375D01*
X1713010Y53958D01*
X1714095Y52917D01*
X1714405Y51667D01*
X1714250Y50416D01*
X1713630Y49375D01*
X1710530Y47292D01*
X1709135Y45833D01*
X1708205Y43750D01*
X1707895Y41875D01*
X1714405D01*
G01X1708205Y80642D02*
X1709135Y81891D01*
X1710220Y82517D01*
X1711460Y82725D01*
X1713010Y82308D01*
X1714095Y81267D01*
X1714405Y80017D01*
X1714250Y78766D01*
X1713630Y77725D01*
X1710530Y75642D01*
X1709135Y74183D01*
X1708205Y72100D01*
X1707895Y70225D01*
X1714405D01*
G01X1708205Y108992D02*
X1709135Y110241D01*
X1710220Y110867D01*
X1711460Y111075D01*
X1713010Y110658D01*
X1714095Y109617D01*
X1714405Y108367D01*
X1714250Y107116D01*
X1713630Y106075D01*
X1710530Y103992D01*
X1709135Y102533D01*
X1708205Y100450D01*
X1707895Y98575D01*
X1714405D01*
G01X1711150Y183625D02*
X1712235Y183833D01*
X1713475Y184458D01*
X1714250Y185500D01*
X1714560Y186958D01*
X1714250Y188416D01*
X1713320Y189667D01*
X1711925Y190292D01*
X1710375D01*
X1709445Y190708D01*
X1708670Y191750D01*
X1708360Y193208D01*
X1708825Y194667D01*
X1709910Y195708D01*
X1711150Y196125D01*
X1712390Y195708D01*
X1713475Y194667D01*
X1713940Y193208D01*
X1713630Y191750D01*
X1712855Y190708D01*
X1711925Y190292D01*
X1710375D01*
X1708980Y189667D01*
X1708050Y188416D01*
X1707740Y186958D01*
X1708050Y185500D01*
X1708825Y184458D01*
X1710065Y183833D01*
X1711150Y183625D01*
G01X1708205Y222392D02*
X1709135Y223641D01*
X1710220Y224267D01*
X1711460Y224475D01*
X1713010Y224058D01*
X1714095Y223017D01*
X1714405Y221767D01*
X1714250Y220516D01*
X1713630Y219475D01*
X1710530Y217392D01*
X1709135Y215933D01*
X1708205Y213850D01*
X1707895Y211975D01*
X1714405D01*
G01X1708515Y241783D02*
X1709600Y240742D01*
X1710840Y240325D01*
X1712080Y240742D01*
X1713165Y241991D01*
X1713940Y243867D01*
X1714250Y245742D01*
Y248033D01*
X1713940Y249908D01*
X1713165Y251575D01*
X1712235Y252408D01*
X1711150Y252825D01*
X1709910Y252408D01*
X1708980Y251575D01*
X1708360Y250325D01*
X1708050Y248658D01*
X1708360Y247200D01*
X1709135Y245742D01*
X1710065Y244908D01*
X1711150Y244700D01*
X1712390Y245116D01*
X1713320Y246158D01*
X1714250Y248033D01*
G54D23*
X105315Y186571D03*
X768750Y-178675D03*
G54D14*
X17716Y18465D03*
X45276D03*
X264173Y20040D03*
X291733D03*
X309055Y18465D03*
X336615D03*
X768750Y-36925D03*
G54D15*
X22047Y46417D03*
X333466D03*
X768750Y48125D03*
G54D24*
X105316Y213343D03*
X768750Y-8575D03*
G54D16*
X24016Y89331D03*
X330315D03*
X768750Y76475D03*
G54D25*
X143118Y44803D03*
X194851D03*
X768750Y104825D03*
G54D26*
X153237Y58583D03*
X165048Y52677D03*
X155205D03*
X161111Y58583D03*
X168985D03*
X182764Y52677D03*
X172922D03*
X176859Y58583D03*
X184733D03*
X768750Y246575D03*
G54D17*
X19100Y187420D03*
X17065Y255712D03*
X24705Y258767D03*
X22237Y304626D03*
X30638Y304602D03*
Y311957D03*
X33000Y318700D03*
X36200Y368400D03*
X31500Y428500D03*
X40940Y112559D03*
X47294Y184491D03*
X48035Y191535D03*
X39408Y195990D03*
X48940Y204871D03*
X39900Y211000D03*
X39567Y243133D03*
X51500Y258200D03*
X37485Y258807D03*
X41100Y248900D03*
X47440Y304225D03*
X39039Y301299D03*
Y311933D03*
X50950Y318050D03*
X44481Y328760D03*
X38560Y329739D03*
X37020Y385600D03*
X46100Y412700D03*
X38000Y428800D03*
X45100Y435800D03*
X59945Y117795D03*
X60800Y137000D03*
X52410Y186900D03*
X59700Y196200D03*
X52948Y200700D03*
X58000Y217700D03*
X61200Y282600D03*
X60600Y318000D03*
X52800Y322400D03*
X62458Y355873D03*
X58564Y354280D03*
X65607Y352724D03*
Y359023D03*
Y371584D03*
X74757Y83745D03*
X66900Y125300D03*
X71124Y178565D03*
X74583Y217314D03*
X76200Y247400D03*
X77437Y262760D03*
X77500Y316100D03*
X81000Y321900D03*
X78900Y336600D03*
X75056Y346425D03*
X68757D03*
X71700Y340600D03*
X81355Y346425D03*
X78206Y349574D03*
Y359023D03*
X68757Y362173D03*
X71906Y365322D03*
X79000Y395500D03*
X73976Y408665D03*
X69139Y413452D03*
X74782Y413800D03*
X91358Y83745D03*
X88500Y128000D03*
X81500Y176515D03*
X87500Y237300D03*
X92300Y282100D03*
X92698Y323224D03*
X87617Y352724D03*
X93916D03*
X96030Y409400D03*
X84320Y430510D03*
X111000Y77000D03*
X104500Y73500D03*
X110950Y82050D03*
X111075Y104600D03*
X98720Y236980D03*
X103580Y237400D03*
X106600Y253689D03*
X106574Y280028D03*
X99990Y307900D03*
X100500Y328547D03*
X100253Y346387D03*
X108701Y418300D03*
X108336Y411547D03*
X109048Y425853D03*
X103461Y425875D03*
X125800Y47330D03*
X112800Y60400D03*
X112600Y52800D03*
X123325Y111000D03*
X120500Y115525D03*
X113590Y245170D03*
X121200Y234890D03*
X112900Y239200D03*
X111600Y262730D03*
Y284000D03*
X122957Y300991D03*
X123100Y295974D03*
X124935Y324900D03*
X124300Y348800D03*
X111950Y371200D03*
X122047Y372260D03*
X125650Y368650D03*
X122330Y364670D03*
X119200Y389700D03*
X117410Y381350D03*
X112800Y421600D03*
X116632Y411500D03*
X122498Y419675D03*
X112796Y412490D03*
X140730Y72600D03*
X132500Y167300D03*
X135300Y175100D03*
X129810Y191310D03*
X134891Y225171D03*
X138000Y244600D03*
X136100Y334000D03*
X129135Y410250D03*
X128866Y433066D03*
X135350Y433016D03*
X152800Y75600D03*
X145100Y87400D03*
X149800Y135100D03*
X148429Y147682D03*
X144500Y169570D03*
X146882Y177501D03*
X143742Y203395D03*
X142702Y227817D03*
X149862Y243788D03*
X145250Y256890D03*
X141890Y310570D03*
X145703Y370700D03*
X152500Y382600D03*
X150820Y387325D03*
X156710Y73420D03*
X156286Y124903D03*
X166733Y128700D03*
X159328Y160847D03*
X163500Y229184D03*
X160850Y301344D03*
X170800Y317600D03*
X161154Y376704D03*
X156300Y376300D03*
X165501Y382800D03*
X158200Y381400D03*
X162100Y414000D03*
X156101Y425100D03*
X165500Y433100D03*
X182108Y129094D03*
X174553Y128728D03*
X181495Y153449D03*
X175196Y156599D03*
X184645Y166047D03*
Y181795D03*
X181495Y172347D03*
X184645Y175496D03*
X178346D03*
X181495Y188095D03*
X175196Y200655D03*
X181495Y203805D03*
X175196Y206955D03*
X184645Y219553D03*
X178346Y229002D03*
X184645D03*
X180458Y258825D03*
X174400Y251936D03*
X184480Y429370D03*
X193100Y69100D03*
X186891Y113991D03*
X187435Y129623D03*
X195983Y129294D03*
X197243Y159748D03*
X190944D03*
Y166047D03*
X200393Y162898D03*
X187794Y156599D03*
Y172347D03*
X194094Y222703D03*
X200393Y229002D03*
X187794Y225852D03*
X200393Y222703D03*
X192380Y291900D03*
X191199Y300200D03*
X188546Y326356D03*
X187400Y379400D03*
X187300Y384300D03*
X197660Y390870D03*
X195800Y396780D03*
X200274Y410960D03*
X190370Y422490D03*
X195000Y422540D03*
X199940Y423700D03*
X197600Y415400D03*
X195300Y432327D03*
X186720Y432490D03*
X211400Y59238D03*
X204100Y67400D03*
X211490Y143700D03*
X209842Y159748D03*
X206692Y162898D03*
X209842Y166047D03*
X212991Y162898D03*
X203542Y159748D03*
Y225852D03*
X206692Y229002D03*
X212991D03*
X206692Y222703D03*
X214034Y261482D03*
X205900Y266130D03*
X204207Y278200D03*
X208360Y384890D03*
X208565Y404501D03*
X205223Y422665D03*
X206150Y412821D03*
X229900Y61000D03*
X227547Y74275D03*
X224000D03*
X227760Y82524D03*
X216400Y106400D03*
X226040Y101220D03*
X217262Y129294D03*
X229342Y129240D03*
X221278Y129294D03*
X225552Y166047D03*
X222402Y159748D03*
X228739Y222703D03*
X228702Y229002D03*
X225590Y225852D03*
X222440Y222703D03*
X222402Y229002D03*
X219290Y225852D03*
X230196Y267477D03*
X220866Y272160D03*
X226405Y266335D03*
X229220Y283250D03*
X216384Y312216D03*
X228800Y312100D03*
X228230Y340040D03*
X222575Y387625D03*
X227206Y400100D03*
X220134Y400780D03*
X240000Y67400D03*
X235630Y104990D03*
X231592Y110500D03*
X233511Y129594D03*
X242500Y129000D03*
X232384Y148884D03*
X231851Y166047D03*
X235001Y156599D03*
X244450Y200655D03*
X231889Y225890D03*
X239298Y268800D03*
X241263Y282654D03*
X234500Y293500D03*
X241231Y407285D03*
X256000Y56000D03*
X258500Y146400D03*
X250749Y169197D03*
X253898Y175496D03*
X250749Y184945D03*
X257048Y197506D03*
Y191244D03*
X253100Y257800D03*
X257145Y279700D03*
X258100Y295080D03*
X245900Y305000D03*
X257900Y312100D03*
X256124Y336355D03*
X249400Y410300D03*
X267939Y41122D03*
X272505Y83545D03*
X264989Y101732D03*
X262100Y280700D03*
X262310Y311225D03*
X261300Y334100D03*
X273580Y354250D03*
X274190Y408900D03*
X269700Y411379D03*
X271500Y418300D03*
X267100Y432900D03*
X263800Y430300D03*
X272999Y430500D03*
X286000Y47000D03*
X290000Y82000D03*
X277505Y83545D03*
X282505D03*
X288116Y120306D03*
X280400Y126000D03*
X287796Y131542D03*
X288280Y126212D03*
X284357Y267027D03*
X281889Y287636D03*
X285911Y279569D03*
X287507Y301596D03*
X289939Y309060D03*
X286372Y320700D03*
X289600Y322253D03*
X286372Y326768D03*
X276400Y370400D03*
X283973Y382553D03*
X278900Y421400D03*
X281300Y416200D03*
X277700Y412580D03*
X297466Y51521D03*
X297575Y73738D03*
X293773Y73530D03*
X298575Y101900D03*
X304000Y116500D03*
X300500Y125000D03*
X291000Y297700D03*
X290120Y339370D03*
X298152Y393332D03*
X292700Y403700D03*
X315100Y116400D03*
X309521Y226397D03*
Y235352D03*
X312114Y288439D03*
X312272Y282107D03*
X306200Y308800D03*
X312300Y340700D03*
X308926Y401900D03*
X322500Y102900D03*
X320938Y122677D03*
X331641Y141743D03*
X325900Y365643D03*
X326100Y375717D03*
X326200Y370681D03*
X326375Y380724D03*
X339101Y117328D03*
X337842Y128533D03*
X337004Y202113D03*
Y210113D03*
X335475Y367500D03*
X335500Y380000D03*
X768750Y303275D03*
G54D27*
X144685Y297776D03*
X768750Y-121975D03*
G54D18*
X27300Y68200D03*
X340639Y432809D03*
X768750Y-150325D03*
G54D19*
X23819Y339154D03*
Y349154D03*
Y359154D03*
Y369154D03*
Y379154D03*
Y389154D03*
Y399154D03*
Y409154D03*
X65709Y42244D03*
Y52244D03*
X75709Y42244D03*
Y52244D03*
X95709Y42244D03*
X85709D03*
X95709Y52244D03*
X85709D03*
X768750Y161525D03*
G54D28*
X236220Y424016D03*
X301181D03*
X768750Y19775D03*
G54D29*
X271209Y177524D03*
X289254Y194839D03*
X286106Y210587D03*
X295410Y172936D03*
X298714Y210477D03*
X292404Y201282D03*
X299667Y201334D03*
X292404Y213737D03*
X305002Y172936D03*
X311158Y194839D03*
Y210587D03*
X768750Y359975D03*
M02*
